P  JOB   G:/<user>/9127_F0T_Expander_BD_F_v02_0110_1240.brd                        
P  CODE  00                                                                     
P  UNITS CUST 0                                                                 
P  TITLE G:/<user>/9127_F0T_Expander_BD_F_v02_0110_1240.brd                        
P  NUM   001                                                                    
P  REV   A                                                                      
P  VER IPC-D-356A                                                               
C                                                                               
C  IPC-D-356 Ouptut File from Allegro                                           
C  IPC File Date: Wed Jan 11 16:12:25 2023                                      
C                                                                               
C                                                                               
C  Board File:             9127_F0T_Expander_BD_F_v02_0110_1240.brd             
C  Design Rule Status:     UP TO DATE                                           
C  Unit of Measure:        mils                                                 
C  Decimal Place Accuracy: 2                                                    
C  Number of etch Layers:  18                                                   
C  Board Thickness(mils):  121.700000                                           
C  Drawing Extents(mils):  -5000000  -5000000  47000000  58000000               
C                                                                               
C                                                                               
C  BOARD LAYER INFORMATION                                                      
C                                                                               
C     Layer      Layer            Layer             Film  Layer                 
C     Name       Material         Type              Type  Number                
C  ---------------------------------------------------------                    
C  TOP           COPPER           CONDUCTOR         POS     1                   
C  GND           COPPER           PLANE             NEG     2                   
C  VCC           COPPER           PLANE             NEG     3                   
C  VCC1          COPPER           PLANE             NEG     4                   
C  GND1          COPPER           PLANE             NEG     5                   
C  IN1           COPPER           CONDUCTOR         POS     6                   
C  GND2          COPPER           PLANE             NEG     7                   
C  IN2           COPPER           CONDUCTOR         POS     8                   
C  GND3          COPPER           PLANE             NEG     9                   
C  IN3           COPPER           CONDUCTOR         POS    10                   
C  GND4          COPPER           PLANE             NEG    11                   
C  IN4           COPPER           CONDUCTOR         POS    12                   
C  GND5          COPPER           PLANE             NEG    13                   
C  IN5           COPPER           CONDUCTOR         POS    14                   
C  GND6          COPPER           PLANE             NEG    15                   
C  IN6           COPPER           CONDUCTOR         POS    16                   
C  GND7          COPPER           PLANE             NEG    17                   
C  BOTTOM        COPPER           CONDUCTOR         POS    18                   
C                                                                               
C                                                                               
C  PADSTACK INFORMATION                                                         
C                                                                               
C     Padstack          First     Last                                          
C     Name              Layer     Layer     Width     Height                    
C  ---------------------------------------------------------                    
C  SMD12X21             TOP       TOP            1600      2500                 
C  SMD11X20             TOP       TOP            1500      2400                 
C  C41D41N              TOP       BOTTOM         7100      7100                 
C  SMD85X156_CUT_NPM    TOP       TOP            8900     16000                 
C  SMD12X20_NPM         TOP       TOP            1600      2400                 
C  TP_R16X4-1R16X8-1    TOP       TOP           12000     12000                 
C  TP_R16X4-1R16X8-1B   BOTTOM    BOTTOM        12000     12000                 
C  C122D122N            TOP       BOTTOM        15200     15200                 
C  SMD24X42             TOP       TOP            2800      4600                 
C  SMD12X36             TOP       TOP            1600      4000                 
C  SMD78X107            TOP       TOP            8200     11100                 
C  SMD11X24             TOP       TOP            1500      2800                 
C  C394D221_NPB         TOP       BOTTOM        39800     39800                 
C  VT20D10B28           TOP       BOTTOM         7502      7500                 
C  TP28B                BOTTOM    BOTTOM         7502      7500                 
C  VT19-3D10B26         TOP       BOTTOM         7502      7500                 
C  TP20B                BOTTOM    BOTTOM         7502      7500                 
C  VT20D10B20           TOP       BOTTOM         7502      7500                 
C  VT18D10B20A26_BGA    TOP       BOTTOM         7502      7500                 
C  VIA18D10A26_BGA      TOP       BOTTOM         2600      2600                 
C  VT16D8B20A26         TOP       BOTTOM         7502      7500                 
C  SMD237X237_PM221X221 TOP       TOP           24022     24022                 
C  SMD0-24X0-6_CUT      TOP       TOP            1344      2762                 
C  C315D166_NPM         TOP       BOTTOM        31900     31900                 
C  SMD16X44             TOP       TOP            2000      4800                 
C  SMD60X126_CUT        TOP       TOP           12998      6306                 
C  SMD24X42_PM22X40     TOP       TOP            2800      4600                 
C  SMD24X95_PM20X91_IY1 TOP       TOP            2800      9900                 
C  SMD168X168           TOP       TOP           17200     17200                 
C  SH11X34_CUT          TOP       TOP            1500      3800                 
C  C30D30N_T3-14_0      TOP       BOTTOM         6000      6000                 
C  SMD56X231_PM35X231IX TOP       TOP            5912     23432                 
C  SMD56X231_PM35X231IX TOP       TOP            5912     23432                 
C  SMD126X270           TOP       TOP           13000     27400                 
C  SH4-6X4-7_PM4-3X4-41 TOP       TOP           18904     18510                 
C  SMD28X46_PM24X42     TOP       TOP            3200      5000                 
C  SMD128X135           TOP       TOP           13200     13900                 
C  C48D32_T2            TOP       BOTTOM         6200      6200                 
C  C52D52N              TOP       BOTTOM         8200      8200                 
C  SMD18X20             TOP       TOP            2200      2400                 
C  FIDUCIAL_40          TOP       TOP           12000     12000                 
C  C125D125N            TOP       BOTTOM        15500     15500                 
C  C256D125N_V165_ANT25 TOP       BOTTOM        26000     26000                 
C  SMD116X146           TOP       TOP           12000     15000                 
C  C178D178N            TOP       BOTTOM        20800     20800                 
C  C134D134N            TOP       BOTTOM        16400     16400                 
C  SMD46X69             TOP       TOP            5000      7300                 
C  VIA16D8A24_BGA       TOP       BOTTOM         2400      2400                 
C  C256D126             TOP       BOTTOM        26000     26000                 
C  SMD37X50_CUT         TOP       TOP            4042      5322                 
C  SMD10X50             TOP       TOP            1400      5400                 
C  SMD10X32             TOP       TOP            1400      3600                 
C  SMD10X34_CUT         TOP       TOP            1384      3746                 
C  SMD59X79             TOP       TOP            6300      8300                 
C  VIA18D10A28_BGA      TOP       BOTTOM         2800      2800                 
C  R40X15               TOP       TOP            4400      1900                 
C  SMD14X58_SM14X58     TOP       TOP            1400      5800                 
C  SMD38X56             TOP       TOP            4200      6000                 
C  SMD22X56             TOP       TOP            2600      6000                 
C  SMD24X52             TOP       TOP            2800      5600                 
C  SMD16X54             TOP       TOP            2000      5800                 
C  SMD24X54             TOP       TOP            2800      5800                 
C  SMD32X75_PM28X71IY-1 TOP       TOP            3600      7900                 
C  SMD40X48             TOP       TOP            4400      5200                 
C  SMD24X28             TOP       TOP            2800      3200                 
C  SMD32X34             TOP       TOP            3600      3800                 
C  SMD14X48             TOP       TOP            1800      5200                 
C  C64D44_T2            TOP       BOTTOM         7400      7400                 
C  C44D44N              TOP       BOTTOM         7400      7400                 
C  OB62X137D44X97_T2    TOP       BOTTOM         7400     14100                 
C  OB64X137D44X97_T2    TOP       BOTTOM         7400     14100                 
C  SMD186X189           TOP       TOP           19000     19300                 
C  SMD50X56             TOP       TOP            5400      6000                 
C  SMD40X109            TOP       TOP            4400     11300                 
C  SMD46X63             TOP       TOP            5000      6700                 
C  SMD9X15              TOP       TOP            1300      1900                 
C  SMD134X134           TOP       TOP           13800     13800                 
C  SMD10X15             TOP       TOP            1400      1900                 
C  SMD10X14             TOP       TOP            1400      1800                 
C  SMD48X59             TOP       TOP            5200      6300                 
C  SMD36X40             TOP       TOP            4000      4400                 
C  SMD48X56             TOP       TOP            5200      6000                 
C  SMD24X44             TOP       TOP            2800      4800                 
C  SMD14X52             TOP       TOP            1800      5600                 
C  SMD14X59             TOP       TOP            1800      6300                 
C  SMD12X63_PM10X61     TOP       TOP            1600      6700                 
C  SMD24X46             TOP       TOP            2800      5000                 
C  SMD17X46             TOP       TOP            2100      5000                 
C  SMD124X124           TOP       TOP           12800     12800                 
C  SMD166X166           TOP       TOP           17000     17000                 
C  SH7X34_CUT           TOP       TOP            1100      3800                 
C  SH111X111_CUT        TOP       TOP           11424     11424                 
C  SMDC9                TOP       TOP            1300      1300                 
C  SMD7X22              TOP       TOP            1100      2600                 
C  SMD201X201_CUT       TOP       TOP           20478     20478                 
C  SMD140X140           TOP       TOP           14400     14400                 
C  SMD10X29             TOP       TOP            1400      3300                 
C  SMD24X32             TOP       TOP            2800      3600                 
C  SMD6X28              TOP       TOP            1000      3200                 
C  SMD7X20              TOP       TOP            1100      2400                 
C  SMD28X40_PM24X36     TOP       TOP            3200      4400                 
C  SMD24X28_PM20X24     TOP       TOP            2800      3200                 
C  SMD14X44             TOP       TOP            1800      4800                 
C  SMD85X89             TOP       TOP            8900      9300                 
C  OB44X87D20X63_T1-96  TOP       BOTTOM         5000      9300                 
C  OB44X71D20X48_T1-96  TOP       BOTTOM         5000      7800                 
C  SMD17X59             TOP       TOP            2100      6300                 
C  VT18D8B20            TOP       BOTTOM         7502      7500                 
C  SMD14X63_PM12X61     TOP       TOP            1800      6700                 
C  SMD11X54             TOP       TOP            1500      5800                 
C  SMD25X48             TOP       TOP            2900      5200                 
C  SMD11X28             TOP       TOP            1500      3200                 
C  SMD22X68             TOP       TOP            2600      7200                 
C  SMD115X138           TOP       TOP           11900     14200                 
C  C28-2D12-2_T1-96_FIT TOP       BOTTOM         3220      3220                 
C  S28-2D12-2_T1-96_FIT TOP       BOTTOM         3220      3220                 
C  SMD67X67             TOP       TOP            7100      7100                 
C  SMD10X22             TOP       TOP            1400      2600                 
C  SMD63X138            TOP       TOP            6700     14200                 
C  SMD11X18             TOP       TOP            1500      2200                 
C  SMD46X386_SM46X71_PM TOP       TOP            4600     38600                 
C  SMD30X36_CUT         TOP       TOP            3352      3944                 
C  SMD30X36_CUT_R       TOP       TOP            3352      3944                 
C  SMD10X28             TOP       TOP            1400      3200                 
C  SMD69X105            TOP       TOP            7300     10900                 
C  SMD67X99             TOP       TOP            7100     10300                 
C  SMD28X52             TOP       TOP            3200      5600                 
C  SMD11X32             TOP       TOP            1500      3600                 
C  SMD73X138            TOP       TOP            7700     14200                 
C  C61D41               TOP       BOTTOM         7100      7100                 
C  S61D41               TOP       BOTTOM         7100      7100                 
C  SMD14X61             TOP       TOP            1800      6500                 
C  SMD95X130            TOP       TOP            9900     13400                 
C  SMD10X20             TOP       TOP            1400      2400                 
C  SMD32X36             TOP       TOP            3600      4000                 
C  SMD11X36             TOP       TOP            1500      4000                 
C  SH32X124_SM32X124_CU TOP       TOP            3150     12402                 
C  SMD12X79             TOP       TOP            1600      8300                 
C  SMD12X32             TOP       TOP            1600      3600                 
C  SMD7X32              TOP       TOP            1100      3600                 
C  SMD130X169-2         TOP       TOP           13400     17320                 
C  SMD42X99             TOP       TOP            4600     10300                 
C  SMD18X20_NPM         TOP       TOP            2200      2400                 
C  SH20X18_NPM          TOP       TOP            2400      4200                 
C  GHC30D22_NTH         TOP       BOTTOM         4200      4200                 
C  C125D125N_T2-0       TOP       BOTTOM        15500     15500                 
C  R166X197D79B158_IX3- TOP       BOTTOM        17000     20100                 
C  C85D67_SM85_NPM      TOP       BOTTOM         9700      9700                 
C  TC785CC25_O          TOP       BOTTOM         8700      8700                 
C  TC395CC25_O          TOP       BOTTOM         4800      4800                 
C  VIA19-3D10           TOP       BOTTOM         3000      3000                 
C  SMD44X54             TOP       TOP            4800      5800                 
C  SMD12X18             TOP       TOP            1600      2200                 
C  SMD24X170            TOP       TOP            2800     17400                 
C  SMD81X91             TOP       TOP            8500      9500                 
C  SMD69X77             TOP       TOP            7300      8100                 
C  SMD83X213_CUT        TOP       TOP            8668     21660                 
C  SMD9X24              TOP       TOP            1300      2800                 
C  SMD7X24              TOP       TOP            1100      2800                 
C  SMD144X144           TOP       TOP           14800     14800                 
C  SMD122X132           TOP       TOP           12600     13600                 
C  SH28X32_NPM          TOP       TOP            3200      7600                 
C  SMD28X32_NPM         TOP       TOP            3200      3600                 
C  RE-R_0824-2          TOP       TOP            2384      2368                 
C  RE-L_0824-2          TOP       TOP            2384      2368                 
C  VIA18D10A26_BGA_DBFI TOP       BOTTOM         2600      2600                 
C  SMD50X135            TOP       TOP            5400     13900                 
C  SMD95X111            TOP       TOP            9900     11500                 
C  SMD63X119            TOP       TOP            6700     12300                 
C  SMD84-8X130          TOP       TOP            8880     13400                 
C  VIA16D8A26_BGA       TOP       BOTTOM         2600      2600                 
C  SMDC16               TOP       TOP            2000      2000                 
C  SMD40X56             TOP       TOP            4400      6000                 
C  SMD16X24             TOP       TOP            2000      2800                 
C  SMD24X24_PM20X20     TOP       TOP            2800      2800                 
C  SMD22X53             TOP       TOP            2600      5700                 
C  SMD16X36_PM14X34     TOP       TOP            2000      4000                 
C  SMD20X60             TOP       TOP            2400      6400                 
C  SMD17X24             TOP       TOP            2100      2800                 
C  SMDC18               TOP       TOP            2200      2200                 
C  OB64X137D44X97_T1-96 TOP       BOTTOM         7400     14100                 
C  SMD15X50             TOP       TOP            1900      5400                 
C  C44D44N_T1-96        TOP       BOTTOM         7400      7400                 
C  SMD15X53             TOP       TOP            1900      5700                 
C  C35-68D19-68_T1-96_F TOP       BOTTOM         3968      3968                 
C  C70-51D39-99_FIT     TOP       BOTTOM         7451      7451                 
C  S70-51D39-99_FIT     TOP       BOTTOM         7451      7451                 
C  SMD12X15             TOP       TOP            1600      1900                 
C  SMD40X50             TOP       TOP            4400      5400                 
C  SMD28X32             TOP       TOP            3200      3600                 
C  OC20X4R              TOP       TOP            1640      1640                 
C  VT20D10T30           TOP       BOTTOM         7502      7500                 
C  VT20D10B26           TOP       BOTTOM         7502      7500                 
C  VIA20D10             TOP       BOTTOM         3000      3000                 
C  SPD_C125                                     12500     12500                 
C  TP26B                BOTTOM    BOTTOM         7500      7500                 
C  TP30T                TOP       TOP            7500      7500                 
C                                                                               
C                                                                               
C  ****************************************                                     
C     Name mapping for long Signal names                                        
C  ****************************************                                     
C                                                                               
P  NNAMEm0000 BIC_USB_HUB_XOUT_R                                                
P  NNAMEm0001 PEX_USB_HUB_XOUT_R                                                
P  NNAMEm0002 FM_UV_LT6700_VS                                                   
P  NNAMEm0003 HSC_OC_LT6700_VS                                                  
P  NNAMEm0004 BOARD_TYPE_2_ADC_R                                                
P  NNAMEm0005 BOARD_TYPE_1_ADC_R                                                
P  NNAMEm0006 BOARD_TYPE_0_ADC_R                                                
P  NNAMEm0007 SMB_BIC_FPGA_R2_SDA                                               
P  NNAMEm0008 SMB_BIC_FPGA_R2_SCL                                               
P  NNAMEm0009 P12V_AUX_FP_TRIGGER                                               
P  NNAMEm0010 SMB_BIC_FPGA_R1_SCL                                               
P  NNAMEm0011 SMB_BIC_FPGA_R1_SDA                                               
P  NNAMEm0012 PRSNT_GPU_A1_R_N                                                  
P  NNAMEm0013 PRSNT_GPU_A2_R_N                                                  
P  NNAMEm0014 PRSNT_GPU_A3_R_N                                                  
P  NNAMEm0015 BIC_USB_8042_HUB_HS_SUSPEND                                       
P  NNAMEm0016 BIC_USB_8042_HUB_OVCUR4                                           
P  NNAMEm0017 BIC_USB_8042_HUB_OVCUR3                                           
P  NNAMEm0018 BIC_USB_8042_HUB_OVCUR2                                           
P  NNAMEm0019 BIC_USB_8042_HUB_OVCUR1                                           
P  NNAMEm0020 BIC_USB_8042_HUB_VBUS                                             
P  NNAMEm0021 BIC_USB_8042_HUB_XOUT                                             
P  NNAMEm0022 BIC_USB_8042_HUB_XIN                                              
P  NNAMEm0023 USB2_GPU_HMC_USB8042_DN                                           
P  NNAMEm0024 USB2_GPU_HMC_USB8042_DP                                           
P  NNAMEm0025 USB2_BIC_USB8042_DN                                               
P  NNAMEm0026 USB2_BIC_USB8042_DP                                               
P  NNAMEm0027 USB2_MB_BMC_USB8042_DN                                            
P  NNAMEm0028 USB2_MB_BMC_USB8042_DP                                            
P  NNAMEm0029 BIC_USB_8042_HUB_PWRCTL3                                          
P  NNAMEm0030 BIC_USB_8042_HUB_PWRCTL2                                          
P  NNAMEm0031 BIC_USB_8042_HUB_TEST                                             
P  NNAMEm0032 BIC_USB_8042_HUB_GRSTZ                                            
P  NNAMEm0033 BIC_USB_8042_HUB_FULLPWRMGMTZ                                     
P  NNAMEm0034 BIC_USB_8042_HUB_GANGED                                           
P  NNAMEm0035 BIC_USB_8042_HUB_R1                                               
P  NNAMEm0036 TDR_DIFF_100_IN3_DIN                                              
P  NNAMEm0037 TDR_DIFF_100_BOT_DIN                                              
P  NNAMEm0038 TDR_DIFF_100_IN5_DIP                                              
P  NNAMEm0039 TDR_DIFF_100_IN3_DIP                                              
P  NNAMEm0040 TDR_DIFF_100_IN5_DIN                                              
P  NNAMEm0041 TDR_DIFF_100_IN1_DIN                                              
P  NNAMEm0042 TDR_DIFF_100_IN6_DIN                                              
P  NNAMEm0043 TDR_DIFF_100_IN6_DIP                                              
P  NNAMEm0044 TDR_DIFF_100_IN2_DIN                                              
P  NNAMEm0045 TDR_DIFF_100_TOP_DIN                                              
P  NNAMEm0046 TDR_DIFF_100_TOP_DIP                                              
P  NNAMEm0047 TDR_DIFF_100_BOT_DIP                                              
P  NNAMEm0048 TDR_DIFF_100_IN1_DIP                                              
P  NNAMEm0049 TDR_DIFF_100_IN4_DIP                                              
P  NNAMEm0050 TDR_DIFF_100_IN2_DIP                                              
P  NNAMEm0051 TDR_DIFF_100_IN4_DIN                                              
P  NNAMEm0052 SMB_PEX2_SLAVE1_SCL                                               
P  NNAMEm0053 SMB_PEX2_SLAVE1_SDA                                               
P  NNAMEm0054 SMB_PEX3_SLAVE1_SDA                                               
P  NNAMEm0055 SMB_PEX3_SLAVE1_SCL                                               
P  NNAMEm0056 SMB_PEX1_SLAVE1_SCL                                               
P  NNAMEm0057 SMB_PEX1_SLAVE1_SDA                                               
P  NNAMEm0058 GPU_3V3IO_RSVD4_ISO_R                                             
P  NNAMEm0059 GPU_3V3IO_RSVD4_ISO                                               
P  NNAMEm0060 GPU_3V3IO_RSVD3_ISO_R                                             
P  NNAMEm0061 GPU_3V3IO_RSVD3_ISO                                               
P  NNAMEm0062 GPU_3V3IO_RSVD4_N                                                 
P  NNAMEm0063 GPU_3V3IO_RSVD3_N                                                 
P  NNAMEm0064 SMB_PEX0_SLAVE1_SCL                                               
P  NNAMEm0065 SMB_PEX0_SLAVE1_SDA                                               
P  NNAMEm0066 SPI_BIC1_LS01_EN                                                  
P  NNAMEm0067 SPI_BIC1_LS23_EN                                                  
P  NNAMEm0068 A_HSC_LOW_DRAIN                                                   
P  NNAMEm0069 GPU_3V3IO_RSVD1_ISO_R                                             
P  NNAMEm0070 GPU_3V3IO_RSVD1_ISO                                               
P  NNAMEm0071 GPU_3V3IO_RSVD1_N                                                 
P  NNAMEm0072 NIC0_CLK_EN_BUF_R_N                                               
P  NNAMEm0073 NIC2_CLK_EN_BUF_R_N                                               
P  NNAMEm0074 NIC1_CLK_EN_BUF_R_N                                               
P  NNAMEm0075 MB_3V3IO_RSVD1_ISO_R                                              
P  NNAMEm0076 NIC6_CLK_EN_BUF_R_N                                               
P  NNAMEm0077 NIC7_CLK_EN_BUF_R_N                                               
P  NNAMEm0078 MB_3V3IO_RSVD3_ISO_R                                              
P  NNAMEm0079 NIC5_CLK_EN_BUF_R_N                                               
P  NNAMEm0080 NIC3_CLK_EN_BUF_R_N                                               
P  NNAMEm0081 MB_3V3IO_RSVD4_ISO_R                                              
P  NNAMEm0082 NIC4_CLK_EN_BUF_R_N                                               
P  NNAMEm0083 MB_3V3IO_RSVD4_ISO                                                
P  NNAMEm0084 MB_3V3IO_RSVD3_ISO                                                
P  NNAMEm0085 MB_3V3IO_RSVD1_ISO                                                
P  NNAMEm0086 MB_3V3IO_RSVD1_N                                                  
P  NNAMEm0087 MB_3V3IO_RSVD3_N                                                  
P  NNAMEm0088 MB_3V3IO_RSVD4_N                                                  
P  NNAMEm0089 NIC7_CLK_EN_BUF_N                                                 
P  NNAMEm0090 NIC6_CLK_EN_BUF_N                                                 
P  NNAMEm0091 NIC5_CLK_EN_BUF_N                                                 
P  NNAMEm0092 NIC4_CLK_EN_BUF_N                                                 
P  NNAMEm0093 NIC3_CLK_EN_BUF_N                                                 
P  NNAMEm0094 NIC2_CLK_EN_BUF_N                                                 
P  NNAMEm0095 NIC1_CLK_EN_BUF_N                                                 
P  NNAMEm0096 NIC0_CLK_EN_BUF_N                                                 
P  NNAMEm0097 P12V_HSC_SENSE2_R2_P                                              
P  NNAMEm0098 LTC4282_T_CRIT_N                                                  
P  NNAMEm0099 P12V_HSC_GATE_RC                                                  
P  NNAMEm0100 P12V_HSC_SENSE2_R2_N                                              
P  NNAMEm0101 UART_PEX0_CLI_BUF_R1_TX                                           
P  NNAMEm0102 UART_PEX3_CLI_R1_RX                                               
P  NNAMEm0103 UART_PEX1_CLI_R1_RX                                               
P  NNAMEm0104 UART_PEX1_CLI_BUF_R1_TX                                           
P  NNAMEm0105 UART_PEX2_CLI_R1_RX                                               
P  NNAMEm0106 UART_PEX3_CLI_BUF_R1_TX                                           
P  NNAMEm0107 UART_PEX2_CLI_BUF_R1_TX                                           
P  NNAMEm0108 UART_PEX0_CLI_R1_RX                                               
P  NNAMEm0109 UART_PEX1_SDB_R1_RX                                               
P  NNAMEm0110 UART_PEX2_SDB_R1_RX                                               
P  NNAMEm0111 UART_PEX2_SDB_BUF_R1_TX                                           
P  NNAMEm0112 UART_PEX3_SDB_R1_RX                                               
P  NNAMEm0113 UART_PEX0_SDB_BUF_R1_TX                                           
P  NNAMEm0114 UART_PEX0_SDB_R1_RX                                               
P  NNAMEm0115 UART_PEX1_SDB_BUF_R1_TX                                           
P  NNAMEm0116 UART_PEX3_SDB_BUF_R1_TX                                           
P  NNAMEm0117 P12V_HSC_SENSE1_N                                                 
P  NNAMEm0118 MB0_P12V_STBY_PWRGD                                               
P  NNAMEm0119 SMB_SML1_PMBUS_HSC_SDA                                            
P  NNAMEm0120 IRQ_SML1_PMBUS_ALERT_N                                            
P  NNAMEm0121 P12V_HSC_SENSE2_R1_N                                              
P  NNAMEm0122 P12V_HSC_SENSE1_P                                                 
P  NNAMEm0123 IRQ_HSC_FAULT_R_N                                                 
P  NNAMEm0124 SMB_SML1_PMBUS_HSC_SCL                                            
P  NNAMEm0125 P12V_HSC_SENSE2_P                                                 
P  NNAMEm0126 P12V_HSC_SENSE2_N                                                 
P  NNAMEm0127 HSC_D_OC_FPGA_N                                                   
P  NNAMEm0128 P12V_HSC_SENSE2_R1_P                                              
P  NNAMEm0129 UART_PEX0_CLI_BUF_R_TX                                            
P  NNAMEm0130 UART_PEX3_CLI_CP2108_RX                                           
P  NNAMEm0131 UART_PEX1_CLI_BUF_R_TX                                            
P  NNAMEm0132 UART_PEX3_CLI_CP2108_TX                                           
P  NNAMEm0133 UART_PEX0_CLI_CP2108_RX                                           
P  NNAMEm0134 UART_PEX2_CLI_CP2108_TX                                           
P  NNAMEm0135 UART_PEX1_CLI_CP2108_TX                                           
P  NNAMEm0136 UART_PEX3_CLI_BUF_R_TX                                            
P  NNAMEm0137 UART_PEX2_CLI_CP2108_RX                                           
P  NNAMEm0138 UART_PEX1_CLI_CP2108_RX                                           
P  NNAMEm0139 UART_PEX2_CLI_BUF_R_TX                                            
P  NNAMEm0140 UART_PEX0_CLI_CP2108_TX                                           
P  NNAMEm0141 USB2_CP2108_CLI_DN                                                
P  NNAMEm0142 USB2_CP2108_CLI_DP                                                
P  NNAMEm0143 UART_PEX2_SDB_CP2108_RX                                           
P  NNAMEm0144 UART_PEX1_SDB_CP2108_TX                                           
P  NNAMEm0145 RST_CP2108_CLI_R_N                                                
P  NNAMEm0146 UART_PEX0_SDB_CP2108_TX                                           
P  NNAMEm0147 UART_PEX1_SDB_CP2108_RX                                           
P  NNAMEm0148 RST_CP2108_SDB_R_N                                                
P  NNAMEm0149 UART_PEX0_SDB_CP2108_RX                                           
P  NNAMEm0150 USB2_CP2108_SDB_DP                                                
P  NNAMEm0151 UART_PEX2_SDB_CP2108_TX                                           
P  NNAMEm0152 UART_PEX3_SDB_CP2108_RX                                           
P  NNAMEm0153 UART_PEX3_SDB_CP2108_TX                                           
P  NNAMEm0154 USB2_CP2108_SDB_DN                                                
P  NNAMEm0155 HSC_P12V_MP5990_EN                                                
P  NNAMEm0156 LTC4282_ALERT1_R_N                                                
P  NNAMEm0157 SMB_LTC4282_TEMP_SDA                                              
P  NNAMEm0158 SMB_LTC4282_TEMP_SCL                                              
P  NNAMEm0159 LTC4282_TEMP_D-                                                   
P  NNAMEm0160 LTC4282_TEMP_D+                                                   
P  NNAMEm0161 LTC4282_TEMP_R_D-                                                 
P  NNAMEm0162 LTC4282_TEMP_R_D+                                                 
P  NNAMEm0163 P1V8_PLL0_PEX1_SCALED                                             
P  NNAMEm0164 PWRGD_PEX3_P1V8_PLL_R                                             
P  NNAMEm0165 PWRGD_PEX2_P1V8_PLL_R                                             
P  NNAMEm0166 PWRGD_PEX1_P1V8_PLL_R                                             
P  NNAMEm0167 PWRGD_PEX1_P1V8_PLL                                               
P  NNAMEm0168 P1V8_PLL_PEX1_ADJ                                                 
P  NNAMEm0169 PEX1_P1V8_PLL_EN                                                  
P  NNAMEm0170 P1V8_PLL_PEX0_ADJ                                                 
P  NNAMEm0171 PWRGD_PEX0_P1V8_PLL                                               
P  NNAMEm0172 PEX0_P1V8_PLL_EN                                                  
P  NNAMEm0173 P1V8_PLL0_PEX3_SCALED                                             
P  NNAMEm0174 P1V8_PLL0_PEX2_SCALED                                             
P  NNAMEm0175 P1V8_PLL0_PEX0_SCALED                                             
P  NNAMEm0176 PWRGD_PEX3_P1V8_PLL                                               
P  NNAMEm0177 PWRGD_PEX2_P1V8_PLL                                               
P  NNAMEm0178 PEX3_P1V8_PLL_EN                                                  
P  NNAMEm0179 P1V8_PLL_PEX3_ADJ                                                 
P  NNAMEm0180 PWRGD_PEX0_P1V8_PLL_R                                             
P  NNAMEm0181 PEX2_P1V8_PLL_EN                                                  
P  NNAMEm0182 P1V8_PLL_PEX2_ADJ                                                 
P  NNAMEm0183 P1V25_SERDES_VDDPLL_PEX1_C10                                      
P  NNAMEm0184 P1V25_SERDES_VDDPLL_PEX1_C9                                       
P  NNAMEm0185 P1V25_SERDES_VDDPLL_PEX1_C7                                       
P  NNAMEm0186 P0V8_SERDES_VDDA_PEX1_C1                                          
P  NNAMEm0187 P1V25_SERDES_VDDPLL_PEX1_C4                                       
P  NNAMEm0188 P0V8_SERDES_VDDA_PEX1_C7                                          
P  NNAMEm0189 P1V25_SERDES_VDDPLL_PEX1_C11                                      
P  NNAMEm0190 P1V25_SERDES_VDDPLL_PEX1_C2                                       
P  NNAMEm0191 P1V25_SERDES_VDDPLL_PEX1_C0                                       
P  NNAMEm0192 P0V8_SERDES_VDDA_PEX1_C11                                         
P  NNAMEm0193 P0V8_SERDES_VDDA_PEX1_C2                                          
P  NNAMEm0194 P0V8_SERDES_VDDA_PEX1_C9                                          
P  NNAMEm0195 P0V8_SERDES_VDDA_PEX1_C5                                          
P  NNAMEm0196 P0V8_SERDES_VDDA_PEX1_C6                                          
P  NNAMEm0197 P0V8_SERDES_VDDA_PEX1_C3                                          
P  NNAMEm0198 P1V25_SERDES_VDDPLL_PEX1_C8                                       
P  NNAMEm0199 P0V8_SERDES_VDDA_PEX1_C10                                         
P  NNAMEm0200 P0V8_SERDES_VDDA_PEX1_C4                                          
P  NNAMEm0201 P0V8_SERDES_VDDA_PEX1_C0                                          
P  NNAMEm0202 P1V25_SERDES_VDDPLL_PEX1_C1                                       
P  NNAMEm0203 P1V25_SERDES_VDDPLL_PEX1_C6                                       
P  NNAMEm0204 P1V25_SERDES_VDDPLL_PEX1_C5                                       
P  NNAMEm0205 P0V8_SERDES_VDDA_PEX1_C8                                          
P  NNAMEm0206 P1V25_SERDES_VDDPLL_PEX1_C3                                       
P  NNAMEm0207 P0V8_SERDES_VDDA_PEX2_C3                                          
P  NNAMEm0208 P1V25_SERDES_VDDPLL_PEX2_C5                                       
P  NNAMEm0209 P0V8_SERDES_VDDA_PEX2_C10                                         
P  NNAMEm0210 P1V25_SERDES_VDDPLL_PEX2_C3                                       
P  NNAMEm0211 P1V25_SERDES_VDDPLL_PEX2_C7                                       
P  NNAMEm0212 P0V8_SERDES_VDDA_PEX2_C2                                          
P  NNAMEm0213 P0V8_SERDES_VDDA_PEX2_C6                                          
P  NNAMEm0214 P1V25_SERDES_VDDPLL_PEX2_C9                                       
P  NNAMEm0215 P1V25_SERDES_VDDPLL_PEX2_C0                                       
P  NNAMEm0216 P1V25_SERDES_VDDPLL_PEX2_C11                                      
P  NNAMEm0217 P0V8_SERDES_VDDA_PEX2_C8                                          
P  NNAMEm0218 P0V8_SERDES_VDDA_PEX0_C7                                          
P  NNAMEm0219 P1V25_SERDES_VDDPLL_PEX2_C1                                       
P  NNAMEm0220 P0V8_SERDES_VDDA_PEX0_C6                                          
P  NNAMEm0221 P1V25_SERDES_VDDPLL_PEX2_C2                                       
P  NNAMEm0222 P0V8_SERDES_VDDA_PEX0_C9                                          
P  NNAMEm0223 P0V8_SERDES_VDDA_PEX2_C1                                          
P  NNAMEm0224 P0V8_SERDES_VDDA_PEX0_C10                                         
P  NNAMEm0225 P0V8_SERDES_VDDA_PEX2_C11                                         
P  NNAMEm0226 P0V8_SERDES_VDDA_PEX0_C11                                         
P  NNAMEm0227 P0V8_SERDES_VDDA_PEX2_C5                                          
P  NNAMEm0228 P0V8_SERDES_VDDA_PEX0_C8                                          
P  NNAMEm0229 P1V25_SERDES_VDDPLL_PEX2_C8                                       
P  NNAMEm0230 P1V25_SERDES_VDDPLL_PEX2_C6                                       
P  NNAMEm0231 P1V25_SERDES_VDDPLL_PEX2_C10                                      
P  NNAMEm0232 P0V8_SERDES_VDDA_PEX2_C7                                          
P  NNAMEm0233 P1V25_SERDES_VDDPLL_PEX2_C4                                       
P  NNAMEm0234 P0V8_SERDES_VDDA_PEX2_C4                                          
P  NNAMEm0235 P0V8_SERDES_VDDA_PEX2_C0                                          
P  NNAMEm0236 P0V8_SERDES_VDDA_PEX2_C9                                          
P  NNAMEm0237 P0V8_SERDES_VDDA_PEX3_C5                                          
P  NNAMEm0238 P1V25_SERDES_VDDPLL_PEX3_C1                                       
P  NNAMEm0239 P0V8_SERDES_VDDA_PEX3_C11                                         
P  NNAMEm0240 P1V25_SERDES_VDDPLL_PEX3_C4                                       
P  NNAMEm0241 P1V25_SERDES_VDDPLL_PEX3_C9                                       
P  NNAMEm0242 P0V8_SERDES_VDDA_PEX3_C8                                          
P  NNAMEm0243 P1V25_SERDES_VDDPLL_PEX3_C0                                       
P  NNAMEm0244 P0V8_SERDES_VDDA_PEX3_C9                                          
P  NNAMEm0245 P1V25_SERDES_VDDPLL_PEX3_C8                                       
P  NNAMEm0246 P1V25_SERDES_VDDPLL_PEX3_C10                                      
P  NNAMEm0247 P1V25_SERDES_VDDPLL_PEX3_C5                                       
P  NNAMEm0248 P1V25_SERDES_VDDPLL_PEX3_C2                                       
P  NNAMEm0249 P0V8_SERDES_VDDA_PEX3_C6                                          
P  NNAMEm0250 P1V25_SERDES_VDDPLL_PEX3_C6                                       
P  NNAMEm0251 P1V25_SERDES_VDDPLL_PEX3_C3                                       
P  NNAMEm0252 P1V25_SERDES_VDDPLL_PEX3_C11                                      
P  NNAMEm0253 P0V8_SERDES_VDDA_PEX3_C2                                          
P  NNAMEm0254 P0V8_SERDES_VDDA_PEX3_C0                                          
P  NNAMEm0255 P0V8_SERDES_VDDA_PEX3_C1                                          
P  NNAMEm0256 P0V8_SERDES_VDDA_PEX3_C4                                          
P  NNAMEm0257 P0V8_SERDES_VDDA_PEX3_C10                                         
P  NNAMEm0258 P1V25_SERDES_VDDPLL_PEX3_C7                                       
P  NNAMEm0259 P0V8_SERDES_VDDA_PEX3_C3                                          
P  NNAMEm0260 P0V8_SERDES_VDDA_PEX3_C7                                          
P  NNAMEm0261 P1V25_SERDES_VDDPLL_PEX0_C7                                       
P  NNAMEm0262 P1V25_SERDES_VDDPLL_PEX0_C2                                       
P  NNAMEm0263 P1V25_SERDES_VDDPLL_PEX0_C10                                      
P  NNAMEm0264 P1V25_SERDES_VDDPLL_PEX0_C8                                       
P  NNAMEm0265 P1V25_SERDES_VDDPLL_PEX0_C9                                       
P  NNAMEm0266 P1V25_SERDES_VDDPLL_PEX0_C5                                       
P  NNAMEm0267 P1V25_SERDES_VDDPLL_PEX0_C4                                       
P  NNAMEm0268 P1V25_SERDES_VDDPLL_PEX0_C0                                       
P  NNAMEm0269 P1V25_SERDES_VDDPLL_PEX0_C6                                       
P  NNAMEm0270 P1V25_SERDES_VDDPLL_PEX0_C3                                       
P  NNAMEm0271 P1V25_SERDES_VDDPLL_PEX0_C11                                      
P  NNAMEm0272 P0V8_SERDES_VDDA_PEX0_C0                                          
P  NNAMEm0273 P1V25_SERDES_VDDPLL_PEX0_C1                                       
P  NNAMEm0274 P0V8_SERDES_VDDA_PEX0_C5                                          
P  NNAMEm0275 P0V8_SERDES_VDDA_PEX0_C4                                          
P  NNAMEm0276 P0V8_SERDES_VDDA_PEX0_C3                                          
P  NNAMEm0277 P0V8_SERDES_VDDA_PEX0_C2                                          
P  NNAMEm0278 P0V8_SERDES_VDDA_PEX0_C1                                          
P  NNAMEm0279 FPGA_PEX0_MODE_SEL1_ISO                                           
P  NNAMEm0280 FPGA_PEX0_MODE_SEL1_D_N                                           
P  NNAMEm0281 FPGA_PEX3_MODE_SEL1                                               
P  NNAMEm0282 FPGA_PEX3_MODE_SEL1_R                                             
P  NNAMEm0283 FPGA_PEX3_MODE_SEL2                                               
P  NNAMEm0284 FPGA_PEX3_MODE_SEL2_R                                             
P  NNAMEm0285 FPGA_PEX2_MODE_SEL1_R                                             
P  NNAMEm0286 FPGA_PEX2_MODE_SEL1                                               
P  NNAMEm0287 FPGA_PEX2_MODE_SEL2                                               
P  NNAMEm0288 FPGA_PEX2_MODE_SEL2_R                                             
P  NNAMEm0289 FPGA_PEX1_MODE_SEL1_R                                             
P  NNAMEm0290 FPGA_PEX1_MODE_SEL1                                               
P  NNAMEm0291 FPGA_PEX1_MODE_SEL2                                               
P  NNAMEm0292 FPGA_PEX1_MODE_SEL2_R                                             
P  NNAMEm0293 FPGA_PEX0_MODE_SEL1_R                                             
P  NNAMEm0294 FPGA_PEX0_MODE_SEL1                                               
P  NNAMEm0295 FPGA_PEX3_MODE_SEL1_ISO                                           
P  NNAMEm0296 FPGA_PEX3_MODE_SEL1_D_N                                           
P  NNAMEm0297 FPGA_PEX3_MODE_SEL2_ISO                                           
P  NNAMEm0298 FPGA_PEX0_MODE_SEL2_R                                             
P  NNAMEm0299 FPGA_PEX3_MODE_SEL2_D_N                                           
P  NNAMEm0300 FPGA_PEX0_MODE_SEL2                                               
P  NNAMEm0301 FPGA_PEX2_MODE_SEL1_ISO                                           
P  NNAMEm0302 FPGA_PEX2_MODE_SEL1_D_N                                           
P  NNAMEm0303 FPGA_PEX2_MODE_SEL2_ISO                                           
P  NNAMEm0304 FPGA_PEX2_MODE_SEL2_D_N                                           
P  NNAMEm0305 FPGA_PEX1_MODE_SEL1_ISO                                           
P  NNAMEm0306 FPGA_PEX1_MODE_SEL1_D_N                                           
P  NNAMEm0307 FPGA_PEX1_MODE_SEL2_ISO                                           
P  NNAMEm0308 FPGA_PEX1_MODE_SEL2_D_N                                           
P  NNAMEm0309 FPGA_PEX0_MODE_SEL2_ISO                                           
P  NNAMEm0310 FPGA_PEX0_MODE_SEL2_D_N                                           
P  NNAMEm0311 RST_PEX3_S3_PERST_R_N                                             
P  NNAMEm0312 CLK_100M_DB800ZL_PEX3_S3_R_DN                                     
P  NNAMEm0313 CLK_100M_DB800ZL_PEX3_S3_R_DP                                     
P  NNAMEm0314 CLK_100M_DB800ZL_PEX2_S3_R_DN                                     
P  NNAMEm0315 CLK_100M_DB800ZL_PEX2_S3_R_DP                                     
P  NNAMEm0316 RST_PEX2_S3_PERST_R_N                                             
P  NNAMEm0317 CLK_100M_DB800ZL_PEX1_S3_R_DN                                     
P  NNAMEm0318 CLK_100M_DB800ZL_PEX1_S3_R_DP                                     
P  NNAMEm0319 RST_PEX1_S3_PERST_R_N                                             
P  NNAMEm0320 CLK_100M_DB800ZL_PEX0_S3_R_DP                                     
P  NNAMEm0321 CLK_100M_DB800ZL_PEX0_S3_R_DN                                     
P  NNAMEm0322 RST_PEX0_S3_PERST_R_N                                             
P  NNAMEm0323 RST_PEX1_S3_PERST_N                                               
P  NNAMEm0324 RST_PEX1_S1_PERST_N                                               
P  NNAMEm0325 RST_PEX1_S0_PERST_N                                               
P  NNAMEm0326 SMB_PEX0_MUX_SDA                                                  
P  NNAMEm0327 SMB_PEX3_MUX_SDA                                                  
P  NNAMEm0328 SMB_PEX3_MUX_SCL                                                  
P  NNAMEm0329 SMB_PEX1_MUX_SDA                                                  
P  NNAMEm0330 SMB_PEX2_MUX_SDA                                                  
P  NNAMEm0331 SMB_PEX1_MUX_SCL                                                  
P  NNAMEm0332 SMB_PEX2_MUX_SCL                                                  
P  NNAMEm0333 SMB_PEX0_MUX_SCL                                                  
P  NNAMEm0334 SMB_PEX_MUX_SCL                                                   
P  NNAMEm0335 SMB_PEX_MUX_SDA                                                   
P  NNAMEm0336 RST_PEX0_S3_PERST_N                                               
P  NNAMEm0337 RST_PEX0_S1_PERST_N                                               
P  NNAMEm0338 RST_PEX0_S0_PERST_N                                               
P  NNAMEm0339 SMB_PEX_LS_R_SDA                                                  
P  NNAMEm0340 SMB_PEX_LS_R_SCL                                                  
P  NNAMEm0341 PWRGD_P3V3_AUX_BUF_R                                              
P  NNAMEm0342 PWRGD_P5V_AUX_BUF_R                                               
P  NNAMEm0343 PWRGD_P12V_AUX_BUF_R                                              
P  NNAMEm0344 PWRGD_P3V3_AUX_BUF                                                
P  NNAMEm0345 PWRGD_P5V_AUX_BUF                                                 
P  NNAMEm0346 PWRGD_P12V_AUX_BUF                                                
P  NNAMEm0347 PWRGD_P3V3_AUX_R2                                                 
P  NNAMEm0348 PWRGD_P5V_AUX_R2                                                  
P  NNAMEm0349 PWRGD_P12V_AUX_R1                                                 
P  NNAMEm0350 PEX_S3_REF_CLK_BUFFER_EN_N                                        
P  NNAMEm0351 RST_PEX3_S0_PERST_N                                               
P  NNAMEm0352 RST_PEX3_S1_PERST_N                                               
P  NNAMEm0353 RST_PEX3_S3_PERST_N                                               
P  NNAMEm0354 CLK_100M_DB800ZL_PEX1_S3_DP                                       
P  NNAMEm0355 CLK_100M_DB800ZL_PEX0_S3_DP                                       
P  NNAMEm0356 CLK_100M_DB800ZL_PEX3_S3_DP                                       
P  NNAMEm0357 CLK_100M_DB800ZL_PEX1_S3_DN                                       
P  NNAMEm0358 SMB_BMC_9FGL0451E_S3_SDA                                          
P  NNAMEm0359 CLK_100M_DB800ZL_PEX2_S3_DN                                       
P  NNAMEm0360 SMB_BMC_9FGL0451E_S3_SCL                                          
P  NNAMEm0361 CLK_100M_DB800ZL_PEX0_S3_DN                                       
P  NNAMEm0362 CLK_100M_DB800ZL_PEX2_S3_DP                                       
P  NNAMEm0363 CLK_100M_DB800ZL_PEX3_S3_DN                                       
P  NNAMEm0364 SMB_9ZXL0451E_S3_ADDR0                                            
P  NNAMEm0365 CLK_100M_MB_1_R_DP                                                
P  NNAMEm0366 CLK_100M_MB_1_DN                                                  
P  NNAMEm0367 CLK_100M_MB_1_R_DN                                                
P  NNAMEm0368 PU_9ZXL0451E_S3_HBW                                               
P  NNAMEm0369 CLK_100M_MB_1_DP                                                  
P  NNAMEm0370 RST_PEX2_S0_PERST_N                                               
P  NNAMEm0371 RST_PEX2_S1_PERST_N                                               
P  NNAMEm0372 P3V3_CLK_BUFFER_9ZXL0451E_S3_VZX3P3A                              
P  NNAMEm0373 RST_PEX2_S3_PERST_N                                               
P  NNAMEm0374 P3V3_CLK_BUFFER_9ZXL0451E_S3_VZX3P3                               
P  NNAMEm0375 RST_PEX_MUX_R_N                                                   
P  NNAMEm0376 SMB_NIC7_LS_R_SCL                                                 
P  NNAMEm0377 SMB_NIC7_LS_R_SDA                                                 
P  NNAMEm0378 SMB_NIC6_LS_R_SCL                                                 
P  NNAMEm0379 SMB_NIC6_LS_R_SDA                                                 
P  NNAMEm0380 SMB_NIC5_LS_R_SCL                                                 
P  NNAMEm0381 SMB_NIC5_LS_R_SDA                                                 
P  NNAMEm0382 SMB_NIC4_LS_R_SCL                                                 
P  NNAMEm0383 SMB_NIC4_LS_R_SDA                                                 
P  NNAMEm0384 PRSNT_DBV2_SLIMSAS_R                                              
P  NNAMEm0385 SMB_BIC_I2C6_MUX_THERMAL_R2_SCL                                   
P  NNAMEm0386 SMB_BIC_I2C6_MUX_THERMAL_R1_SCL                                   
P  NNAMEm0387 SMB_CLK_ISO_R_SCL_R1                                              
P  NNAMEm0388 JTAG_FPGA_R_TDO                                                   
P  NNAMEm0389 SMB_CLK_ISO_SDA                                                   
P  NNAMEm0390 SMB_CLK_ISO_SCL                                                   
P  NNAMEm0391 PD_BIC_UART_SEL                                                   
P  NNAMEm0392 PU_BIC_UART_SEL                                                   
P  NNAMEm0393 I3C_MB_BMC_R_SCL                                                  
P  NNAMEm0394 I3C_MB_BMC_R_SDA                                                  
P  NNAMEm0395 BIC_UART_HW_SEL1                                                  
P  NNAMEm0396 BIC_UART_SW_SEL1_R                                                
P  NNAMEm0397 SMB_CLK_ISO_R_SDA                                                 
P  NNAMEm0398 SMB_CLK_ISO_R_SCL                                                 
P  NNAMEm0399 SMB_MB_I3C_ISO_SDA                                                
P  NNAMEm0400 SMB_MB_I3C_ISO_SCL                                                
P  NNAMEm0401 GPU_HGX_DETECT_R_N                                                
P  NNAMEm0402 NC_P0V8_PEX2_PWM6                                                 
P  NNAMEm0403 NC_P0V8_PEX2_PWM5                                                 
P  NNAMEm0404 NC_P0V8_PEX2_ISEN6                                                
P  NNAMEm0405 NC_P0V8_PEX2_ISEN5                                                
P  NNAMEm0406 SMB_BIC_FPGA_R_SDA                                                
P  NNAMEm0407 SMB_BIC_FPGA_R_SCL                                                
P  NNAMEm0408 SMB_BIC_RECOVER_IOEXP_SDA                                         
P  NNAMEm0409 SMB_BIC_RECOVER_IOEXP_SCL                                         
P  NNAMEm0410 BIC_UART_BMC_SEL_R                                                
P  NNAMEm0411 BIC_UART_BMC_SEL                                                  
P  NNAMEm0412 BIC_UART_BIC_SEL_R                                                
P  NNAMEm0413 BIC_UART_SW_SEL1                                                  
P  NNAMEm0414 BIC_FWSPICK_IOEXP                                                 
P  NNAMEm0415 IRQ_BIC_RECOVER_IOEXP_N                                           
P  NNAMEm0416 RST_BIC_RECOVER_N                                                 
P  NNAMEm0417 BIC_RECOVER_IOEXP_A1                                              
P  NNAMEm0418 PD_MB_HSC_ISO_D1_EN                                               
P  NNAMEm0419 BIC_RECOVER_IOEXP_A0                                              
P  NNAMEm0420 NC_P0V8_PEX0_PWM4                                                 
P  NNAMEm0421 PRSNT_DBV2_SLIMSAS                                                
P  NNAMEm0422 NC_P0V8_PEX0_ISEN4                                                
P  NNAMEm0423 MB_HSC_ISO_D1_EN                                                  
P  NNAMEm0424 NC_P0V8_PEX0_ISEN5                                                
P  NNAMEm0425 NC_P0V8_PEX0_PWM5                                                 
P  NNAMEm0426 P4E_PEX0_STN3_TX_C_DN<49>                                         
P  NNAMEm0427 P4E_PEX0_STN3_RX_DP<49>                                           
P  NNAMEm0428 P4E_PEX0_STN3_TX_C_DP<49>                                         
P  NNAMEm0429 P4E_PEX0_STN3_TX_DN<48>                                           
P  NNAMEm0430 P4E_PEX0_STN3_TX_DP<48>                                           
P  NNAMEm0431 P4E_PEX0_STN3_TX_DN<49>                                           
P  NNAMEm0432 P4E_PEX0_STN3_TX_DP<49>                                           
P  NNAMEm0433 P4E_PEX0_STN3_RX_DN<48>                                           
P  NNAMEm0434 P4E_PEX0_STN3_TX_C_DP<48>                                         
P  NNAMEm0435 P4E_PEX0_STN3_TX_C_DN<48>                                         
P  NNAMEm0436 P4E_PEX0_STN3_RX_DP<48>                                           
P  NNAMEm0437 P4E_PEX0_STN3_RX_DN<49>                                           
P  NNAMEm0438 SPI_PEX2_SDIO1_MUX                                                
P  NNAMEm0439 SH_P0V8_PEX1_VSEN1_L                                              
P  NNAMEm0440 PRSNT_GPU_ISO_R1_N                                                
P  NNAMEm0441 SH_P0V8_PEX0_RGND0                                                
P  NNAMEm0442 TP_PEX3_VDDQ_EFUSE                                                
P  NNAMEm0443 TP_PEX2_VDDQ_EFUSE                                                
P  NNAMEm0444 TP_PEX1_VDDQ_EFUSE                                                
P  NNAMEm0445 TP_PEX0_VDDQ_EFUSE                                                
P  NNAMEm0446 SH_P0V8_PEX0_VSEN0_L                                              
P  NNAMEm0447 SPI_PEX3_RST_R_N                                                  
P  NNAMEm0448 SPI_PEX2_RST_R_N                                                  
P  NNAMEm0449 SPI_PEX1_RST_R_N                                                  
P  NNAMEm0450 RST_BIC_USB_HUB_R1_N                                              
P  NNAMEm0451 SH_P0V8_PEX1_RGND1                                                
P  NNAMEm0452 SH_P0V8_PEX3_VSEN3_L                                              
P  NNAMEm0453 SH_P0V8_PEX3_RGND3                                                
P  NNAMEm0454 SH_P0V8_PEX2_VSEN2_L                                              
P  NNAMEm0455 SH_P0V8_PEX2_RGND2                                                
P  NNAMEm0456 SPI_PEX0_RST_R_N                                                  
P  NNAMEm0457 PWRGD_P1V8_PEX_R1                                                 
P  NNAMEm0458 P12V_NIC7_CO_ISET_R                                               
P  NNAMEm0459 P12V_NIC4_CO_OV_FB                                                
P  NNAMEm0460 P12V_NIC7_CO_SS                                                   
P  NNAMEm0461 P12V_NIC4_CO_AVIN_PD                                              
P  NNAMEm0462 P12V_NIC6_CO_TIMER                                                
P  NNAMEm0463 P12V_NIC5_CO_IMON_VR                                              
P  NNAMEm0464 P12V_NIC6_CO_FLTB                                                 
P  NNAMEm0465 P12V_NIC5_CO_ISET                                                 
P  NNAMEm0466 P12V_NIC7_CO_OV_FB                                                
P  NNAMEm0467 P12V_NIC7_CO_AVIN_PD                                              
P  NNAMEm0468 PWRGD_P12V_NIC5_CO                                                
P  NNAMEm0469 P12V_NIC6_CO_OV_FB                                                
P  NNAMEm0470 P12V_NIC5_CO_ISET_R                                               
P  NNAMEm0471 P12V_NIC7_CO_EN                                                   
P  NNAMEm0472 P12V_NIC6_CO_SS                                                   
P  NNAMEm0473 P12V_NIC7_CO_ISET                                                 
P  NNAMEm0474 P12V_NIC6_CO_IMON_VR                                              
P  NNAMEm0475 P12V_NIC5_CO_AVIN_PD                                              
P  NNAMEm0476 P12V_NIC4_CO_TIMER                                                
P  NNAMEm0477 PWRGD_P12V_NIC7_CO                                                
P  NNAMEm0478 P12V_NIC4_CO_SS                                                   
P  NNAMEm0479 PWRGD_P12V_NIC6_CO                                                
P  NNAMEm0480 P12V_NIC7_CO_IMON_VR                                              
P  NNAMEm0481 P12V_NIC5_CO_FLTB                                                 
P  NNAMEm0482 P12V_NIC6_CO_ISET_R                                               
P  NNAMEm0483 P12V_NIC4_CO_FLTB                                                 
P  NNAMEm0484 P12V_NIC5_CO_OV_FB                                                
P  NNAMEm0485 P12V_NIC5_CO_SS                                                   
P  NNAMEm0486 PWRGD_P12V_NIC4_CO                                                
P  NNAMEm0487 P12V_NIC6_CO_EN                                                   
P  NNAMEm0488 P12V_NIC4_CO_IMON_VR                                              
P  NNAMEm0489 P12V_NIC5_CO_TIMER                                                
P  NNAMEm0490 P12V_NIC4_CO_EN                                                   
P  NNAMEm0491 P12V_NIC7_CO_FLTB                                                 
P  NNAMEm0492 P12V_NIC4_CO_ISET_R                                               
P  NNAMEm0493 P12V_NIC6_CO_ISET                                                 
P  NNAMEm0494 P12V_NIC4_CO_ISET                                                 
P  NNAMEm0495 P12V_NIC5_CO_EN                                                   
P  NNAMEm0496 P12V_NIC7_CO_TIMER                                                
P  NNAMEm0497 P12V_NIC6_CO_AVIN_PD                                              
P  NNAMEm0498 P3V3_SSD13_CO_ILIMIT                                              
P  NNAMEm0499 P3V3_SSD13_CO_EN                                                  
P  NNAMEm0500 P3V3_SSD14_CO_MODE                                                
P  NNAMEm0501 P3V3_SSD15_CO_ILIMIT                                              
P  NNAMEm0502 P3V3_SSD15_CO_MODE                                                
P  NNAMEm0503 P3V3_SSD11_CO_MODE                                                
P  NNAMEm0504 P3V3_SSD9_PG_G1                                                   
P  NNAMEm0505 P3V3_SSD14_CO_ILIMIT                                              
P  NNAMEm0506 P3V3_SSD8_PG_G1                                                   
P  NNAMEm0507 P3V3_SSD12_CO_EN                                                  
P  NNAMEm0508 P3V3_SSD8_CO_DV_DT                                                
P  NNAMEm0509 P3V3_SSD13_PG_G1                                                  
P  NNAMEm0510 P3V3_SSD9_CO_EN                                                   
P  NNAMEm0511 P3V3_SSD14_PG_G1                                                  
P  NNAMEm0512 P3V3_SSD12_PG_G1                                                  
P  NNAMEm0513 P3V3_SSD5_PG_G1                                                   
P  NNAMEm0514 P3V3_SSD10_CO_DV_DT                                               
P  NNAMEm0515 P3V3_SSD15_CO_EN                                                  
P  NNAMEm0516 P3V3_SSD4_CO_ILIMIT                                               
P  NNAMEm0517 P3V3_SSD8_CO_GATE                                                 
P  NNAMEm0518 P3V3_SSD12_CO_DV_DT                                               
P  NNAMEm0519 P3V3_SSD6_CO_EN                                                   
P  NNAMEm0520 P3V3_SSD10_PG_G1                                                  
P  NNAMEm0521 P3V3_SSD13_CO_DV_DT                                               
P  NNAMEm0522 P3V3_SSD5_PG_G2                                                   
P  NNAMEm0523 P3V3_SSD12_CO_MODE                                                
P  NNAMEm0524 P3V3_SSD5_CO_MODE                                                 
P  NNAMEm0525 P3V3_SSD11_CO_EN                                                  
P  NNAMEm0526 P3V3_SSD12_PG_G2                                                  
P  NNAMEm0527 P3V3_SSD7_CO_MODE                                                 
P  NNAMEm0528 P3V3_SSD8_CO_EN                                                   
P  NNAMEm0529 P3V3_SSD13_PG_G2                                                  
P  NNAMEm0530 P3V3_SSD6_CO_ILIMIT                                               
P  NNAMEm0531 P3V3_SSD11_PG_G1                                                  
P  NNAMEm0532 P3V3_SSD15_PG_G1                                                  
P  NNAMEm0533 P3V3_SSD4_PG_G1                                                   
P  NNAMEm0534 P3V3_SSD11_CO_DV_DT                                               
P  NNAMEm0535 P3V3_SSD6_PG_G1                                                   
P  NNAMEm0536 P3V3_SSD9_CO_GATE                                                 
P  NNAMEm0537 P3V3_SSD15_CO_GATE                                                
P  NNAMEm0538 P3V3_SSD7_CO_EN                                                   
P  NNAMEm0539 P3V3_SSD10_CO_MODE                                                
P  NNAMEm0540 P3V3_SSD14_CO_GATE                                                
P  NNAMEm0541 P3V3_SSD12_CO_GATE                                                
P  NNAMEm0542 P3V3_SSD8_PG_G2                                                   
P  NNAMEm0543 P3V3_SSD15_PG_G2                                                  
P  NNAMEm0544 P3V3_SSD4_CO_GATE                                                 
P  NNAMEm0545 P3V3_SSD11_CO_GATE                                                
P  NNAMEm0546 P3V3_SSD14_CO_EN                                                  
P  NNAMEm0547 P3V3_NIC5_PG_G2                                                   
P  NNAMEm0548 P3V3_SSD5_CO_ILIMIT                                               
P  NNAMEm0549 P3V3_SSD10_CO_GATE                                                
P  NNAMEm0550 P3V3_NIC6_CO_GATE                                                 
P  NNAMEm0551 P3V3_SSD5_CO_EN                                                   
P  NNAMEm0552 P3V3_SSD8_CO_ILIMIT                                               
P  NNAMEm0553 P3V3_SSD13_CO_GATE                                                
P  NNAMEm0554 P3V3_NIC6_CO_DV_DT                                                
P  NNAMEm0555 P3V3_SSD4_CO_EN                                                   
P  NNAMEm0556 P3V3_SSD14_PG_G2                                                  
P  NNAMEm0557 P3V3_SSD7_CO_ILIMIT                                               
P  NNAMEm0558 P3V3_SSD10_PG_G2                                                  
P  NNAMEm0559 P3V3_SSD15_CO_DV_DT                                               
P  NNAMEm0560 P3V3_NIC7_PG_G1                                                   
P  NNAMEm0561 P3V3_SSD6_CO_GATE                                                 
P  NNAMEm0562 P3V3_SSD11_CO_ILIMIT                                              
P  NNAMEm0563 P3V3_SSD12_CO_ILIMIT                                              
P  NNAMEm0564 P3V3_NIC2_CO_EN                                                   
P  NNAMEm0565 P3V3_NIC4_CO_EN                                                   
P  NNAMEm0566 P3V3_SSD10_CO_ILIMIT                                              
P  NNAMEm0567 P3V3_SSD14_CO_DV_DT                                               
P  NNAMEm0568 85_10INCH_BOTTOM_DN                                               
P  NNAMEm0569 P3V3_NIC7_CO_MODE                                                 
P  NNAMEm0570 P3V3_SSD6_CO_DV_DT                                                
P  NNAMEm0571 P3V3_SSD8_CO_MODE                                                 
P  NNAMEm0572 P3V3_SSD13_CO_MODE                                                
P  NNAMEm0573 85_10INCH_IN4_DP                                                  
P  NNAMEm0574 P3V3_SSD4_CO_DV_DT                                                
P  NNAMEm0575 P3V3_SSD9_CO_MODE                                                 
P  NNAMEm0576 85_10INCH_IN5_DN                                                  
P  NNAMEm0577 P3V3_NIC4_CO_GATE                                                 
P  NNAMEm0578 P3V3_SSD5_CO_DV_DT                                                
P  NNAMEm0579 P3V3_SSD9_CO_ILIMIT                                               
P  NNAMEm0580 85_5INCH_BOTTOM_DP                                                
P  NNAMEm0581 P3V3_NIC4_PG_G1                                                   
P  NNAMEm0582 P3V3_SSD7_CO_GATE                                                 
P  NNAMEm0583 P3V3_SSD11_PG_G2                                                  
P  NNAMEm0584 85_10INCH_IN6_DN                                                  
P  NNAMEm0585 P3V3_NIC3_CO_EN                                                   
P  NNAMEm0586 P3V3_NIC5_CO_ILIMIT                                               
P  NNAMEm0587 P3V3_SSD6_PG_G2                                                   
P  NNAMEm0588 P3V3_SSD10_CO_EN                                                  
P  NNAMEm0589 85_10INCH_IN3_DN                                                  
P  NNAMEm0590 P12V_SSD13_PG_G2                                                  
P  NNAMEm0591 P3V3_NIC6_CO_ILIMIT                                               
P  NNAMEm0592 P3V3_SSD4_PG_G2                                                   
P  NNAMEm0593 P3V3_SSD9_PG_G2                                                   
P  NNAMEm0594 85_10INCH_TOP_DP                                                  
P  NNAMEm0595 P12V_SSD14_PG_G2                                                  
P  NNAMEm0596 P3V3_NIC6_CO_EN                                                   
P  NNAMEm0597 P3V3_SSD7_PG_G2                                                   
P  NNAMEm0598 P3V3_SSD9_CO_DV_DT                                                
P  NNAMEm0599 85_10INCH_IN2_DN                                                  
P  NNAMEm0600 P12V_SSD12_CO_MODE                                                
P  NNAMEm0601 P3V3_NIC2_CO_GATE                                                 
P  NNAMEm0602 P3V3_NIC4_CO_MODE                                                 
P  NNAMEm0603 P3V3_SSD6_CO_MODE                                                 
P  NNAMEm0604 85_5INCH_IN6_DN                                                   
P  NNAMEm0605 P12V_SSD13_CO_MODE                                                
P  NNAMEm0606 P3V3_NIC3_CO_ILIMIT                                               
P  NNAMEm0607 P3V3_NIC5_CO_DV_DT                                                
P  NNAMEm0608 P3V3_SSD7_PG_G1                                                   
P  NNAMEm0609 85_10INCH_IN4_DN                                                  
P  NNAMEm0610 P12V_SSD15_PG_G2                                                  
P  NNAMEm0611 P3V3_NIC6_PG_G1                                                   
P  NNAMEm0612 P3V3_SSD4_CO_MODE                                                 
P  NNAMEm0613 85_5INCH_IN6_DP                                                   
P  NNAMEm0614 P12V_SSD12_CO_DV_DT                                               
P  NNAMEm0615 P3V3_NIC7_CO_DV_DT                                                
P  NNAMEm0616 85_5INCH_IN3_DP                                                   
P  NNAMEm0617 P12V_SSD15_CO_DV_DT                                               
P  NNAMEm0618 P3V3_NIC2_CO_MODE                                                 
P  NNAMEm0619 P3V3_NIC5_CO_MODE                                                 
P  NNAMEm0620 P3V3_SSD7_CO_DV_DT                                                
P  NNAMEm0621 P12V_SSD15_CO_EN                                                  
P  NNAMEm0622 P3V3_NIC4_PG_G2                                                   
P  NNAMEm0623 P3V3_SSD5_CO_GATE                                                 
P  NNAMEm0624 85_5INCH_TOP_DP                                                   
P  NNAMEm0625 P3V3_NIC6_PG_G2                                                   
P  NNAMEm0626 85_5INCH_IN5_DN                                                   
P  NNAMEm0627 P12V_SSD12_CO_ILIMIT                                              
P  NNAMEm0628 P3V3_NIC3_PG_G2                                                   
P  NNAMEm0629 P3V3_NIC4_CO_ILIMIT                                               
P  NNAMEm0630 85_5INCH_IN5_DP                                                   
P  NNAMEm0631 P12V_SSD14_CO_ILIMIT                                              
P  NNAMEm0632 P3V3_NIC3_CO_GATE                                                 
P  NNAMEm0633 P3V3_NIC7_CO_EN                                                   
P  NNAMEm0634 85_10INCH_IN6_DP                                                  
P  NNAMEm0635 P3V3_NIC3_CO_DV_DT                                                
P  NNAMEm0636 P3V3_NIC7_CO_ILIMIT                                               
P  NNAMEm0637 85_5INCH_IN4_DP                                                   
P  NNAMEm0638 P12V_SSD12_CO_GATE                                                
P  NNAMEm0639 P3V3_NIC7_PG_G2                                                   
P  NNAMEm0640 85_5INCH_IN4_DN                                                   
P  NNAMEm0641 P12V_SSD12_PG_G2                                                  
P  NNAMEm0642 P3V3_NIC2_CO_DV_DT                                                
P  NNAMEm0643 85_5INCH_TOP_DN                                                   
P  NNAMEm0644 P12V_SSD12_PG_G1                                                  
P  NNAMEm0645 P3V3_NIC3_PG_G1                                                   
P  NNAMEm0646 P3V3_NIC5_CO_EN                                                   
P  NNAMEm0647 85_10INCH_IN2_DP                                                  
P  NNAMEm0648 P12V_SSD15_CO_ILIMIT                                              
P  NNAMEm0649 P3V3_NIC2_PG_G1                                                   
P  NNAMEm0650 P3V3_NIC5_CO_GATE                                                 
P  NNAMEm0651 85_5INCH_IN2_DN                                                   
P  NNAMEm0652 P12V_SSD15_PG_G1                                                  
P  NNAMEm0653 P3V3_NIC6_CO_MODE                                                 
P  NNAMEm0654 85_5INCH_IN1_DP                                                   
P  NNAMEm0655 P12V_SSD13_CO_EN                                                  
P  NNAMEm0656 P3V3_NIC7_CO_GATE                                                 
P  NNAMEm0657 85_10INCH_IN1_DN                                                  
P  NNAMEm0658 P12V_SSD14_CO_GATE                                                
P  NNAMEm0659 P3V3_NIC2_CO_ILIMIT                                               
P  NNAMEm0660 P3V3_NIC5_PG_G1                                                   
P  NNAMEm0661 85_10INCH_TOP_DN                                                  
P  NNAMEm0662 P12V_SSD15_CO_GATE                                                
P  NNAMEm0663 P3V3_NIC3_CO_MODE                                                 
P  NNAMEm0664 P3V3_NIC4_CO_DV_DT                                                
P  NNAMEm0665 85_10INCH_IN1_DP                                                  
P  NNAMEm0666 P12V_SSD13_CO_ILIMIT                                              
P  NNAMEm0667 85_10INCH_BOTTOM_DP                                               
P  NNAMEm0668 P12V_SSD13_PG_G1                                                  
P  NNAMEm0669 85_5INCH_BOTTOM_DN                                                
P  NNAMEm0670 P12V_SSD12_CO_EN                                                  
P  NNAMEm0671 P3V3_NIC2_PG_G2                                                   
P  NNAMEm0672 85_5INCH_IN1_DN                                                   
P  NNAMEm0673 85_5INCH_IN3_DN                                                   
P  NNAMEm0674 P12V_SSD14_PG_G1                                                  
P  NNAMEm0675 85_10INCH_IN5_DP                                                  
P  NNAMEm0676 85_10INCH_IN3_DP                                                  
P  NNAMEm0677 P12V_SSD15_CO_MODE                                                
P  NNAMEm0678 85_5INCH_IN2_DP                                                   
P  NNAMEm0679 P12V_SSD13_CO_GATE                                                
P  NNAMEm0680 P12V_SSD14_CO_DV_DT                                               
P  NNAMEm0681 P12V_SSD13_CO_DV_DT                                               
P  NNAMEm0682 P12V_SSD8_CO_EN                                                   
P  NNAMEm0683 P12V_SSD14_CO_EN                                                  
P  NNAMEm0684 P12V_SSD14_CO_MODE                                                
P  NNAMEm0685 P12V_SSD11_CO_EN                                                  
P  NNAMEm0686 P12V_SSD9_PG_G1                                                   
P  NNAMEm0687 P12V_SSD9_CO_MODE                                                 
P  NNAMEm0688 P12V_SSD9_CO_EN                                                   
P  NNAMEm0689 P12V_SSD10_CO_GATE                                                
P  NNAMEm0690 P12V_SSD10_CO_DV_DT                                               
P  NNAMEm0691 P12V_SSD8_PG_G1                                                   
P  NNAMEm0692 P12V_SSD10_PG_G2                                                  
P  NNAMEm0693 P12V_SSD9_PG_G2                                                   
P  NNAMEm0694 P12V_SSD9_CO_DV_DT                                                
P  NNAMEm0695 P12V_SSD11_CO_GATE                                                
P  NNAMEm0696 P12V_SSD8_PG_G2                                                   
P  NNAMEm0697 P12V_SSD10_CO_MODE                                                
P  NNAMEm0698 P12V_SSD9_CO_ILIMIT                                               
P  NNAMEm0699 P12V_SSD11_CO_MODE                                                
P  NNAMEm0700 P12V_SSD8_CO_ILIMIT                                               
P  NNAMEm0701 P12V_SSD8_CO_DV_DT                                                
P  NNAMEm0702 P12V_SSD9_CO_GATE                                                 
P  NNAMEm0703 P12V_SSD8_CO_GATE                                                 
P  NNAMEm0704 PWRGD_P3V3_SSD14_D                                                
P  NNAMEm0705 P12V_SSD11_CO_ILIMIT                                              
P  NNAMEm0706 PWRGD_P3V3_SSD13_D                                                
P  NNAMEm0707 P12V_SSD8_CO_MODE                                                 
P  NNAMEm0708 PWRGD_P3V3_SSD12_D                                                
P  NNAMEm0709 P12V_SSD10_PG_G1                                                  
P  NNAMEm0710 PWRGD_P3V3_SSD15_D                                                
P  NNAMEm0711 P12V_SSD11_PG_G2                                                  
P  NNAMEm0712 PWRGD_P3V3_SSD10_D                                                
P  NNAMEm0713 P12V_SSD11_PG_G1                                                  
P  NNAMEm0714 PWRGD_P3V3_SSD8_D                                                 
P  NNAMEm0715 P12V_SSD10_CO_EN                                                  
P  NNAMEm0716 PWRGD_P3V3_SSD9_D                                                 
P  NNAMEm0717 P12V_SSD11_CO_DV_DT                                               
P  NNAMEm0718 PWRGD_P3V3_SSD11_D                                                
P  NNAMEm0719 P12V_SSD5_PG_G2                                                   
P  NNAMEm0720 P12V_SSD10_CO_ILIMIT                                              
P  NNAMEm0721 PWRGD_P3V3_SSD5_D                                                 
P  NNAMEm0722 P12V_SSD5_CO_MODE                                                 
P  NNAMEm0723 PWRGD_P3V3_SSD6_D                                                 
P  NNAMEm0724 PWRGD_P3V3_SSD4_D                                                 
P  NNAMEm0725 P12V_SSD4_CO_EN                                                   
P  NNAMEm0726 PWRGD_P3V3_SSD7_D                                                 
P  NNAMEm0727 P12V_SSD6_CO_EN                                                   
P  NNAMEm0728 P12V_SSD4_PG_G1                                                   
P  NNAMEm0729 P12V_SSD5_CO_GATE                                                 
P  NNAMEm0730 P12V_SSD7_CO_ILIMIT                                               
P  NNAMEm0731 P12V_SSD5_CO_DV_DT                                                
P  NNAMEm0732 PWRGD_P3V3_NIC6_D                                                 
P  NNAMEm0733 PWRGD_P3V3_NIC5_D                                                 
P  NNAMEm0734 P12V_SSD7_CO_DV_DT                                                
P  NNAMEm0735 PWRGD_P3V3_NIC7_D                                                 
P  NNAMEm0736 P12V_SSD4_CO_GATE                                                 
P  NNAMEm0737 PWRGD_P3V3_NIC4_D                                                 
P  NNAMEm0738 P12V_SSD6_CO_DV_DT                                                
P  NNAMEm0739 PWRGD_P3V3_NIC0_D                                                 
P  NNAMEm0740 P12V_SSD5_PG_G1                                                   
P  NNAMEm0741 PWRGD_P3V3_NIC2_D                                                 
P  NNAMEm0742 P12V_SSD7_PG_G2                                                   
P  NNAMEm0743 PWRGD_P3V3_NIC1_D                                                 
P  NNAMEm0744 P12V_SSD5_CO_EN                                                   
P  NNAMEm0745 PWRGD_P3V3_NIC3_D                                                 
P  NNAMEm0746 P12V_SSD6_CO_MODE                                                 
P  NNAMEm0747 PWRGD_P12V_SSD12_D                                                
P  NNAMEm0748 P12V_SSD4_CO_ILIMIT                                               
P  NNAMEm0749 PWRGD_P12V_SSD13_D                                                
P  NNAMEm0750 P12V_SSD7_CO_GATE                                                 
P  NNAMEm0751 PWRGD_P12V_SSD14_D                                                
P  NNAMEm0752 P12V_SSD4_CO_MODE                                                 
P  NNAMEm0753 PWRGD_P12V_SSD15_D                                                
P  NNAMEm0754 P12V_SSD7_PG_G1                                                   
P  NNAMEm0755 PWRGD_P12V_SSD9_D                                                 
P  NNAMEm0756 PWRGD_P12V_SSD8_D                                                 
P  NNAMEm0757 P12V_SSD7_CO_MODE                                                 
P  NNAMEm0758 PWRGD_P12V_SSD11_D                                                
P  NNAMEm0759 P12V_SSD7_CO_EN                                                   
P  NNAMEm0760 PWRGD_P12V_SSD10_D                                                
P  NNAMEm0761 P12V_SSD6_CO_GATE                                                 
P  NNAMEm0762 PWRGD_P12V_SSD4_D                                                 
P  NNAMEm0763 P12V_SSD6_CO_ILIMIT                                               
P  NNAMEm0764 PWRGD_P12V_SSD5_D                                                 
P  NNAMEm0765 P12V_SSD6_PG_G2                                                   
P  NNAMEm0766 PWRGD_P12V_SSD6_D                                                 
P  NNAMEm0767 P12V_SSD5_CO_ILIMIT                                               
P  NNAMEm0768 PWRGD_P12V_SSD7_D                                                 
P  NNAMEm0769 P12V_SSD4_PG_G2                                                   
P  NNAMEm0770 P12V_SSD6_PG_G1                                                   
P  NNAMEm0771 P12V_SSD4_CO_DV_DT                                                
P  NNAMEm0772 SPI_PEX2_SDIO2_R                                                  
P  NNAMEm0773 SPI_PEX2_SDIO3_R                                                  
P  NNAMEm0774 SPI_PEX2_CS_R_N                                                   
P  NNAMEm0775 SPI_PEX2_SDIO1_R                                                  
P  NNAMEm0776 SPI_PEX2_SDIO0_R                                                  
P  NNAMEm0777 JP_FPGA_DEBUG_N                                                   
P  NNAMEm0778 FM_SYS_THROTTLE_R1                                                
P  NNAMEm0779 RST_SMB_NIC1_MUX_ISO_R_N                                          
P  NNAMEm0780 PWRGD_P12V_SSD2_D                                                 
P  NNAMEm0781 P12V_SSD3_CO_ILIMIT                                               
P  NNAMEm0782 P12V_SSD0_CO_EN                                                   
P  NNAMEm0783 P12V_SSD2_CO_EN                                                   
P  NNAMEm0784 P12V_SSD2_PG_G2                                                   
P  NNAMEm0785 P12V_SSD1_CO_EN                                                   
P  NNAMEm0786 USB_DEBUG_RST_BTN_R_N                                             
P  NNAMEm0787 P12V_SSD0_PG_G2                                                   
P  NNAMEm0788 PWRGD_P12V_SSD1_D                                                 
P  NNAMEm0789 P12V_SSD3_CO_MODE                                                 
P  NNAMEm0790 P12V_SSD2_PG_G1                                                   
P  NNAMEm0791 P12V_SSD1_CO_GATE                                                 
P  NNAMEm0792 P12V_SSD1_PG_G2                                                   
P  NNAMEm0793 P12V_SSD3_CO_DV_DT                                                
P  NNAMEm0794 P12V_SSD3_CO_GATE                                                 
P  NNAMEm0795 P12V_SSD3_PG_G2                                                   
P  NNAMEm0796 P12V_SSD0_CO_MODE                                                 
P  NNAMEm0797 P12V_SSD2_CO_ILIMIT                                               
P  NNAMEm0798 P12V_SSD2_CO_MODE                                                 
P  NNAMEm0799 P12V_SSD0_PG_G1                                                   
P  NNAMEm0800 PWRGD_P12V_SSD3_D                                                 
P  NNAMEm0801 P12V_SSD0_CO_ILIMIT                                               
P  NNAMEm0802 P12V_SSD2_CO_DV_DT                                                
P  NNAMEm0803 P12V_SSD0_CO_DV_DT                                                
P  NNAMEm0804 P12V_SSD1_CO_MODE                                                 
P  NNAMEm0805 P12V_SSD1_CO_DV_DT                                                
P  NNAMEm0806 P12V_SSD1_CO_ILIMIT                                               
P  NNAMEm0807 P12V_SSD3_CO_EN                                                   
P  NNAMEm0808 P12V_SSD3_PG_G1                                                   
P  NNAMEm0809 PWRGD_P12V_SSD0_D                                                 
P  NNAMEm0810 PEX3_SYS_ERR_FPGA                                                 
P  NNAMEm0811 P12V_SSD1_PG_G1                                                   
P  NNAMEm0812 P12V_NIC0_CO_FLTB                                                 
P  NNAMEm0813 P12V_SSD0_CO_GATE                                                 
P  NNAMEm0814 PEX2_SYS_ERR_FPGA                                                 
P  NNAMEm0815 P12V_NIC1_CO_AVIN_PD                                              
P  NNAMEm0816 P12V_SSD2_CO_GATE                                                 
P  NNAMEm0817 P12V_NIC3_CO_OV_FB                                                
P  NNAMEm0818 P12V_NIC2_CO_ISET                                                 
P  NNAMEm0819 P12V_NIC1_CO_SS                                                   
P  NNAMEm0820 P12V_NIC2_CO_OV_FB                                                
P  NNAMEm0821 P12V_NIC0_CO_ISET_R                                               
P  NNAMEm0822 P12V_NIC2_CO_IMON_VR                                              
P  NNAMEm0823 P12V_NIC0_CO_AVIN_PD                                              
P  NNAMEm0824 P12V_NIC3_CO_IMON_VR                                              
P  NNAMEm0825 P12V_NIC2_CO_SS                                                   
P  NNAMEm0826 P12V_NIC2_CO_AVIN_PD                                              
P  NNAMEm0827 P12V_NIC2_CO_ISET_R                                               
P  NNAMEm0828 P12V_NIC3_CO_TIMER                                                
P  NNAMEm0829 PWRGD_P12V_NIC0_CO                                                
P  NNAMEm0830 P12V_NIC3_CO_SS                                                   
P  NNAMEm0831 PEX1_SYS_ERR_FPGA                                                 
P  NNAMEm0832 P12V_NIC3_CO_ISET_R                                               
P  NNAMEm0833 P12V_NIC1_CO_ISET                                                 
P  NNAMEm0834 P12V_NIC0_CO_ISET                                                 
P  NNAMEm0835 P12V_NIC1_CO_EN                                                   
P  NNAMEm0836 P12V_NIC1_CO_OV_FB                                                
P  NNAMEm0837 P12V_NIC1_CO_TIMER                                                
P  NNAMEm0838 P12V_NIC1_CO_IMON_VR                                              
P  NNAMEm0839 P12V_NIC0_CO_EN                                                   
P  NNAMEm0840 SW_P12V_P0V8_PEX3_FLT                                             
P  NNAMEm0841 P12V_NIC2_CO_TIMER                                                
P  NNAMEm0842 PWRGD_P12V_NIC1_CO                                                
P  NNAMEm0843 P12V_NIC3_CO_FLTB                                                 
P  NNAMEm0844 P12V_NIC2_CO_EN                                                   
P  NNAMEm0845 P12V_NIC3_CO_AVIN_PD                                              
P  NNAMEm0846 PWRGD_P12V_NIC3_CO                                                
P  NNAMEm0847 P12V_NIC0_CO_SS                                                   
P  NNAMEm0848 PWRGD_P12V_NIC2_CO                                                
P  NNAMEm0849 P12V_NIC1_CO_ISET_R                                               
P  NNAMEm0850 P12V_NIC3_CO_EN                                                   
P  NNAMEm0851 P12V_NIC3_CO_ISET                                                 
P  NNAMEm0852 P12V_NIC0_CO_OV_FB                                                
P  NNAMEm0853 P12V_NIC1_CO_FLTB                                                 
P  NNAMEm0854 P12V_NIC0_CO_IMON_VR                                              
P  NNAMEm0855 P12V_NIC2_CO_FLTB                                                 
P  NNAMEm0856 P12V_NIC0_CO_TIMER                                                
P  NNAMEm0857 P3V3_SSD3_CO_EN                                                   
P  NNAMEm0858 P3V3_SSD3_PG_G1                                                   
P  NNAMEm0859 P3V3_SSD3_CO_MODE                                                 
P  NNAMEm0860 P3V3_SSD2_CO_EN                                                   
P  NNAMEm0861 P3V3_SSD0_CO_GATE                                                 
P  NNAMEm0862 P3V3_SSD3_CO_DV_DT                                                
P  NNAMEm0863 P3V3_NIC1_PG_G1                                                   
P  NNAMEm0864 P3V3_SSD2_CO_ILIMIT                                               
P  NNAMEm0865 P3V3_SSD2_CO_DV_DT                                                
P  NNAMEm0866 P3V3_NIC1_CO_GATE                                                 
P  NNAMEm0867 P3V3_SSD1_CO_DV_DT                                                
P  NNAMEm0868 P3V3_NIC0_CO_ILIMIT                                               
P  NNAMEm0869 P3V3_SSD0_CO_MODE                                                 
P  NNAMEm0870 P3V3_NIC0_CO_MODE                                                 
P  NNAMEm0871 P3V3_SSD0_PG_G1                                                   
P  NNAMEm0872 P3V3_NIC1_CO_MODE                                                 
P  NNAMEm0873 P3V3_SSD2_PG_G2                                                   
P  NNAMEm0874 P3V3_NIC1_PG_G2                                                   
P  NNAMEm0875 P3V3_SSD2_PG_G1                                                   
P  NNAMEm0876 P3V3_NIC1_CO_DV_DT                                                
P  NNAMEm0877 P3V3_SSD1_CO_ILIMIT                                               
P  NNAMEm0878 P3V3_NIC0_CO_EN                                                   
P  NNAMEm0879 P3V3_SSD3_CO_GATE                                                 
P  NNAMEm0880 P3V3_NIC0_PG_G1                                                   
P  NNAMEm0881 P3V3_SSD1_CO_EN                                                   
P  NNAMEm0882 P3V3_NIC0_CO_DV_DT                                                
P  NNAMEm0883 P3V3_SSD3_CO_ILIMIT                                               
P  NNAMEm0884 P3V3_NIC1_CO_ILIMIT                                               
P  NNAMEm0885 P3V3_SSD1_CO_GATE                                                 
P  NNAMEm0886 P3V3_NIC1_CO_EN                                                   
P  NNAMEm0887 P3V3_SSD1_CO_MODE                                                 
P  NNAMEm0888 P3V3_SSD0_CO_EN                                                   
P  NNAMEm0889 P3V3_NIC0_CO_GATE                                                 
P  NNAMEm0890 PWRGD_P3V3_SSD0_D                                                 
P  NNAMEm0891 P3V3_NIC0_PG_G2                                                   
P  NNAMEm0892 PWRGD_P3V3_SSD2_D                                                 
P  NNAMEm0893 P3V3_SSD0_CO_DV_DT                                                
P  NNAMEm0894 P3V3_SSD0_CO_ILIMIT                                               
P  NNAMEm0895 P3V3_SSD1_PG_G2                                                   
P  NNAMEm0896 P3V3_SSD2_CO_GATE                                                 
P  NNAMEm0897 P3V3_SSD2_CO_MODE                                                 
P  NNAMEm0898 P3V3_SSD1_PG_G1                                                   
P  NNAMEm0899 P3V3_SSD3_PG_G2                                                   
P  NNAMEm0900 P3V3_SSD0_PG_G2                                                   
P  NNAMEm0901 PWRGD_P3V3_SSD3_D                                                 
P  NNAMEm0902 PWRGD_P3V3_SSD1_D                                                 
P  NNAMEm0903 SPI_PEX2_CS_MUX_N                                                 
P  NNAMEm0904 SPI_PEX2_SDIO0_MUX                                                
P  NNAMEm0905 SPI_PEX2_CLK_MUX                                                  
P  NNAMEm0906 HSC_D_OC_BUF_R_N                                                  
P  NNAMEm0907 RST_SMB_SSD6_ISO_N                                                
P  NNAMEm0908 IRQ_SSD_LED_IOEXP_R_N                                             
P  NNAMEm0909 RST_SMB_SSD5_ISO_R_N                                              
P  NNAMEm0910 RST_SMB_SSD12_ISO_R_N                                             
P  NNAMEm0911 RST_SMB_SSD14_ISO_R_N                                             
P  NNAMEm0912 RST_SMB_SSD5_ISO_N                                                
P  NNAMEm0913 RST_SMB_SSD8_ISO_R_N                                              
P  NNAMEm0914 RST_SMB_SSD9_ISO_R_N                                              
P  NNAMEm0915 IRQ_SSD_LED_IOEXP_N                                               
P  NNAMEm0916 RST_SMB_SSD4_ISO_R_N                                              
P  NNAMEm0917 RST_SMB_SSD13_ISO_R_N                                             
P  NNAMEm0918 RST_SMB_SSD11_ISO_R_N                                             
P  NNAMEm0919 RST_SMB_SSD4_ISO_N                                                
P  NNAMEm0920 RST_SMB_SSD10_ISO_R_N                                             
P  NNAMEm0921 RST_SMB_SSD15_ISO_R_N                                             
P  NNAMEm0922 RST_SMB_SSD3_ISO_R_N                                              
P  NNAMEm0923 JTAG_BIC_TCK_R1                                                   
P  NNAMEm0924 JTAG_BIC_TMS_R1                                                   
P  NNAMEm0925 RST_SMB_SSD3_ISO_N                                                
P  NNAMEm0926 JTAG_BIC_TDI_R1                                                   
P  NNAMEm0927 RST_SMB_SSD2_ISO_R_N                                              
P  NNAMEm0928 RST_SMB_SSD2_ISO_N                                                
P  NNAMEm0929 RST_FW_BIC_PLTRST_N                                               
P  NNAMEm0930 RST_SMB_SSD1_ISO_R_N                                              
P  NNAMEm0931 RST_SMB_SSD13_ISO_N                                               
P  NNAMEm0932 RST_SMB_SSD14_N                                                   
P  NNAMEm0933 RST_SMB_SSD1_ISO_N                                                
P  NNAMEm0934 RST_SMB_SSD11_ISO_N                                               
P  NNAMEm0935 RST_SMB_SSD12_ISO_N                                               
P  NNAMEm0936 RST_SMB_SSD0_ISO_R_N                                              
P  NNAMEm0937 RST_SMB_SSD13_N                                                   
P  NNAMEm0938 RST_SMB_SSD9_ISO_N                                                
P  NNAMEm0939 RST_SMB_SSD0_ISO_N                                                
P  NNAMEm0940 RST_SMB_SSD10_N                                                   
P  NNAMEm0941 RST_SMB_SSD15_N                                                   
P  NNAMEm0942 RST_SMB_SSD12_N                                                   
P  NNAMEm0943 RST_SMB_SSD14_ISO_N                                               
P  NNAMEm0944 RST_SMB_SSD11_N                                                   
P  NNAMEm0945 RST_SMB_SSD10_ISO_N                                               
P  NNAMEm0946 RST_SMB_SSD8_ISO_N                                                
P  NNAMEm0947 P3V3_FPGA_VCCIO5                                                  
P  NNAMEm0948 P3V3_FPGA_VCCIO4                                                  
P  NNAMEm0949 P3V3_FPGA_VCCIO3                                                  
P  NNAMEm0950 PWRGD_P1V2_AUX_FPGA_R                                             
P  NNAMEm0951 P3V3_FPGA_VCCIO2                                                  
P  NNAMEm0952 SSD5_LED_ISO_R_N                                                  
P  NNAMEm0953 P3V3_FPGA_VCCIO1                                                  
P  NNAMEm0954 PWRGD_P1V2_AUX_FPGA                                               
P  NNAMEm0955 P3V3_FPGA_VCCIO0                                                  
P  NNAMEm0956 SSD4_LED_ISO_R_N                                                  
P  NNAMEm0957 P3V3_VCC_FPGA_CORE                                                
P  NNAMEm0958 SSD3_LED_ISO_R_N                                                  
P  NNAMEm0959 RST_SMB_SSD7_ISO_N                                                
P  NNAMEm0960 SSD2_LED_ISO_R_N                                                  
P  NNAMEm0961 RST_SMB_SSD15_ISO_N                                               
P  NNAMEm0962 RST_PEX_NIC7_PERST_N                                              
P  NNAMEm0963 NIC7_PEX_PWR_EN                                                   
P  NNAMEm0964 RST_PEX_NIC4_PERST_N                                              
P  NNAMEm0965 NIC4_PEX_PWR_EN                                                   
P  NNAMEm0966 SSD1_LED_ISO_R_N                                                  
P  NNAMEm0967 RST_PEX_NIC3_PERST_N                                              
P  NNAMEm0968 NIC3_PEX_PWR_EN                                                   
P  NNAMEm0969 RST_PEX_NIC2_PERST_N                                              
P  NNAMEm0970 SSD0_LED_ISO_R_N                                                  
P  NNAMEm0971 NIC2_PEX_PWR_EN                                                   
P  NNAMEm0972 RST_GPU_PERST_2_R_N                                               
P  NNAMEm0973 RST_PEX_NIC0_PERST_N                                              
P  NNAMEm0974 NIC0_PEX_PWR_EN                                                   
P  NNAMEm0975 RST_PEX_NIC1_PERST_N                                              
P  NNAMEm0976 NIC1_PEX_PWR_EN                                                   
P  NNAMEm0977 SSD15_LED_ISO_N                                                   
P  NNAMEm0978 SSD14_LED_ISO_N                                                   
P  NNAMEm0979 PEX_ADC_ALERT_N                                                   
P  NNAMEm0980 SSD15_LED_ISO_R_N                                                 
P  NNAMEm0981 SSD14_LED_ISO_R_N                                                 
P  NNAMEm0982 SSD12_LED_ISO_R_N                                                 
P  NNAMEm0983 NIC_ADC_ALERT_N                                                   
P  NNAMEm0984 SSD13_LED_ISO_R_N                                                 
P  NNAMEm0985 SSD_8_15_ADC_ALERT_N                                              
P  NNAMEm0986 SSD13_LED_ISO_N                                                   
P  NNAMEm0987 SSD12_LED_ISO_N                                                   
P  NNAMEm0988 SSD_0_7_ADC_ALERT_N                                               
P  NNAMEm0989 SSD10_LED_ISO_N                                                   
P  NNAMEm0990 FM_PFR_LED_BLUE_R                                                 
P  NNAMEm0991 SSD11_LED_ISO_N                                                   
P  NNAMEm0992 SSD11_LED_ISO_R_N                                                 
P  NNAMEm0993 SSD10_LED_ISO_R_N                                                 
P  NNAMEm0994 FM_PFR_LED_AMBER_R                                                
P  NNAMEm0995 SSD8_LED_ISO_R_N                                                  
P  NNAMEm0996 SSD9_LED_ISO_R_N                                                  
P  NNAMEm0997 SSD7_LED_ISO_R_N                                                  
P  NNAMEm0998 PU_FPGA_PROGRAMN                                                  
P  NNAMEm0999 SSD6_LED_ISO_R_N                                                  
P  NNAMEm1000 RST_SMB_NIC0_MUX_ISO_R_N                                          
P  NNAMEm1001 RST_SMB_NIC_MUX_R_N                                               
P  NNAMEm1002 SMB_MB_BMC_ISO_FPGA_SDA                                           
P  NNAMEm1003 SMB_MB_BMC_ISO_FPGA_SCL                                           
P  NNAMEm1004 MB_HSC_ISO_D2_EN                                                  
P  NNAMEm1005 PEX0_SYS_ERR_FPGA                                                 
P  NNAMEm1006 RST_BIC_I2C6_MUX_N                                                
P  NNAMEm1007 RST_BIC_I2C9_SSD_MUX1_N                                           
P  NNAMEm1008 RST_BIC_I2C9_SSD_MUX0_N                                           
P  NNAMEm1009 BIC_UART_BIC_SEL                                                  
P  NNAMEm1010 BIC_FORCE_THROTTLE_R_N                                            
P  NNAMEm1011 SMB_ALERT_HSC_N                                                   
P  NNAMEm1012 RST_SSD_LED_IOEXP_R_N                                             
P  NNAMEm1013 RST_SMB_SSD7_ISO_R_N                                              
P  NNAMEm1014 RST_SSD_LED_IOEXP_N                                               
P  NNAMEm1015 RST_SMB_SSD6_ISO_R_N                                              
P  NNAMEm1016 SSD10_PEX_PWR_EN_R                                                
P  NNAMEm1017 PRSNT_SSD2_FPGA_PCA9555_N                                         
P  NNAMEm1018 P3V3_CLK_GEN_VDDXTAL_CK440_PEX                                    
P  NNAMEm1019 PRSNT_NIC0_FPGA_PCA9555_N                                         
P  NNAMEm1020 PRSNT_NIC0_FPGA_R_N                                               
P  NNAMEm1021 P3V3_CLK_GEN_VDDPT_CK440_PEX                                      
P  NNAMEm1022 PRSNT_SSD1_FPGA_PCA9555_N                                         
P  NNAMEm1023 P3V3_CLK_GEN_VDDA25M_CK440_PEX                                    
P  NNAMEm1024 RST_BIC_BUF_RSMRST_N_BUF                                          
P  NNAMEm1025 RST_BIC_SRST_BIC_N                                                
P  NNAMEm1026 PRSNT_SSD0_FPGA_PCA9555_N                                         
P  NNAMEm1027 NIC7_CLK_EN_R_N                                                   
P  NNAMEm1028 PEX2_EXT_GPIO_LATCH_N                                             
P  NNAMEm1029 RST_BIC_SRST_R_N                                                  
P  NNAMEm1030 RST_BIC_BUF_RSMRST_N                                              
P  NNAMEm1031 RST_PEX_SSD11_PERST_R_N                                           
P  NNAMEm1032 RST_NIC7_PERST_R_N                                                
P  NNAMEm1033 PRSNT_SSD15_FPGA_PCA9555_N                                        
P  NNAMEm1034 P0V8_PEX0_SMBALERT                                                
P  NNAMEm1035 PRSNT_SSD14_FPGA_PCA9555_N                                        
P  NNAMEm1036 SSD8_PEX_PWR_EN_R                                                 
P  NNAMEm1037 PEX0_EXT_GPIO_LATCH_N                                             
P  NNAMEm1038 SSD15_PWRDIS_BIC_R                                                
P  NNAMEm1039 PCEPLL2_VDDA18_PEX3_R                                             
P  NNAMEm1040 PCEPLL5_VDDA18_PEX3_R                                             
P  NNAMEm1041 PCEPLL6_VDDA18_PEX3_R                                             
P  NNAMEm1042 NIC6_CLK_EN_R_N                                                   
P  NNAMEm1043 PCEPLL4_VDDA18_PEX3_R                                             
P  NNAMEm1044 SEL_FLASH_PEX3_BUF                                                
P  NNAMEm1045 RST_NIC6_PERST_R_N                                                
P  NNAMEm1046 NIC7_PWRBRK_R_N                                                   
P  NNAMEm1047 SEL_FLASH_PEX2_BUF                                                
P  NNAMEm1048 SYSPLL_VDDA18_PEX3_R                                              
P  NNAMEm1049 RST_PEX_SSD5_PERST_N                                              
P  NNAMEm1050 SEL_FLASH_PEX1_BUF                                                
P  NNAMEm1051 PCEPLL1_VDDA18_PEX3_R                                             
P  NNAMEm1052 PU_CLK_25M_FPGA_EN                                                
P  NNAMEm1053 SEL_FLASH_PEX0_BUF                                                
P  NNAMEm1054 P1V8_VDDA_PEX3_R                                                  
P  NNAMEm1055 SSD5_PEX_PWR_EN                                                   
P  NNAMEm1056 PCEPLL0_VDDA18_PEX3_R                                             
P  NNAMEm1057 PCEPLL7_VDDA18_PEX3_R                                             
P  NNAMEm1058 PEX1_EXT_GPIO_LATCH_N                                             
P  NNAMEm1059 PCEPLL3_VDDA18_PEX3_R                                             
P  NNAMEm1060 NIC0_PWRBRK_R_N                                                   
P  NNAMEm1061 PRSNT_SSD7_FPGA_N                                                 
P  NNAMEm1062 PCEPLL7_VDDA18_PEX3                                               
P  NNAMEm1063 PCEPLL4_VDDA18_PEX3                                               
P  NNAMEm1064 PCEPLL3_VDDA18_PEX3                                               
P  NNAMEm1065 PCEPLL1_VDDA18_PEX3                                               
P  NNAMEm1066 RST_BIC_EXTRST_N                                                  
P  NNAMEm1067 PCEPLL0_VDDA18_PEX3                                               
P  NNAMEm1068 PWRGD_P1V2_AUX_DLY                                                
P  NNAMEm1069 RST_PEX0_S0_PERST_R_N                                             
P  NNAMEm1070 PCEPLL6_VDDA18_PEX3                                               
P  NNAMEm1071 RST_PEX0_S1_PERST_R_N                                             
P  NNAMEm1072 PCEPLL5_VDDA18_PEX3                                               
P  NNAMEm1073 SYSPLL_VDDA18_PEX3                                                
P  NNAMEm1074 PCEPLL2_VDDA18_PEX3                                               
P  NNAMEm1075 PCEPLL0_VDDA18_PEX2_R                                             
P  NNAMEm1076 I2C_PEX0_HOST_R_SCL                                               
P  NNAMEm1077 RST_PEX3_PERST_N                                                  
P  NNAMEm1078 SYSPLL_VDDA18_PEX2_R                                              
P  NNAMEm1079 RST_PEX_SSD6_PERST_N                                              
P  NNAMEm1080 PCEPLL1_VDDA18_PEX2_R                                             
P  NNAMEm1081 I2C_PEX0_HOST_R_SDA                                               
P  NNAMEm1082 RST_PEX0_PERST_N                                                  
P  NNAMEm1083 PCEPLL3_VDDA18_PEX2_R                                             
P  NNAMEm1084 SSD6_PEX_PWR_EN                                                   
P  NNAMEm1085 RST_BIC_USB_HUB_N                                                 
P  NNAMEm1086 P1V8_VDDA_PEX2_R                                                  
P  NNAMEm1087 I2C_PEX0_HOST_SCL                                                 
P  NNAMEm1088 NIC1_MAIN_PWR_BIC_EN_R                                            
P  NNAMEm1089 IRQ_PEX3_CLKREQ_INT_N                                             
P  NNAMEm1090 RST_PEX_USB_HUB_N                                                 
P  NNAMEm1091 I2C_PEX0_HOST_SDA                                                 
P  NNAMEm1092 RST_PEX_SSD4_PERST_N                                              
P  NNAMEm1093 RST_BIC_EXTRST_R_N                                                
P  NNAMEm1094 PCEPLL6_VDDA18_PEX2_R                                             
P  NNAMEm1095 NIC0_MAIN_PWR_BIC_EN_R                                            
P  NNAMEm1096 PCEPLL7_VDDA18_PEX2_R                                             
P  NNAMEm1097 RST_PEX_SSD0_PERST_N                                              
P  NNAMEm1098 RST_PEX_USB_HUB_R_N                                               
P  NNAMEm1099 PCEPLL2_VDDA18_PEX2_R                                             
P  NNAMEm1100 RST_PEX2_PERST_N                                                  
P  NNAMEm1101 PCEPLL5_VDDA18_PEX2_R                                             
P  NNAMEm1102 SSD0_PEX_PWR_EN                                                   
P  NNAMEm1103 SSD4_PEX_PWR_EN                                                   
P  NNAMEm1104 NIC2_PWRBRK_R_N                                                   
P  NNAMEm1105 IRQ_PEX2_CLKREQ_INT_N                                             
P  NNAMEm1106 PCEPLL4_VDDA18_PEX2_R                                             
P  NNAMEm1107 PEX0_PCA9555_INT_R_N                                              
P  NNAMEm1108 PCEPLL5_VDDA18_PEX2                                               
P  NNAMEm1109 RST_PEX1_PERST_N                                                  
P  NNAMEm1110 PCEPLL2_VDDA18_PEX2                                               
P  NNAMEm1111 I2C0_PEX0_SHPC_SCL                                                
P  NNAMEm1112 PCEPLL7_VDDA18_PEX2                                               
P  NNAMEm1113 I2C0_PEX0_SHPC_SDA                                                
P  NNAMEm1114 PCEPLL0_VDDA18_PEX2                                               
P  NNAMEm1115 SSD_LED_IOEXP_A0                                                  
P  NNAMEm1116 IRQ_PEX1_CLKREQ_INT_N                                             
P  NNAMEm1117 USB2_GPU_HMC_R_DN                                                 
P  NNAMEm1118 UART_BIC_DEBUG_TX                                                 
P  NNAMEm1119 SMB_SSD_LED_IOEXP_SCL                                             
P  NNAMEm1120 USB2_GPU_HMC_R_DP                                                 
P  NNAMEm1121 PCEPLL4_VDDA18_PEX2                                               
P  NNAMEm1122 NIC5_CLK_EN_R_N                                                   
P  NNAMEm1123 SMB_SSD_LED_IOEXP_SDA                                             
P  NNAMEm1124 PCEPLL6_VDDA18_PEX2                                               
P  NNAMEm1125 PCEPLL1_VDDA18_PEX2                                               
P  NNAMEm1126 RST_NIC5_PERST_R_N                                                
P  NNAMEm1127 JTAG_BIC_TDO_R1                                                   
P  NNAMEm1128 PEX0_PCA9555_1_INT_N                                              
P  NNAMEm1129 RST_PEX_SSD7_PERST_R_N                                            
P  NNAMEm1130 IRQ_PEX0_CLKREQ_INT_N                                             
P  NNAMEm1131 USB2_MB_BMC_R_DN                                                  
P  NNAMEm1132 PEX0_PCA9555_INT_N                                                
P  NNAMEm1133 FM_SYS_THROTTLE                                                   
P  NNAMEm1134 USB2_MB_BMC_R_DP                                                  
P  NNAMEm1135 SYSPLL_VDDA18_PEX2                                                
P  NNAMEm1136 RST_PEX_SSD3_PERST_N                                              
P  NNAMEm1137 PEX_USB_HUB_PSELF                                                 
P  NNAMEm1138 PCEPLL3_VDDA18_PEX2                                               
P  NNAMEm1139 SSD3_PEX_PWR_EN                                                   
P  NNAMEm1140 SSD15_PEX_PWR_EN                                                  
P  NNAMEm1141 PCEPLL7_VDDA18_PEX0                                               
P  NNAMEm1142 RST_PEX_SSD15_PERST_N                                             
P  NNAMEm1143 BIC_USB_HUB_PSELF                                                 
P  NNAMEm1144 PCEPLL1_VDDA18_PEX0                                               
P  NNAMEm1145 NIC4_CLK_EN_R_N                                                   
P  NNAMEm1146 PU_CLK_25M_BIC_EN                                                 
P  NNAMEm1147 PCEPLL6_VDDA18_PEX0                                               
P  NNAMEm1148 BIC_USB_HUB_OVCUR1                                                
P  NNAMEm1149 PCEPLL5_VDDA18_PEX0_R                                             
P  NNAMEm1150 BIC_USB_HUB_XIN                                                   
P  NNAMEm1151 PCEPLL2_VDDA18_PEX0_R                                             
P  NNAMEm1152 SMB_PEX1_PCA9555_SDA                                              
P  NNAMEm1153 NIC6_PWRBRK_R_N                                                   
P  NNAMEm1154 BIC_USB_HUB_PGANG                                                 
P  NNAMEm1155 SYSPLL_VDDA18_PEX0                                                
P  NNAMEm1156 BIC_USB_HUB_OVCUR4                                                
P  NNAMEm1157 PCEPLL6_VDDA18_PEX0_R                                             
P  NNAMEm1158 SMB_PEX1_PCA9555_SCL                                              
P  NNAMEm1159 BIC_USB_HUB_RREF                                                  
P  NNAMEm1160 PCEPLL3_VDDA18_PEX0                                               
P  NNAMEm1161 BIC_USB_HUB_OVCUR2                                                
P  NNAMEm1162 SYSPLL_VDDA18_PEX0_R                                              
P  NNAMEm1163 SMB_PEX1_HOST_LS_SDA                                              
P  NNAMEm1164 SSD7_PEX_PWR_EN_R                                                 
P  NNAMEm1165 IRQ_IOEXP_DBV2_N                                                  
P  NNAMEm1166 PCEPLL4_VDDA18_PEX0_R                                             
P  NNAMEm1167 SMB_PEX1_HOST_LS_SCL                                              
P  NNAMEm1168 NIC3_CLK_EN_R_N                                                   
P  NNAMEm1169 BIC_USB_HUB_OVCUR3                                                
P  NNAMEm1170 PCEPLL7_VDDA18_PEX0_R                                             
P  NNAMEm1171 I2C0_PEX1_SHPC_SCL                                                
P  NNAMEm1172 BIC_USB_HUB_XOUT                                                  
P  NNAMEm1173 PCEPLL1_VDDA18_PEX0_R                                             
P  NNAMEm1174 I2C0_PEX1_SHPC_SDA                                                
P  NNAMEm1175 BIC_USB_HUB_TEST                                                  
P  NNAMEm1176 PCEPLL0_VDDA18_PEX0_R                                             
P  NNAMEm1177 SMB_PEX1_SLAVE_SCL                                                
P  NNAMEm1178 NIC6_MAIN_PWR_BIC_EN_R                                            
P  NNAMEm1179 BIC_RST_PWRGD_RSMRST_R                                            
P  NNAMEm1180 PCEPLL2_VDDA18_PEX0                                               
P  NNAMEm1181 SSD2_PEX_PWR_EN                                                   
P  NNAMEm1182 SMB_PEX1_SLAVE_SDA                                                
P  NNAMEm1183 NIC4_MAIN_PWR_BIC_EN_R                                            
P  NNAMEm1184 BIC_RST_RSMRST_R_N                                                
P  NNAMEm1185 PCEPLL4_VDDA18_PEX0                                               
P  NNAMEm1186 I2C_PEX1_HOST_R_SCL                                               
P  NNAMEm1187 SMB_PEX2_PCA9555_SDA                                              
P  NNAMEm1188 NIC3_MAIN_PWR_BIC_EN_R                                            
P  NNAMEm1189 PCEPLL3_VDDA18_PEX0_R                                             
P  NNAMEm1190 NIC5_MAIN_PWR_BIC_EN_R                                            
P  NNAMEm1191 PCEPLL5_VDDA18_PEX0                                               
P  NNAMEm1192 I2C_PEX1_HOST_R_SDA                                               
P  NNAMEm1193 SMB_PEX2_PCA9555_SCL                                              
P  NNAMEm1194 NIC2_MAIN_PWR_BIC_EN_R                                            
P  NNAMEm1195 RST_BIC_USB_HUB_R_N                                               
P  NNAMEm1196 PCEPLL0_VDDA18_PEX0                                               
P  NNAMEm1197 PRSNT_NIC6_FPGA_N                                                 
P  NNAMEm1198 RST_SSD9_PERST_R_N                                                
P  NNAMEm1199 NIC7_MAIN_PWR_BIC_EN_R                                            
P  NNAMEm1200 BIC_RST_PWRGD_RSMRST                                              
P  NNAMEm1201 PCEPLL3_VDDA18_PEX1_R                                             
P  NNAMEm1202 RST_PEX_SSD2_PERST_N                                              
P  NNAMEm1203 I2C_PEX1_HOST_SCL                                                 
P  NNAMEm1204 PWRGD_P1V8_PEX2_R                                                 
P  NNAMEm1205 SSD_LED_IOEXP_A1                                                  
P  NNAMEm1206 SYSPLL_VDDA18_PEX1_R                                              
P  NNAMEm1207 SMB_PEX2_HOST_LS_SDA                                              
P  NNAMEm1208 PRSNT_NIC7_FPGA_N                                                 
P  NNAMEm1209 RST_SSD8_PERST_R_N                                                
P  NNAMEm1210 BIC_RST_RSMRST_N                                                  
P  NNAMEm1211 PCEPLL2_VDDA18_PEX1_R                                             
P  NNAMEm1212 SMB_PEX2_HOST_LS_SCL                                              
P  NNAMEm1213 PCEPLL7_VDDA18_PEX1_R                                             
P  NNAMEm1214 I2C_PEX1_HOST_SDA                                                 
P  NNAMEm1215 I2C_PEX2_HOST_R_SCL                                               
P  NNAMEm1216 P3V3_BIC_USB_HUB                                                  
P  NNAMEm1217 PCEPLL0_VDDA18_PEX1_R                                             
P  NNAMEm1218 PCEPLL1_VDDA18_PEX1_R                                             
P  NNAMEm1219 I2C_PEX2_HOST_R_SDA                                               
P  NNAMEm1220 PCEPLL5_VDDA18_PEX1_R                                             
P  NNAMEm1221 RST_SSD10_PERST_R_N                                               
P  NNAMEm1222 NIC6_MAIN_PWR_BIC_EN                                              
P  NNAMEm1223 PCEPLL4_VDDA18_PEX1_R                                             
P  NNAMEm1224 I2C_PEX2_HOST_SCL                                                 
P  NNAMEm1225 NIC7_MAIN_PWR_BIC_EN                                              
P  NNAMEm1226 PCEPLL6_VDDA18_PEX1_R                                             
P  NNAMEm1227 I2C_PEX2_HOST_SDA                                                 
P  NNAMEm1228 RST_SSD11_PERST_R_N                                               
P  NNAMEm1229 BIC_HEARTBEAT_N                                                   
P  NNAMEm1230 I2C0_PEX2_SHPC_SCL                                                
P  NNAMEm1231 RST_NIC3_PERST_R_N                                                
P  NNAMEm1232 PCEPLL4_VDDA18_PEX1                                               
P  NNAMEm1233 I2C0_PEX2_SHPC_SDA                                                
P  NNAMEm1234 P0V8_PEX3_ISEN1                                                   
P  NNAMEm1235 PCEPLL3_VDDA18_PEX1                                               
P  NNAMEm1236 SMB_PEX2_SLAVE_SCL                                                
P  NNAMEm1237 PCA9555_1_PEX3_A0                                                 
P  NNAMEm1238 SSD7_AUX_P3V3_EN_R                                                
P  NNAMEm1239 PCEPLL7_VDDA18_PEX1                                               
P  NNAMEm1240 SMB_PEX2_SLAVE_SDA                                                
P  NNAMEm1241 PCA9555_1_PEX3_A1                                                 
P  NNAMEm1242 PCEPLL5_VDDA18_PEX1                                               
P  NNAMEm1243 PCA9555_1_PEX3_A2                                                 
P  NNAMEm1244 PRSNT_SSD15_FPGA_N                                                
P  NNAMEm1245 SSD7_AUX_P3V3_EN                                                  
P  NNAMEm1246 PCEPLL6_VDDA18_PEX1                                               
P  NNAMEm1247 PCA9555_0_PEX3_A1                                                 
P  NNAMEm1248 RST_SSD12_PERST_R_N                                               
P  NNAMEm1249 FM_PFR_LED_BLUE                                                   
P  NNAMEm1250 PRSNT_SSD7_R1_N                                                   
P  NNAMEm1251 SYSPLL_VDDA18_PEX1                                                
P  NNAMEm1252 PCA9555_0_PEX3_A0                                                 
P  NNAMEm1253 NIC2_CLK_EN_R_N                                                   
P  NNAMEm1254 RST_SSD13_PERST_R_N                                               
P  NNAMEm1255 BIC_SEL_FLASH_SW3                                                 
P  NNAMEm1256 SSD6_AUX_P3V3_EN_R                                                
P  NNAMEm1257 PCEPLL2_VDDA18_PEX1                                               
P  NNAMEm1258 PU_PEX1_SIO_BLINK                                                 
P  NNAMEm1259 PCA9555_0_PEX3_A2                                                 
P  NNAMEm1260 PRSNT_SSD14_FPGA_N                                                
P  NNAMEm1261 BIC_SEL_FLASH_SW2_R                                               
P  NNAMEm1262 FM_PFR_LED_AMBER                                                  
P  NNAMEm1263 PCEPLL0_VDDA18_PEX1                                               
P  NNAMEm1264 PU_PEX2_SIO_BLINK                                                 
P  NNAMEm1265 PCA9555_0_PEX2_A1                                                 
P  NNAMEm1266 RST_NIC2_PERST_R_N                                                
P  NNAMEm1267 NC_P0V8_PEX2_ISEN4                                                
P  NNAMEm1268 SSD6_AUX_P3V3_EN                                                  
P  NNAMEm1269 PCEPLL1_VDDA18_PEX1                                               
P  NNAMEm1270 PCA9555_0_PEX2_A2                                                 
P  NNAMEm1271 BIC_SEL_FLASH_SW3_R                                               
P  NNAMEm1272 UART_FIO_DEBUG_R_RX                                               
P  NNAMEm1273 PRSNT_SSD6_R1_N                                                   
P  NNAMEm1274 PCA9555_0_PEX2_A0                                                 
P  NNAMEm1275 BIC_SEL_FLASH_SW0_R                                               
P  NNAMEm1276 SSD5_AUX_P3V3_EN_R                                                
P  NNAMEm1277 PCA9555_1_PEX2_A0                                                 
P  NNAMEm1278 RST_PEX_SSD1_PERST_N                                              
P  NNAMEm1279 RST_PEX_SSD13_PERST_N                                             
P  NNAMEm1280 BIC_SEL_FLASH_SW1_R                                               
P  NNAMEm1281 PCA9555_1_PEX2_A1                                                 
P  NNAMEm1282 SSD1_PEX_PWR_EN                                                   
P  NNAMEm1283 SSD13_PEX_PWR_EN                                                  
P  NNAMEm1284 PRSNT_SSD12_FPGA_N                                                
P  NNAMEm1285 SSD5_AUX_P3V3_EN                                                  
P  NNAMEm1286 PCA9555_1_PEX2_A2                                                 
P  NNAMEm1287 P0V8_PEX2_ISEN2                                                   
P  NNAMEm1288 UART_MB_BIC_RX_BUF_R                                              
P  NNAMEm1289 PRSNT_SSD5_R1_N                                                   
P  NNAMEm1290 PCA9555_1_PEX1_A1                                                 
P  NNAMEm1291 NIC1_CLK_EN_R_N                                                   
P  NNAMEm1292 SSD4_AUX_P3V3_EN_R                                                
P  NNAMEm1293 PU_PEX0_SIO_BLINK                                                 
P  NNAMEm1294 PCA9555_1_PEX1_A2                                                 
P  NNAMEm1295 RST_SSD14_PERST_R_N                                               
P  NNAMEm1296 UART_MB_BIC_RX_BUF                                                
P  NNAMEm1297 P1V8_VDDA_PEX0_R                                                  
P  NNAMEm1298 PCA9555_1_PEX1_A0                                                 
P  NNAMEm1299 RST_NIC1_PERST_R_N                                                
P  NNAMEm1300 RST_SSD15_PERST_R_N                                               
P  NNAMEm1301 FM_SYS_THROTTLE_NIC3                                              
P  NNAMEm1302 UART_MB_BIC_R_RX                                                  
P  NNAMEm1303 PCA9555_0_PEX1_A1                                                 
P  NNAMEm1304 UART_BIC_DEBUG_RX                                                 
P  NNAMEm1305 FM_SYS_THROTTLE_NIC5                                              
P  NNAMEm1306 BUF_UART_MB_BIC_RX_EN                                             
P  NNAMEm1307 PCA9555_0_PEX1_A2                                                 
P  NNAMEm1308 PRSNT_SSD13_FPGA_N                                                
P  NNAMEm1309 NC_P0V8_PEX2_PWM3                                                 
P  NNAMEm1310 FM_SYS_THROTTLE_NIC4                                              
P  NNAMEm1311 SSD4_AUX_P3V3_EN                                                  
P  NNAMEm1312 PCA9555_0_PEX1_A0                                                 
P  NNAMEm1313 PRSNT_SSD11_FPGA_N                                                
P  NNAMEm1314 FM_SYS_THROTTLE_NIC7                                              
P  NNAMEm1315 PRSNT_SSD4_R1_N                                                   
P  NNAMEm1316 P1V8_VDDA_PEX1_R                                                  
P  NNAMEm1317 CLK_25M_BIC_CLKIN                                                 
P  NNAMEm1318 UART_BIC_DEBUG_R_TX                                               
P  NNAMEm1319 FM_SYS_THROTTLE_NIC6                                              
P  NNAMEm1320 SSD3_AUX_P3V3_EN_R                                                
P  NNAMEm1321 PCA9555_1_PEX0_A2                                                 
P  NNAMEm1322 P0V8_PEX3_ISEN2                                                   
P  NNAMEm1323 BIC_SEL_FLASH_SW1                                                 
P  NNAMEm1324 FM_SYS_THROTTLE_NIC2                                              
P  NNAMEm1325 PCA9555_1_PEX0_A1                                                 
P  NNAMEm1326 NIC0_CLK_EN_R_N                                                   
P  NNAMEm1327 FM_SYS_THROTTLE_NIC1                                              
P  NNAMEm1328 SSD3_AUX_P3V3_EN                                                  
P  NNAMEm1329 PCA9555_1_PEX0_A0                                                 
P  NNAMEm1330 UART_BIC_DEBUG_R_RX                                               
P  NNAMEm1331 BIC_SEL_FLASH_SW0                                                 
P  NNAMEm1332 PRSNT_SSD3_R1_N                                                   
P  NNAMEm1333 PCA9555_0_PEX0_A2                                                 
P  NNAMEm1334 RST_NIC0_PERST_R_N                                                
P  NNAMEm1335 TP_CK440_PEX_PFT_IN_DN                                            
P  NNAMEm1336 BIC_SEL_FLASH_SW2                                                 
P  NNAMEm1337 FM_SYS_THROTTLE_NIC0                                              
P  NNAMEm1338 SSD2_AUX_P3V3_EN_R                                                
P  NNAMEm1339 PCA9555_0_PEX0_A1                                                 
P  NNAMEm1340 PRSNT_SSD9_FPGA_N                                                 
P  NNAMEm1341 TP_CK440_PEX_PFT_IN_DP                                            
P  NNAMEm1342 NC_P0V8_PEX2_PWM4                                                 
P  NNAMEm1343 PCA9555_0_PEX0_A0                                                 
P  NNAMEm1344 RST_PEX3_PERST_R_N                                                
P  NNAMEm1345 PU_CK440_PEX_PFT_LOST_N                                           
P  NNAMEm1346 P0V8_PEX2_ISEN1                                                   
P  NNAMEm1347 SSD2_AUX_P3V3_EN                                                  
P  NNAMEm1348 NIC1_PWRBRK_R_N                                                   
P  NNAMEm1349 PRSNT_SSD2_R1_N                                                   
P  NNAMEm1350 PRSNT_SSD8_FPGA_N                                                 
P  NNAMEm1351 NIC5_PWRBRK_R_N                                                   
P  NNAMEm1352 RST_PEX2_PERST_R_N                                                
P  NNAMEm1353 SSD1_AUX_P3V3_EN_R                                                
P  NNAMEm1354 RST_PEX1_PERST_R_N                                                
P  NNAMEm1355 SMB_IO_DEBUG_CARD_R_SCL                                           
P  NNAMEm1356 SSD1_AUX_P3V3_EN                                                  
P  NNAMEm1357 NC_P0V8_PEX2_ISEN3                                                
P  NNAMEm1358 PRSNT_SSD1_R1_N                                                   
P  NNAMEm1359 RST_PEX0_PERST_R_N                                                
P  NNAMEm1360 RST_PEX_SYS_BUF_R_N                                               
P  NNAMEm1361 SMB_MB_BMC_ISO_SDA                                                
P  NNAMEm1362 PEX0_PCA9555_0_INT_N                                              
P  NNAMEm1363 PEX3_PCA9555_INT_R_N                                              
P  NNAMEm1364 SMB_MB_BMC_ISO_SCL                                                
P  NNAMEm1365 PEX3_PCA9555_INT_N                                                
P  NNAMEm1366 SSD15_CLK_EN_R_N                                                  
P  NNAMEm1367 USB_DEBUG_RST_BTN_N                                               
P  NNAMEm1368 PEX3_PCA9555_1_INT_N                                              
P  NNAMEm1369 PWRGD_P1V2_AUX_RST                                                
P  NNAMEm1370 SSD14_CLK_EN_R_N                                                  
P  NNAMEm1371 SMB_IO_DEBUG_CARD_R_SDA                                           
P  NNAMEm1372 SSD13_CLK_EN_R_N                                                  
P  NNAMEm1373 PEX3_PCA9555_0_INT_N                                              
P  NNAMEm1374 SSD12_CLK_EN_R_N                                                  
P  NNAMEm1375 PRSNT_SSD10_FPGA_N                                                
P  NNAMEm1376 PWRGD_SYS_PWROK                                                   
P  NNAMEm1377 NC_P0V8_PEX2_PH2_NC1                                              
P  NNAMEm1378 SSD11_CLK_EN_R_N                                                  
P  NNAMEm1379 NC_P0V8_PEX2_PH2_NC3                                              
P  NNAMEm1380 SSD10_CLK_EN_R_N                                                  
P  NNAMEm1381 PWRGD_DSW_PWROK                                                   
P  NNAMEm1382 NC_P0V8_PEX2_PH1_NC2                                              
P  NNAMEm1383 SSD9_CLK_EN_R_N                                                   
P  NNAMEm1384 NC_P0V8_PEX2_PH1_NC1                                              
P  NNAMEm1385 PEX2_PCA9555_INT_R_N                                              
P  NNAMEm1386 SSD11_PEX_PWR_EN                                                  
P  NNAMEm1387 SSD8_CLK_EN_R_N                                                   
P  NNAMEm1388 PEX2_PCA9555_INT_N                                                
P  NNAMEm1389 RST_PEX_SSD11_PERST_N                                             
P  NNAMEm1390 NC_P0V8_PEX2_PH2_NC2                                              
P  NNAMEm1391 PEX2_PCA9555_1_INT_N                                              
P  NNAMEm1392 FM_CPU_CATERR_MSMI_LVT3_N                                         
P  NNAMEm1393 RST_PEX_SYS_BUF_N                                                 
P  NNAMEm1394 PU_9ZXL0851_0_7_100M                                              
P  NNAMEm1395 PRSNT_SSD11_FPGA_R_N                                              
P  NNAMEm1396 NC_P0V8_PEX2_PH1_NC3                                              
P  NNAMEm1397 SSD6_PWRDIS_BIC                                                   
P  NNAMEm1398 SSD3_PWRDIS_BIC                                                   
P  NNAMEm1399 PEX2_PCA9555_0_INT_N                                              
P  NNAMEm1400 SSD1_PWRDIS_BIC                                                   
P  NNAMEm1401 SMB_BIC_I2C6_SENEOR_SCL                                           
P  NNAMEm1402 SSD5_PWRDIS_BIC                                                   
P  NNAMEm1403 SMB_BIC_I2C6_SENEOR_SDA                                           
P  NNAMEm1404 SSD13_PWRDIS_BIC                                                  
P  NNAMEm1405 RST_PEX_NIC6_PERST_N                                              
P  NNAMEm1406 SSD4_PWRDIS_BIC                                                   
P  NNAMEm1407 RST_BIC_SELF_HW_RST_N                                             
P  NNAMEm1408 NIC6_PEX_PWR_EN                                                   
P  NNAMEm1409 SSD11_PWRDIS_BIC                                                  
P  NNAMEm1410 P1V2_BIC_ADCVREFREXT1                                             
P  NNAMEm1411 RST_BIC_SELF_HW_RST_R_N                                           
P  NNAMEm1412 NIC5_PEX_PWR_EN                                                   
P  NNAMEm1413 RST_PEX_SSD12_PERST_N                                             
P  NNAMEm1414 SSD2_PWRDIS_BIC                                                   
P  NNAMEm1415 RST_PEX_NIC5_PERST_N                                              
P  NNAMEm1416 SSD12_PEX_PWR_EN                                                  
P  NNAMEm1417 FPGA_DEBUG_LED_R_N                                                
P  NNAMEm1418 SSD10_PWRDIS_BIC                                                  
P  NNAMEm1419 RST_PEX_SSD12_PERST_R_N                                           
P  NNAMEm1420 LED_POSTCODE_R_6                                                  
P  NNAMEm1421 SSD7_PWRDIS_BIC                                                   
P  NNAMEm1422 SSD12_PEX_PWR_EN_R                                                
P  NNAMEm1423 LED_POSTCODE_R_3                                                  
P  NNAMEm1424 SSD9_PWRDIS_BIC                                                   
P  NNAMEm1425 LED_POSTCODE_R_7                                                  
P  NNAMEm1426 SSD8_PWRDIS_BIC                                                   
P  NNAMEm1427 LED_POSTCODE_R_5                                                  
P  NNAMEm1428 SSD14_PWRDIS_BIC                                                  
P  NNAMEm1429 SSD15_PWRDIS_BIC                                                  
P  NNAMEm1430 P1V2_BIC_ADCVREFREXT0                                             
P  NNAMEm1431 LED_POSTCODE_R_1                                                  
P  NNAMEm1432 SSD12_PWRDIS_BIC                                                  
P  NNAMEm1433 RST_PEX_SSD14_PERST_N                                             
P  NNAMEm1434 FM_SYS_THROTTLE_R                                                 
P  NNAMEm1435 LED_POSTCODE_R_4                                                  
P  NNAMEm1436 SSD0_PWRDIS_BIC                                                   
P  NNAMEm1437 CK440_PEX_SS_EN                                                   
P  NNAMEm1438 PEX1_PCA9555_INT_R_N                                              
P  NNAMEm1439 LED_POSTCODE_R_0                                                  
P  NNAMEm1440 PEX1_PCA9555_INT_N                                                
P  NNAMEm1441 RST_PEX_SYS_R_N                                                   
P  NNAMEm1442 PEX_REF_CLK_BUFFER_EN_N                                           
P  NNAMEm1443 PEX1_PCA9555_1_INT_N                                              
P  NNAMEm1444 LED_POSTCODE_R_2                                                  
P  NNAMEm1445 PRSNT_SSD2_FPGA_R_N                                               
P  NNAMEm1446 RST_PEX2_S0_PERST_R_N                                             
P  NNAMEm1447 PEX_REF_CLK_GEN_EN_N                                              
P  NNAMEm1448 PEX1_PCA9555_0_INT_N                                              
P  NNAMEm1449 PRSNT_SSD3_FPGA_R_N                                               
P  NNAMEm1450 RST_PEX3_S0_PERST_R_N                                             
P  NNAMEm1451 SMB_ALERT_HSC_R_N                                                 
P  NNAMEm1452 PRSNT_SSD0_FPGA_R_N                                               
P  NNAMEm1453 RST_PEX3_S1_PERST_R_N                                             
P  NNAMEm1454 SMB_PEX3_PCA9555_SDA                                              
P  NNAMEm1455 PRSNT_SSD1_FPGA_R_N                                               
P  NNAMEm1456 SMB_ALERT_PMBUS_R_N                                               
P  NNAMEm1457 SMB_PEX3_PCA9555_SCL                                              
P  NNAMEm1458 SSD14_PEX_PWR_EN                                                  
P  NNAMEm1459 PWR_EN_P1V2_AUX_R                                                 
P  NNAMEm1460 PWRGD_P1V8_PEX3_R                                                 
P  NNAMEm1461 SMB_PEX3_HOST_LS_SDA                                              
P  NNAMEm1462 PRSNT_SSD5_FPGA_R_N                                               
P  NNAMEm1463 PWRGD_P0V8_PEX2_R                                                 
P  NNAMEm1464 PD_BIC_ADCREXT1                                                   
P  NNAMEm1465 SMB_PEX3_HOST_LS_SCL                                              
P  NNAMEm1466 PRSNT_SSD4_FPGA_R_N                                               
P  NNAMEm1467 PWRGD_P0V8_PEX3_R                                                 
P  NNAMEm1468 PD_BIC_ADCREXT0                                                   
P  NNAMEm1469 I2C_PEX3_HOST_R_SCL                                               
P  NNAMEm1470 PRSNT_SSD7_FPGA_R_N                                               
P  NNAMEm1471 PWRGD_P0V8_PEX0_R                                                 
P  NNAMEm1472 PRSNT_SSD6_FPGA_R_N                                               
P  NNAMEm1473 PWRGD_P0V8_PEX1_R                                                 
P  NNAMEm1474 I2C_PEX3_HOST_R_SDA                                               
P  NNAMEm1475 NIC4_PWRBRK_R_N                                                   
P  NNAMEm1476 PWRGD_P12V_AUX_R                                                  
P  NNAMEm1477 I2C_PEX3_HOST_SCL                                                 
P  NNAMEm1478 PWRGD_P1V2_AUX_R                                                  
P  NNAMEm1479 UART_FIO_DEBUG_R_TX                                               
P  NNAMEm1480 I2C_PEX3_HOST_SDA                                                 
P  NNAMEm1481 SSD9_PEX_PWR_EN                                                   
P  NNAMEm1482 I2C0_PEX3_SHPC_SCL                                                
P  NNAMEm1483 RST_PEX_SSD9_PERST_N                                              
P  NNAMEm1484 PRSNT_SSD10_FPGA_R_N                                              
P  NNAMEm1485 I2C0_PEX3_SHPC_SDA                                                
P  NNAMEm1486 NIC7_PEX_PWR_EN_R                                                 
P  NNAMEm1487 PRSNT_SSD9_FPGA_R_N                                               
P  NNAMEm1488 P3V3_BIC_ADCAV33                                                  
P  NNAMEm1489 RST_SMB_FIO_R_N                                                   
P  NNAMEm1490 SMB_PEX3_SLAVE_SCL                                                
P  NNAMEm1491 PRSNT_SSD8_FPGA_R_N                                               
P  NNAMEm1492 RST_SMB_FPGA_R_N                                                  
P  NNAMEm1493 SMB_PEX3_SLAVE_SDA                                                
P  NNAMEm1494 RST_SMB_SSD_R_N                                                   
P  NNAMEm1495 RST_PEX_NIC7_PERST_R_N                                            
P  NNAMEm1496 RST_PEX_SSD13_PERST_R_N                                           
P  NNAMEm1497 PRSNT_SSD13_FPGA_R_N                                              
P  NNAMEm1498 NC_P0V8_PEX3_PH1_NC1                                              
P  NNAMEm1499 PRSNT_NIC7_FPGA_R_N                                               
P  NNAMEm1500 RST_PEX_NIC6_PERST_R_N                                            
P  NNAMEm1501 PRSNT_NIC6_FPGA_R_N                                               
P  NNAMEm1502 PWRGD_P1V8_PEX0_R                                                 
P  NNAMEm1503 PU_PEX3_SIO_BLINK                                                 
P  NNAMEm1504 PRSNT_SSD14_FPGA_R_N                                              
P  NNAMEm1505 SSD15_AUX_P3V3_EN_R                                               
P  NNAMEm1506 RST_NIC4_PERST_R_N                                                
P  NNAMEm1507 PRSNT_SSD15_FPGA_R_N                                              
P  NNAMEm1508 NC_P0V8_PEX3_PH2_NC3                                              
P  NNAMEm1509 PRSNT_SSD12_FPGA_R_N                                              
P  NNAMEm1510 RST_SMB_NIC_MUX_N                                                 
P  NNAMEm1511 SSD15_AUX_P3V3_EN                                                 
P  NNAMEm1512 PRSNT_SSD15_R1_N                                                  
P  NNAMEm1513 BIC_SYS_READY_R2_N                                                
P  NNAMEm1514 SSD14_AUX_P3V3_EN_R                                               
P  NNAMEm1515 NC_P0V8_PEX3_PH2_NC1                                              
P  NNAMEm1516 NC_P0V8_PEX3_PH2_NC2                                              
P  NNAMEm1517 SSD14_AUX_P3V3_EN                                                 
P  NNAMEm1518 NC_P0V8_PEX3_PH1_NC3                                              
P  NNAMEm1519 PRSNT_SSD14_R1_N                                                  
P  NNAMEm1520 SSD13_AUX_P3V3_EN_R                                               
P  NNAMEm1521 BIC_SYS_READY_R_N                                                 
P  NNAMEm1522 RST_PEX2_S1_PERST_R_N                                             
P  NNAMEm1523 SSD13_AUX_P3V3_EN                                                 
P  NNAMEm1524 NIC6_PEX_PWR_EN_R                                                 
P  NNAMEm1525 NC_P0V8_PEX3_PH1_NC2                                              
P  NNAMEm1526 BIC_SYS_READY_N                                                   
P  NNAMEm1527 PRSNT_SSD13_R1_N                                                  
P  NNAMEm1528 SSD13_PEX_PWR_EN_R                                                
P  NNAMEm1529 FM_CK440_PEX_DEV_25M_EN                                           
P  NNAMEm1530 SSD12_AUX_P3V3_EN_R                                               
P  NNAMEm1531 SSD12_AUX_P3V3_EN                                                 
P  NNAMEm1532 SMB_SSD10_ADC_SDA                                                 
P  NNAMEm1533 SMB_CK440_PEX_CLK_SCL                                             
P  NNAMEm1534 PRSNT_SSD12_R1_N                                                  
P  NNAMEm1535 SMB_PEX_P1V8_ADC_SCL                                              
P  NNAMEm1536 CLK_GEN_CK440_PEX_OE4_N                                           
P  NNAMEm1537 P12V_AUX_SCALED                                                   
P  NNAMEm1538 SSD11_AUX_P3V3_EN_R                                               
P  NNAMEm1539 CLK_GEN_CK440_PEX_OE6_N                                           
P  NNAMEm1540 BMC_HEARTBEAT_N_D                                                 
P  NNAMEm1541 SSD11_AUX_P3V3_EN                                                 
P  NNAMEm1542 TP_CLK_CK440_PEX_PFT_OUT_DN                                       
P  NNAMEm1543 PRSNT_SSD11_R1_N                                                  
P  NNAMEm1544 SSD10_AUX_P3V3_EN_R                                               
P  NNAMEm1545 SMB_PEX2_P1V25_ADC_SDA                                            
P  NNAMEm1546 TP_CK440_PEX_SBI_DATA_OUT                                         
P  NNAMEm1547 PRSNT_SSD0_R1_N                                                   
P  NNAMEm1548 SSD10_AUX_P3V3_EN                                                 
P  NNAMEm1549 PRSNT_SSD10_R1_N                                                  
P  NNAMEm1550 SSD0_AUX_P3V3_EN                                                  
P  NNAMEm1551 SSD9_AUX_P3V3_EN_R                                                
P  NNAMEm1552 XTAL_CK440_PEX_25M_R_XIN                                          
P  NNAMEm1553 SMB_PEX3_P1V25_ADC_SCL                                            
P  NNAMEm1554 RST_PEX_SSD7_PERST_N                                              
P  NNAMEm1555 TP_CLK_CK440_PEX_PFT_OUT_DP                                       
P  NNAMEm1556 SSD9_AUX_P3V3_EN                                                  
P  NNAMEm1557 SSD10_PWRDIS_BIC_R                                                
P  NNAMEm1558 SMB_CK440_PEX_CLK_SDA                                             
P  NNAMEm1559 RST_FPGA_BIC_R1_N                                                 
P  NNAMEm1560 PRSNT_SSD9_R1_N                                                   
P  NNAMEm1561 SSD7_PWRDIS_BIC_R                                                 
P  NNAMEm1562 SMB_HOTSWAP_SDA_R                                                 
P  NNAMEm1563 RST_FPGA_BIC_R_N                                                  
P  NNAMEm1564 SSD8_AUX_P3V3_EN_R                                                
P  NNAMEm1565 SSD9_PWRDIS_BIC_R                                                 
P  NNAMEm1566 CLK_GEN_CK440_PEX_OE5_N                                           
P  NNAMEm1567 SSD0_AUX_P3V3_EN_R                                                
P  NNAMEm1568 SSD8_PWRDIS_BIC_R                                                 
P  NNAMEm1569 CLK_CK440_PEX_SMB_ADDR0                                           
P  NNAMEm1570 SSD8_AUX_P3V3_EN                                                  
P  NNAMEm1571 PRSNT_SSD8_R1_N                                                   
P  NNAMEm1572 PU_CK440_PEX_SHFT_LD_N                                            
P  NNAMEm1573 XTAL_CK440_PEX_25M_XOUT                                           
P  NNAMEm1574 P3V3_BIC_USB2AV33                                                 
P  NNAMEm1575 SSD15_PEX_PWR_EN_R                                                
P  NNAMEm1576 P1V2_BIC_USB2AV12                                                 
P  NNAMEm1577 SMB_NIC6_ADC_SDA                                                  
P  NNAMEm1578 SSD14_PWRDIS_BIC_R                                                
P  NNAMEm1579 FM_CK440_PEX_MXCK_25M_100M                                        
P  NNAMEm1580 RST_PEX_SSD14_PERST_R_N                                           
P  NNAMEm1581 PD_CK440_PEX_SBI_CLK                                              
P  NNAMEm1582 SSD10_PEX_PWR_EN                                                  
P  NNAMEm1583 RST_PEX1_S1_PERST_R_N                                             
P  NNAMEm1584 RST_PEX_SSD10_PERST_N                                             
P  NNAMEm1585 RST_PEX1_S0_PERST_R_N                                             
P  NNAMEm1586 SMB_PEX0_HOST_LS_SDA                                              
P  NNAMEm1587 RST_PEX_SSD8_PERST_N                                              
P  NNAMEm1588 SSD14_PEX_PWR_EN_R                                                
P  NNAMEm1589 PD_CK440_PEX_SBI_DATA_IN                                          
P  NNAMEm1590 SMB_NIC7_ADC_SCL                                                  
P  NNAMEm1591 SSD7_PEX_PWR_EN                                                   
P  NNAMEm1592 RST_PEX_SSD15_PERST_R_N                                           
P  NNAMEm1593 CLK_CK440_PEX_SMB_ADDR1                                           
P  NNAMEm1594 SMB_PEX0_HOST_LS_SCL                                              
P  NNAMEm1595 SSD8_PEX_PWR_EN                                                   
P  NNAMEm1596 SMB_PEX0_PCA9555_SDA                                              
P  NNAMEm1597 XTAL_CK440_PEX_25M_XIN                                            
P  NNAMEm1598 PRSNT_NIC7_FPGA_PCA9555_N                                         
P  NNAMEm1599 NIC3_PWRBRK_R_N                                                   
P  NNAMEm1600 SMB_NIC2_ADC_SDA                                                  
P  NNAMEm1601 SMB_PEX0_PCA9555_SCL                                              
P  NNAMEm1602 PWRGD_P1V8_PEX1_R                                                 
P  NNAMEm1603 PRSNT_NIC6_FPGA_PCA9555_N                                         
P  NNAMEm1604 SSD9_PEX_PWR_EN_R                                                 
P  NNAMEm1605 PRSNT_SSD13_FPGA_PCA9555_N                                        
P  NNAMEm1606 PRSNT_SSD12_FPGA_PCA9555_N                                        
P  NNAMEm1607 PRSNT_NIC5_FPGA_PCA9555_N                                         
P  NNAMEm1608 JTAG_BIC_NTRST_N                                                  
P  NNAMEm1609 SMB_PEX0_SLAVE_SDA                                                
P  NNAMEm1610 SSD11_PEX_PWR_EN_R                                                
P  NNAMEm1611 PRSNT_SSD11_FPGA_PCA9555_N                                        
P  NNAMEm1612 SMB_NIC3_ADC_SCL                                                  
P  NNAMEm1613 SMB_PEX0_SLAVE_SCL                                                
P  NNAMEm1614 PRSNT_SSD10_FPGA_PCA9555_N                                        
P  NNAMEm1615 UART_PEX0_CLI_R_RX                                                
P  NNAMEm1616 PRSNT_NIC4_FPGA_PCA9555_N                                         
P  NNAMEm1617 PRSNT_NIC5_FPGA_R_N                                               
P  NNAMEm1618 P12V_SSD9_VIN_N                                                   
P  NNAMEm1619 PRSNT_SSD9_FPGA_PCA9555_N                                         
P  NNAMEm1620 PRSNT_SSD8_FPGA_PCA9555_N                                         
P  NNAMEm1621 SSD11_PWRDIS_BIC_R                                                
P  NNAMEm1622 JTAG_BIC_NTRST_R_N                                                
P  NNAMEm1623 SMB_SSD9_ADC_SDA                                                  
P  NNAMEm1624 PRSNT_NIC3_FPGA_PCA9555_N                                         
P  NNAMEm1625 PRSNT_NIC4_FPGA_R_N                                               
P  NNAMEm1626 SSD12_PWRDIS_BIC_R                                                
P  NNAMEm1627 P12V_SSD9_VIN_P                                                   
P  NNAMEm1628 RST_PEX_SSD10_PERST_R_N                                           
P  NNAMEm1629 PRSNT_SSD7_FPGA_PCA9555_N                                         
P  NNAMEm1630 SSD13_PWRDIS_BIC_R                                                
P  NNAMEm1631 RST_FW_BIC_PLTRST_C                                               
P  NNAMEm1632 SSD9_ADC_ALERT_N                                                  
P  NNAMEm1633 PRSNT_SSD6_FPGA_PCA9555_N                                         
P  NNAMEm1634 PEX_USB2_SEL_CONN                                                 
P  NNAMEm1635 RST_FW_BIC_PLTRST_R                                               
P  NNAMEm1636 SMB_SSD9_ADC_SCL                                                  
P  NNAMEm1637 PRSNT_NIC2_FPGA_PCA9555_N                                         
P  NNAMEm1638 PRSNT_NIC3_FPGA_R_N                                               
P  NNAMEm1639 PRSNT_SSD5_FPGA_PCA9555_N                                         
P  NNAMEm1640 RST_FW_BIC_PLTRST                                                 
P  NNAMEm1641 PRSNT_SSD4_FPGA_PCA9555_N                                         
P  NNAMEm1642 PWR_EN_P1V2_AUX                                                   
P  NNAMEm1643 BIC_FORCE_THROTTLE_N                                              
P  NNAMEm1644 PRSNT_NIC2_FPGA_R_N                                               
P  NNAMEm1645 PEX3_EXT_GPIO_LATCH_N                                             
P  NNAMEm1646 SMB_BIC_I2C6_R_SDA                                                
P  NNAMEm1647 RST_PEX_SSD9_PERST_R_N                                            
P  NNAMEm1648 P3V3_CLK_GEN_VDDMXCK_CK440_PEX                                    
P  NNAMEm1649 SMB_BIC_I2C6_R_SCL                                                
P  NNAMEm1650 RST_PEX_SSD8_PERST_R_N                                            
P  NNAMEm1651 PRSNT_NIC1_FPGA_PCA9555_N                                         
P  NNAMEm1652 P3V3_CLK_GEN_VDDA100M_CK440_PEX                                   
P  NNAMEm1653 PRSNT_SSD3_FPGA_PCA9555_N                                         
P  NNAMEm1654 PRSNT_NIC1_FPGA_R_N                                               
P  NNAMEm1655 P3V3_CLK_GEN_VDD_CK440_PEX                                        
P  NNAMEm1656 PWRGD_P3V3_SSD10                                                  
P  NNAMEm1657 PEX_USB_HUB_OVCUR4                                                
P  NNAMEm1658 CLK_100M_DB2000QL_PEX1_S1_DN                                      
P  NNAMEm1659 RST_BIC_I2C6_MUX_R_N                                              
P  NNAMEm1660 PWRGD_P12V_SSD15_R                                                
P  NNAMEm1661 PEX_USB_HUB_OVCUR3                                                
P  NNAMEm1662 BIC_I2C6_MUX_A2                                                   
P  NNAMEm1663 GPU_RSVD_PARTNER2                                                 
P  NNAMEm1664 SSD2_PEX_PWR_EN_R                                                 
P  NNAMEm1665 PEX_USB_HUB_OVCUR2                                                
P  NNAMEm1666 BIC_I2C6_MUX_A1                                                   
P  NNAMEm1667 PRSNT_SSD0_FPGA_N                                                 
P  NNAMEm1668 PWRGD_P3V3_SSD12                                                  
P  NNAMEm1669 PEX_USB_HUB_OVCUR1                                                
P  NNAMEm1670 CLK_100M_CK440Q_2_DB800ZL_DN                                      
P  NNAMEm1671 BIC_I2C6_MUX_A0                                                   
P  NNAMEm1672 CLK_100M_MB_0_DN                                                  
P  NNAMEm1673 SMB_GPU2_ALERT_N                                                  
P  NNAMEm1674 FPGA_DEBUG_LED_N                                                  
P  NNAMEm1675 SSD3_PWRDIS_BIC_R                                                 
P  NNAMEm1676 CLK_100M_CK440Q_2_DB800ZL_DP                                      
P  NNAMEm1677 PU_PEX3_PAD_TRI_L                                                 
P  NNAMEm1678 SYS_PWR_READY_R_N                                                 
P  NNAMEm1679 PRSNT_SSD5_FPGA_N                                                 
P  NNAMEm1680 PWRGD_P3V3_SSD11                                                  
P  NNAMEm1681 CLK_100M_CK440Q_1_DB800ZL_DN                                      
P  NNAMEm1682 CLK_100M_CK440Q_1_DB800ZL_DP                                      
P  NNAMEm1683 PEX1_MODE_SEL12                                                   
P  NNAMEm1684 SSD4_PWRDIS_BIC_R                                                 
P  NNAMEm1685 CLK_100M_DB2000QL_PEX2_S1_DP                                      
P  NNAMEm1686 PU_9ZXL0851_0_7_HBW                                               
P  NNAMEm1687 PEX1_MODE_SEL10                                                   
P  NNAMEm1688 SSD4_PEX_PWR_EN_R                                                 
P  NNAMEm1689 RST_SSD0_PERST_R_N                                                
P  NNAMEm1690 SSD3_PEX_PWR_EN_R                                                 
P  NNAMEm1691 GPU_BASE_STBY_EN_R                                                
P  NNAMEm1692 RST_PEX_SSD5_PERST_R_N                                            
P  NNAMEm1693 SMB_BMC_9ZXL0851_8_15_SCL                                         
P  NNAMEm1694 SSD6_PWRDIS_BIC_R                                                 
P  NNAMEm1695 CLK_100M_DB2000QL_PEX3_S1_DP                                      
P  NNAMEm1696 SMB_BMC_9ZXL0851_8_15_SDA                                         
P  NNAMEm1697 GPU_3V3IO_RSVD1_FFU                                               
P  NNAMEm1698 PWRGD_P3V3_SSD9                                                   
P  NNAMEm1699 PWRGD_P12V_SSD1                                                   
P  NNAMEm1700 RST_PEX_SSD3_PERST_R_N                                            
P  NNAMEm1701 PEX1_MODE_SEL11                                                   
P  NNAMEm1702 GPU_3V3IO_RSVD0_FFU                                               
P  NNAMEm1703 RST_SSD15_PERST_N                                                 
P  NNAMEm1704 SMB_MB_BMC_R_SCL                                                  
P  NNAMEm1705 RST_PEX_SSD2_PERST_R_N                                            
P  NNAMEm1706 PU_PEX3_ATPG_MODE_L                                               
P  NNAMEm1707 GPU_BASE_HMC_READY                                                
P  NNAMEm1708 PWRGD_P3V3_SSD13                                                  
P  NNAMEm1709 GPU_PWR_BRAKE_N                                                   
P  NNAMEm1710 PRSNT_SSD2_FPGA_N                                                 
P  NNAMEm1711 PWRGD_P3V3_SSD8                                                   
P  NNAMEm1712 TP_CLK_100M_MB_2_DN                                               
P  NNAMEm1713 SSD0_PWRDIS_BIC_R                                                 
P  NNAMEm1714 PWRGD_P3V3_SSD14                                                  
P  NNAMEm1715 FM_UV_ADR_TRIGGER_N                                               
P  NNAMEm1716 SSD2_PWRDIS_BIC_R                                                 
P  NNAMEm1717 PWRGD_P3V3_SSD15                                                  
P  NNAMEm1718 PRSNT_GPU_HMC_N                                                   
P  NNAMEm1719 PRSNT_SSD6_FPGA_N                                                 
P  NNAMEm1720 SSD0_CLK_EN_R_N                                                   
P  NNAMEm1721 PRSNT_SSD15_R_N                                                   
P  NNAMEm1722 PEX3_MODE_SEL10                                                   
P  NNAMEm1723 PWRGD_P3V3_SSD1                                                   
P  NNAMEm1724 P3V3_VDD_9ZXL0851_0_7                                             
P  NNAMEm1725 SSD6_PEX_PWR_EN_R                                                 
P  NNAMEm1726 P3V3_VDDAR_9ZXL0851_0_7                                           
P  NNAMEm1727 GPU_FPGA_EROT_FATALERR_N                                          
P  NNAMEm1728 PRSNT_SSD3_FPGA_N                                                 
P  NNAMEm1729 CLK_100M_DB800ZL_SSD7_R_DP                                        
P  NNAMEm1730 PEX1_SYS_ERR_R_N                                                  
P  NNAMEm1731 CLK_100M_DB2000QL_PEX2_S1_DN                                      
P  NNAMEm1732 CLK_100M_DB800ZL_SSD6_R_DP                                        
P  NNAMEm1733 GPU_FPGA_EROT_RECOV_R_N                                           
P  NNAMEm1734 CLK_100M_DB2000QL_PEX0_S1_DP                                      
P  NNAMEm1735 CLK_100M_DB800ZL_SSD3_R_DP                                        
P  NNAMEm1736 RST_PEX_SSD4_PERST_R_N                                            
P  NNAMEm1737 CLK_100M_DB800ZL_SSD3_R_DN                                        
P  NNAMEm1738 RST_GPU_FPGA_EROT_N                                               
P  NNAMEm1739 PWRGD_P12V_SSD7                                                   
P  NNAMEm1740 RST_PEX_SSD1_PERST_R_N                                            
P  NNAMEm1741 CLK_100M_DB800ZL_SSD0_R_DP                                        
P  NNAMEm1742 MB_SWB_PWR_EN_ISO                                                 
P  NNAMEm1743 SSD1_PWRDIS_BIC_R                                                 
P  NNAMEm1744 CLK_100M_DB800ZL_SSD7_R_DN                                        
P  NNAMEm1745 SMB_BIC_I2C6_SCL                                                  
P  NNAMEm1746 MB_SWB_PWR_EN_ISO_R                                               
P  NNAMEm1747 PWRGD_P12V_SSD3                                                   
P  NNAMEm1748 PRSNT_SSD4_FPGA_N                                                 
P  NNAMEm1749 CLK_100M_DB800ZL_SSD6_R_DN                                        
P  NNAMEm1750 SSD1_CLK_EN_R_N                                                   
P  NNAMEm1751 SSD5_CLK_EN_R_N                                                   
P  NNAMEm1752 SSD5_PEX_PWR_EN_R                                                 
P  NNAMEm1753 SPI_BIC1_MISO_R5                                                  
P  NNAMEm1754 CLK_100M_DB800ZL_SSD0_R_DN                                        
P  NNAMEm1755 GPU_FPGA_BOOT_EN                                                  
P  NNAMEm1756 SMB_MB_BMC_R_SDA                                                  
P  NNAMEm1757 CLK_100M_DB800ZL_SSD5_R_DP                                        
P  NNAMEm1758 PWRGD_P12V_SSD6                                                   
P  NNAMEm1759 SPI_BIC1_MOSI_R5                                                  
P  NNAMEm1760 SMB_BMC_9QXL2001_SCL                                              
P  NNAMEm1761 CLK_100M_DB800ZL_SSD5_R_DN                                        
P  NNAMEm1762 PEX3_SYS_ERR_R_N                                                  
P  NNAMEm1763 PWRGD_P3V3_SSD4                                                   
P  NNAMEm1764 PWRGD_P12V_SSD9_R                                                 
P  NNAMEm1765 CLK_100M_DB800ZL_SSD1_R_DN                                        
P  NNAMEm1766 RST_MB_PERST_2_ISO_N                                              
P  NNAMEm1767 PWRGD_P3V3_SSD6                                                   
P  NNAMEm1768 PRSNT_SSD14_R_N                                                   
P  NNAMEm1769 SPI_BIC1_CLK_R5                                                   
P  NNAMEm1770 CLK_100M_DB800ZL_SSD4_R_DN                                        
P  NNAMEm1771 SMB_BMC_9ZXL0851_0_7_SCL                                          
P  NNAMEm1772 FM_SOL_UART_CH_SEL                                                
P  NNAMEm1773 SSD4_CLK_EN_R_N                                                   
P  NNAMEm1774 PRSNT_SSD12_R_N                                                   
P  NNAMEm1775 CLK_100M_DB800ZL_SSD1_R_DP                                        
P  NNAMEm1776 SMB_BMC_9ZXL0851_0_7_SDA                                          
P  NNAMEm1777 PWRGD_P3V3_SSD2                                                   
P  NNAMEm1778 CLK_100M_DB800ZL_SSD2_R_DN                                        
P  NNAMEm1779 SMB_GPU2_ALERT_R_N                                                
P  NNAMEm1780 RST_MB_PERST_2_ISO_R_N                                            
P  NNAMEm1781 RST_SSD12_PERST_N                                                 
P  NNAMEm1782 CLK_100M_DB800ZL_SSD2_R_DP                                        
P  NNAMEm1783 RST_SSD1_PERST_R_N                                                
P  NNAMEm1784 RST_SSD11_PERST_N                                                 
P  NNAMEm1785 CLK_100M_DB800ZL_SSD4_R_DP                                        
P  NNAMEm1786 PEX3_MODE_SEL11                                                   
P  NNAMEm1787 PWRGD_P3V3_SSD8_R                                                 
P  NNAMEm1788 PWRGD_P12V_SSD5                                                   
P  NNAMEm1789 PWRGD_P3V3_SSD12_R                                                
P  NNAMEm1790 RST_SSD4_PERST_R_N                                                
P  NNAMEm1791 SMB_FPGA_ALERT_R_N                                                
P  NNAMEm1792 CLK_100M_DB2000QL_PEX0_S1_DN                                      
P  NNAMEm1793 PEX3_MODE_SEL12                                                   
P  NNAMEm1794 GPU_BASE_STBY_EN                                                  
P  NNAMEm1795 LED_PEX3_SYS_ERR_N                                                
P  NNAMEm1796 PWRGD_P3V3_SSD9_R                                                 
P  NNAMEm1797 GPU_BASE_PWR_GD_R                                                 
P  NNAMEm1798 PEX3_SYS_ERR_3V3_N                                                
P  NNAMEm1799 RST_SSD3_PERST_R_N                                                
P  NNAMEm1800 UART_PEX3_SDB_BUF_R_TX                                            
P  NNAMEm1801 CLK_100M_PEX3_REF_DN                                              
P  NNAMEm1802 PEX3_SYS_ERR_N_G                                                  
P  NNAMEm1803 UART_MB_BIC_TX_BUF_R                                              
P  NNAMEm1804 UART_PEX2_SDB_BUF_R_TX                                            
P  NNAMEm1805 SMB_BMC_9QXL2001_SDA                                              
P  NNAMEm1806 CLK_100M_PEX3_REF_DP                                              
P  NNAMEm1807 SMB_ISO_SSD0_SDA                                                  
P  NNAMEm1808 GPU_3V3IO_RSVD1_FFU_R                                             
P  NNAMEm1809 RST_SSD2_PERST_R_N                                                
P  NNAMEm1810 UART_PEX3_SDB_TX                                                  
P  NNAMEm1811 CLK_100M_PEX2_REF_DN                                              
P  NNAMEm1812 SMB_ISO_SSD0_SCL                                                  
P  NNAMEm1813 RST_MB_PERST_1_N                                                  
P  NNAMEm1814 UART_PEX2_SDB_TX                                                  
P  NNAMEm1815 CLK_100M_DB2000QL_PEX3_S1_DN                                      
P  NNAMEm1816 CLK_100M_PEX2_REF_DP                                              
P  NNAMEm1817 SMB_SSD0_ISO_EN                                                   
P  NNAMEm1818 GPU_BASE_HMC_READY_R                                              
P  NNAMEm1819 CLK_100M_PEX1_REF_DN                                              
P  NNAMEm1820 GPU_BASE_PWR_EN                                                   
P  NNAMEm1821 CLK_100M_PEX1_REF_DP                                              
P  NNAMEm1822 GPU_3V3IO_RSVD0_FFU_R                                             
P  NNAMEm1823 PWRGD_P3V3_SSD13_R                                                
P  NNAMEm1824 PEX_USB_HUB_XOUT                                                  
P  NNAMEm1825 CLK_100M_PEX0_REF_DN                                              
P  NNAMEm1826 PEX_USB_HUB_XIN                                                   
P  NNAMEm1827 CLK_100M_PEX0_REF_DP                                              
P  NNAMEm1828 PRSNT_GPU_HMC_R_N                                                 
P  NNAMEm1829 CLK_100M_PEX3_REF_R_DN                                            
P  NNAMEm1830 SMB_BIC_I2C6_SDA                                                  
P  NNAMEm1831 RST_BIC_I2C9_SSD_MUX0_R_N                                         
P  NNAMEm1832 RST_SSD5_PERST_R_N                                                
P  NNAMEm1833 CLK_100M_DB2000QL_GPU_REF2_R_DN                                   
P  NNAMEm1834 SSD6_CLK_EN_R_N                                                   
P  NNAMEm1835 RST_SSD13_PERST_N                                                 
P  NNAMEm1836 CLK_100M_PEX3_REF_R_DP                                            
P  NNAMEm1837 RST_MB_PERST_2_N                                                  
P  NNAMEm1838 SSD2_CLK_EN_R_N                                                   
P  NNAMEm1839 PWRGD_P3V3_SSD11_R                                                
P  NNAMEm1840 CLK_100M_DB2000QL_PEX1_S1_DP                                      
P  NNAMEm1841 CLK_100M_DB800ZL_SSD7_DN                                          
P  NNAMEm1842 CLK_100M_DB2000QL_GPU_REF2_R_DP                                   
P  NNAMEm1843 PWRGD_P12V_SSD2                                                   
P  NNAMEm1844 PWRGD_P12V_SSD10_R                                                
P  NNAMEm1845 CLK_100M_DB800ZL_SSD7_DP                                          
P  NNAMEm1846 CLK_100M_PEX2_REF_R_DN                                            
P  NNAMEm1847 MB_SWB_PWRGD_BUF                                                  
P  NNAMEm1848 SSD3_CLK_EN_R_N                                                   
P  NNAMEm1849 PWRGD_P12V_SSD14_R                                                
P  NNAMEm1850 CLK_100M_DB800ZL_SSD6_DN                                          
P  NNAMEm1851 CLK_100M_DB2000QL_GPU_REF1_R_DN                                   
P  NNAMEm1852 MB_SWB_PWRGD_BUF_R                                                
P  NNAMEm1853 PWRGD_P3V3_SSD7                                                   
P  NNAMEm1854 PWRGD_P12V_SSD13_R                                                
P  NNAMEm1855 UART_PEX1_SDB_BUF_R_TX                                            
P  NNAMEm1856 CLK_100M_DB800ZL_SSD6_DP                                          
P  NNAMEm1857 CLK_100M_PEX2_REF_R_DP                                            
P  NNAMEm1858 SMB_GPU1_ALERT_R_N                                                
P  NNAMEm1859 SSD7_CLK_EN_R_N                                                   
P  NNAMEm1860 PWRGD_P12V_SSD11_R                                                
P  NNAMEm1861 UART_PEX0_SDB_BUF_R_TX                                            
P  NNAMEm1862 CLK_100M_DB800ZL_SSD5_DN                                          
P  NNAMEm1863 CLK_100M_DB2000QL_GPU_REF1_R_DP                                   
P  NNAMEm1864 GPU_FPGA_EROT_FATALERR_R_N                                        
P  NNAMEm1865 PWRGD_P12V_SSD4                                                   
P  NNAMEm1866 PRSNT_SSD10_R_N                                                   
P  NNAMEm1867 UART_PEX1_SDB_TX                                                  
P  NNAMEm1868 CLK_100M_DB800ZL_SSD5_DP                                          
P  NNAMEm1869 CLK_100M_PEX1_REF_R_DN                                            
P  NNAMEm1870 SMB_CK440_CLK_SDA                                                 
P  NNAMEm1871 UART_PEX0_SDB_TX                                                  
P  NNAMEm1872 CLK_100M_DB800ZL_SSD4_DN                                          
P  NNAMEm1873 CLK_100M_DB2000QL_GPU_REF0_R_DN                                   
P  NNAMEm1874 SMB_CK440_CLK_SCL                                                 
P  NNAMEm1875 GPU_FPGA_EROT_RECOV_N                                             
P  NNAMEm1876 CLK_100M_DB800ZL_SSD4_DP                                          
P  NNAMEm1877 CLK_100M_PEX1_REF_R_DP                                            
P  NNAMEm1878 RST_SSD9_PERST_N                                                  
P  NNAMEm1879 CLK_100M_DB800ZL_SSD3_DN                                          
P  NNAMEm1880 CLK_100M_DB2000QL_GPU_REF0_R_DP                                   
P  NNAMEm1881 PWRGD_P3V3_SSD5                                                   
P  NNAMEm1882 CLK_100M_DB800ZL_SSD3_DP                                          
P  NNAMEm1883 CLK_100M_PEX0_REF_R_DN                                            
P  NNAMEm1884 RST_SSD7_PERST_R_N                                                
P  NNAMEm1885 RST_SSD10_PERST_N                                                 
P  NNAMEm1886 CLK_100M_DB800ZL_SSD2_DN                                          
P  NNAMEm1887 CLK_100M_DB2000QL_GPU_REF2_DN                                     
P  NNAMEm1888 LED_PEX2_SYS_ERR_N                                                
P  NNAMEm1889 RST_GPU_PERST_2_BUF_N                                             
P  NNAMEm1890 PWRGD_P3V3_SSD10_R                                                
P  NNAMEm1891 CLK_100M_DB800ZL_SSD2_DP                                          
P  NNAMEm1892 CLK_100M_PEX0_REF_R_DP                                            
P  NNAMEm1893 CLK_100M_DB2000QL_GPU_REF2_DP                                     
P  NNAMEm1894 SMB_BIC_I2C6_MUX_SSD_0_7_ADC_R_SDA                                
P  NNAMEm1895 PEX2_SYS_ERR_3V3_N                                                
P  NNAMEm1896 RST_GPU_PERST_2_N                                                 
P  NNAMEm1897 PWRGD_P3V3_SSD3                                                   
P  NNAMEm1898 CLK_100M_DB800ZL_SSD1_DN                                          
P  NNAMEm1899 PU_PEX0_ATPG_MODE_L                                               
P  NNAMEm1900 CLK_100M_DB2000QL_GPU_REF1_DN                                     
P  NNAMEm1901 SMB_SSD13_ISO_EN                                                  
P  NNAMEm1902 SMB_BIC_I2C6_MUX_SSD_0_7_ADC_R_SCL                                
P  NNAMEm1903 PEX2_SYS_ERR_N_G                                                  
P  NNAMEm1904 RST_SSD6_PERST_R_N                                                
P  NNAMEm1905 CLK_100M_DB800ZL_SSD1_DP                                          
P  NNAMEm1906 XTAL_CK440_25M_R_XIN                                              
P  NNAMEm1907 CLK_100M_DB2000QL_GPU_REF1_DP                                     
P  NNAMEm1908 SMB_ISO_SSD10_SCL                                                 
P  NNAMEm1909 RST_GPU_PERST_1_BUF_N                                             
P  NNAMEm1910 PWRGD_P3V3_SSD14_R                                                
P  NNAMEm1911 CLK_100M_DB800ZL_SSD0_DN                                          
P  NNAMEm1912 PU_PEX0_PAD_TRI_L                                                 
P  NNAMEm1913 CLK_100M_DB2000QL_GPU_REF0_DN                                     
P  NNAMEm1914 SMB_ISO_SSD12_SDA                                                 
P  NNAMEm1915 RST_GPU_PERST_0_BUF_R_N                                           
P  NNAMEm1916 RST_GPU_PERST_1_R_N                                               
P  NNAMEm1917 CLK_100M_DB800ZL_SSD0_DP                                          
P  NNAMEm1918 CLK_100M_DB2000QL_GPU_REF0_DP                                     
P  NNAMEm1919 SMB_ISO_SSD11_SCL                                                 
P  NNAMEm1920 SMB_GPU_1_R_SCL                                                   
P  NNAMEm1921 RST_GPU_PERST_1_N                                                 
P  NNAMEm1922 SMB_SSD14_ISO_EN                                                  
P  NNAMEm1923 GPU_PEX_STRAP1_R                                                  
P  NNAMEm1924 RST_SSD8_PERST_N                                                  
P  NNAMEm1925 UART_PEX3_SDB_R_TX                                                
P  NNAMEm1926 SMB_ISO_SSD12_SCL                                                 
P  NNAMEm1927 RST_GPU_PERST_0_BUF_N                                             
P  NNAMEm1928 UART_PEX2_SDB_R_TX                                                
P  NNAMEm1929 SMB_SSD15_ISO_EN                                                  
P  NNAMEm1930 SMB_GPU_1_R_SDA                                                   
P  NNAMEm1931 RST_GPU_PERST_0_R_N                                               
P  NNAMEm1932 PWRGD_P12V_SSD8_R                                                 
P  NNAMEm1933 UART_PEX3_SDB_BUF_R_RX                                            
P  NNAMEm1934 SMB_ISO_SSD14_SDA                                                 
P  NNAMEm1935 GPU_BASE_FPGA_READY                                               
P  NNAMEm1936 RST_GPU_PERST_0_N                                                 
P  NNAMEm1937 SMB_ISO_SSD13_SCL                                                 
P  NNAMEm1938 RST_SSD14_PERST_N                                                 
P  NNAMEm1939 UART_PEX2_SDB_BUF_R_RX                                            
P  NNAMEm1940 SMB_SSD9_ISO_EN                                                   
P  NNAMEm1941 PRSNT_SSD13_R_N                                                   
P  NNAMEm1942 UART_PEX1_SDB_R_TX                                                
P  NNAMEm1943 SMB_ISO_SSD13_SDA                                                 
P  NNAMEm1944 PWRGD_P12V_SSD12_R                                                
P  NNAMEm1945 UART_PEX0_SDB_R_TX                                                
P  NNAMEm1946 SMB_ISO_SSD15_SCL                                                 
P  NNAMEm1947 PRSNT_SSD11_R_N                                                   
P  NNAMEm1948 UART_PEX1_SDB_BUF_R_RX                                            
P  NNAMEm1949 SMB_SSD11_ISO_EN                                                  
P  NNAMEm1950 PRSNT_GPU_ISO_R_N                                                 
P  NNAMEm1951 UART_PEX0_SDB_BUF_R_RX                                            
P  NNAMEm1952 SMB_ISO_SSD11_SDA                                                 
P  NNAMEm1953 SMB_ISO_SSD14_SCL                                                 
P  NNAMEm1954 PRSNT_GPU_ISO_N                                                   
P  NNAMEm1955 SMB_SSD12_ISO_EN                                                  
P  NNAMEm1956 SMB_BIC_I2C9_MUX0_SSD7_R_SDA                                      
P  NNAMEm1957 SMB_ISO_SSD15_SDA                                                 
P  NNAMEm1958 USB2_GPU_HMC_DP                                                   
P  NNAMEm1959 PU_CLK_PFT_LOST_N                                                 
P  NNAMEm1960 SMB_BIC_I2C9_MUX0_SSD5_R_SDA                                      
P  NNAMEm1961 SMB_ISO_SSD10_SDA                                                 
P  NNAMEm1962 SMB_BIC_I2C9_MUX0_SSD4_R_SDA                                      
P  NNAMEm1963 SMB_SSD10_ISO_EN                                                  
P  NNAMEm1964 RST_GPU_FPGA_PEX_RST_R_N                                          
P  NNAMEm1965 SMB_BIC_I2C9_MUX0_SSD6_R_SDA                                      
P  NNAMEm1966 SMB_GPU_2_R_SCL                                                   
P  NNAMEm1967 PRSNT_GPU_D_R_N                                                   
P  NNAMEm1968 PWRGD_P3V3_SSD5_R                                                 
P  NNAMEm1969 SMB_BIC_I2C9_MUX0_SSD5_R_SCL                                      
P  NNAMEm1970 SMB_GPU_2_R_SDA                                                   
P  NNAMEm1971 PWRGD_P3V3_SSD7_R                                                 
P  NNAMEm1972 SMB_BIC_I2C9_MUX0_SSD4_R_SCL                                      
P  NNAMEm1973 GPU_PWR_BRAKE_R_N                                                 
P  NNAMEm1974 SMB_BIC_I2C9_MUX0_SSD7_R_SCL                                      
P  NNAMEm1975 GPU_THERM_OVERT_N                                                 
P  NNAMEm1976 RST_SSD0_PERST_N                                                  
P  NNAMEm1977 NIC0_MAIN_PWR_BIC_EN                                              
P  NNAMEm1978 SMB_BIC_I2C9_MUX0_SSD6_R_SCL                                      
P  NNAMEm1979 JP_FPGA_FRC_PWRON_N                                               
P  NNAMEm1980 PRSNT_NIC3_FPGA_N                                                 
P  NNAMEm1981 SMB_BIC_I2C9_MUX0_SSD4_SCL                                        
P  NNAMEm1982 PWRGD_P3V3_SSD4_R                                                 
P  NNAMEm1983 UART_PEX3_SDB_BUF_RX                                              
P  NNAMEm1984 SMB_BIC_I2C9_MUX0_SSD7_SCL                                        
P  NNAMEm1985 NIC2_MAIN_PWR_BIC_EN                                              
P  NNAMEm1986 SMB_BIC_I2C9_MUX0_SSD7_SDA                                        
P  NNAMEm1987 NIC3_PEX_PWR_EN_R                                                 
P  NNAMEm1988 UART_PEX2_SDB_BUF_RX                                              
P  NNAMEm1989 SMB_BIC_I2C9_MUX0_SSD6_SDA                                        
P  NNAMEm1990 SMB_ISO_SSD9_SDA                                                  
P  NNAMEm1991 GPU_PEX_STRAP0_R                                                  
P  NNAMEm1992 SMB_PEX1_FPGA_SDA                                                 
P  NNAMEm1993 SMB_BIC_I2C9_MUX0_SSD5_SDA                                        
P  NNAMEm1994 USB2_GPU_HMC_DN                                                   
P  NNAMEm1995 RST_SSD7_PERST_N                                                  
P  NNAMEm1996 RST_PEX_NIC2_PERST_R_N                                            
P  NNAMEm1997 SMB_BIC_I2C9_MUX0_SSD4_SDA                                        
P  NNAMEm1998 RST_MB_PERST_1_ISO_N                                              
P  NNAMEm1999 SMB_PEX3_FPGA_SCL                                                 
P  NNAMEm2000 NIC7_MAIN_PWR_EN                                                  
P  NNAMEm2001 PWRGD_P12V_SSD9                                                   
P  NNAMEm2002 SMB_BIC_I2C9_MUX0_SSD6_SCL                                        
P  NNAMEm2003 RST_MB_PERST_1_ISO_R_N                                            
P  NNAMEm2004 PWRGD_P3V3_SSD3_R                                                 
P  NNAMEm2005 XTAL_CK440_25M_XOUT                                               
P  NNAMEm2006 SMB_BIC_I2C9_MUX0_SSD5_SCL                                        
P  NNAMEm2007 SMB_PEX1_FPGA_SCL                                                 
P  NNAMEm2008 PWRGD_P12V_SSD15                                                  
P  NNAMEm2009 SMB_BIC_I2C9_MUX0_SSD0_SDA                                        
P  NNAMEm2010 RST_MB_PERST_0_ISO_N                                              
P  NNAMEm2011 NIC4_PEX_PWR_EN_R                                                 
P  NNAMEm2012 XTAL_CK440_25M_XIN                                                
P  NNAMEm2013 SMB_BIC_I2C9_MUX0_SSD3_SCL                                        
P  NNAMEm2014 RST_MB_PERST_0_ISO_R_N                                            
P  NNAMEm2015 BIC_SYS_READY_R1_N                                                
P  NNAMEm2016 SMB_PEX0_FPGA_SDA                                                 
P  NNAMEm2017 NIC0_PEX_PWR_EN_R                                                 
P  NNAMEm2018 FT4232_SDB_EEPROM_R_SDA                                           
P  NNAMEm2019 CLK_GEN_CK440_OE3_N                                               
P  NNAMEm2020 SMB_BIC_I2C9_MUX0_SSD2_SCL                                        
P  NNAMEm2021 RST_SSD6_PERST_N                                                  
P  NNAMEm2022 UART_PEX1_SDB_BUF_RX                                              
P  NNAMEm2023 FT4232_SDB_EEPROM_R_SCL                                           
P  NNAMEm2024 CLK_GEN_CK440_OE6_N                                               
P  NNAMEm2025 SMB_BIC_I2C9_MUX0_SSD2_SDA                                        
P  NNAMEm2026 RST_PEX_NIC0_PERST_R_N                                            
P  NNAMEm2027 FT4232_SDB_EEPROM_R_CS                                            
P  NNAMEm2028 CLK_GEN_CK440_OE5_N                                               
P  NNAMEm2029 SMB_BIC_I2C9_MUX0_SSD0_SCL                                        
P  NNAMEm2030 PWRGD_P12V_SSD5_R                                                 
P  NNAMEm2031 RST_PEX_NIC3_PERST_R_N                                            
P  NNAMEm2032 PWRGD_P12V_SSD11                                                  
P  NNAMEm2033 UART_PEX0_SDB_BUF_RX                                              
P  NNAMEm2034 FT4232_SDB_EEPROM_DO                                              
P  NNAMEm2035 CLK_GEN_CK440_OE4_N                                               
P  NNAMEm2036 SMB_BIC_I2C9_MUX0_SSD1_SCL                                        
P  NNAMEm2037 RST_SSD3_PERST_N                                                  
P  NNAMEm2038 PRSNT_NIC0_FPGA_N                                                 
P  NNAMEm2039 P3V3_PEX_USB_HUB                                                  
P  NNAMEm2040 SMB_BIC_I2C9_MUX0_SSD1_SDA                                        
P  NNAMEm2041 NIC2_PEX_PWR_EN_R                                                 
P  NNAMEm2042 SMB_BIC_I2C9_MUX0_SSD3_SDA                                        
P  NNAMEm2043 PWRGD_P3V3_SSD2_R                                                 
P  NNAMEm2044 PWRGD_P12V_SSD13                                                  
P  NNAMEm2045 SMB_BIC_I2C9_MUX0_SSD2_R_SDA                                      
P  NNAMEm2046 UART_PEX3_SDB_R_RX                                                
P  NNAMEm2047 FT4232_SDB_EEPROM_CS                                              
P  NNAMEm2048 SMB_BIC_I2C9_MUX0_SSD0_R_SCL                                      
P  NNAMEm2049 PWRGD_P12V_SSD1_R                                                 
P  NNAMEm2050 PWRGD_NIC7_PWR_GOOD_R                                             
P  NNAMEm2051 UART_PEX2_SDB_R_RX                                                
P  NNAMEm2052 SMB_NIC4_LS_SDA                                                   
P  NNAMEm2053 SMB_BIC_I2C9_MUX0_SSD3_R_SCL                                      
P  NNAMEm2054 SMB_PEX0_FPGA_SCL                                                 
P  NNAMEm2055 RST_NIC6_PERST_N                                                  
P  NNAMEm2056 SMB_BIC_I2C9_MUX0_SSD1_R_SCL                                      
P  NNAMEm2057 SMB_ISO_SSD9_SCL                                                  
P  NNAMEm2058 SMB_FPGA_ALERT_N                                                  
P  NNAMEm2059 RST_PEX_NIC5_PERST_R_N                                            
P  NNAMEm2060 FT4232_SDB_EEPROM_SCL                                             
P  NNAMEm2061 SMB_NIC4_LS_SCL                                                   
P  NNAMEm2062 SMB_BIC_I2C9_MUX0_SSD2_R_SCL                                      
P  NNAMEm2063 PWRGD_P12V_SSD6_R                                                 
P  NNAMEm2064 PWRGD_P3V3_NIC6_R                                                 
P  NNAMEm2065 UART_PEX1_SDB_R_RX                                                
P  NNAMEm2066 FT4232_SDB_EEPROM_SDA                                             
P  NNAMEm2067 SMB_BIC_I2C9_MUX0_SSD1_R_SDA                                      
P  NNAMEm2068 RST_SSD4_PERST_N                                                  
P  NNAMEm2069 RST_NIC7_PERST_N                                                  
P  NNAMEm2070 UART_PEX0_SDB_R_RX                                                
P  NNAMEm2071 SMB_BIC_I2C9_MUX0_SSD0_R_SDA                                      
P  NNAMEm2072 FM_SOL_UART_CH_SEL_R                                              
P  NNAMEm2073 RST_PEX_NIC4_PERST_R_N                                            
P  NNAMEm2074 CLK_100M_DB800ZL_SSD13_R_DN                                       
P  NNAMEm2075 SMB_BIC_I2C9_MUX0_SSD3_R_SDA                                      
P  NNAMEm2076 NIC3_MAIN_PWR_BIC_EN                                              
P  NNAMEm2077 CLK_100M_DB800ZL_SSD13_R_DP                                       
P  NNAMEm2078 TP_CLK_PFT_IN_DN                                                  
P  NNAMEm2079 SMB_BIC_I2C9_MUX1_SSD12_SDA                                       
P  NNAMEm2080 SMB_PEX3_FPGA_SDA                                                 
P  NNAMEm2081 PWRGD_NIC6_PWR_GOOD_R                                             
P  NNAMEm2082 CLK_100M_DB800ZL_SSD8_R_DP                                        
P  NNAMEm2083 TP_CLK_PFT_IN_DP                                                  
P  NNAMEm2084 SMB_BIC_I2C9_MUX1_SSD13_SCL                                       
P  NNAMEm2085 PRSNT_NIC1_FPGA_N                                                 
P  NNAMEm2086 CLK_100M_DB800ZL_SSD9_R_DP                                        
P  NNAMEm2087 SMB_BIC_I2C9_MUX1_SSD13_SDA                                       
P  NNAMEm2088 SMB_PEX2_FPGA_SDA                                                 
P  NNAMEm2089 UART_PEX3_CLI_R_TX                                                
P  NNAMEm2090 CLK_100M_DB800ZL_SSD11_R_DP                                       
P  NNAMEm2091 SMB_BIC_I2C9_MUX1_SSD15_SCL                                       
P  NNAMEm2092 PRSNT_NIC5_FPGA_N                                                 
P  NNAMEm2093 PWRGD_P12V_SSD14                                                  
P  NNAMEm2094 RST_FT4232_SDB_R_N                                                
P  NNAMEm2095 UART_PEX3_CLI_TX                                                  
P  NNAMEm2096 CLK_100M_DB800ZL_SSD9_R_DN                                        
P  NNAMEm2097 PEX0_SYS_ERR_R_N                                                  
P  NNAMEm2098 SMB_BIC_I2C9_MUX1_SSD12_SCL                                       
P  NNAMEm2099 PWRGD_P3V3_SSD1_R                                                 
P  NNAMEm2100 NIC4_MAIN_PWR_BIC_EN                                              
P  NNAMEm2101 CLK_100M_DB800ZL_SSD11_R_DN                                       
P  NNAMEm2102 SMB_BIC_I2C9_MUX1_SSD15_SDA                                       
P  NNAMEm2103 PWRGD_P3V3_SSD6_R                                                 
P  NNAMEm2104 CLK_100M_DB800ZL_SSD15_R_DP                                       
P  NNAMEm2105 SMB_BIC_I2C9_MUX1_SSD14_SDA                                       
P  NNAMEm2106 PRSNT_NIC4_FPGA_N                                                 
P  NNAMEm2107 CLK_100M_DB800ZL_SSD14_R_DP                                       
P  NNAMEm2108 SMB_BIC_I2C9_MUX1_SSD14_SCL                                       
P  NNAMEm2109 PWRGD_P12V_SSD4_R                                                 
P  NNAMEm2110 PWRGD_P12V_SSD12                                                  
P  NNAMEm2111 UART_PEX2_CLI_R_TX                                                
P  NNAMEm2112 CLK_100M_DB800ZL_SSD10_R_DN                                       
P  NNAMEm2113 SMB_BIC_I2C9_MUX1_SSD14_R_SDA                                     
P  NNAMEm2114 NIC5_PEX_PWR_EN_R                                                 
P  NNAMEm2115 UART_PEX3_SDB_BUF_TX                                              
P  NNAMEm2116 UART_PEX2_CLI_TX                                                  
P  NNAMEm2117 CLK_100M_DB800ZL_SSD12_R_DN                                       
P  NNAMEm2118 SMB_BIC_I2C9_MUX1_SSD15_R_SCL                                     
P  NNAMEm2119 PWRGD_P12V_SSD3_R                                                 
P  NNAMEm2120 NIC7_AUX_PWR_EN                                                   
P  NNAMEm2121 CLK_100M_DB800ZL_SSD12_R_DP                                       
P  NNAMEm2122 SMB_BIC_I2C9_MUX1_SSD12_R_SDA                                     
P  NNAMEm2123 PWRGD_P12V_SSD2_R                                                 
P  NNAMEm2124 NIC6_MAIN_PWR_EN                                                  
P  NNAMEm2125 UART_PEX2_SDB_BUF_TX                                              
P  NNAMEm2126 CLK_100M_DB800ZL_SSD8_R_DN                                        
P  NNAMEm2127 PU_PEX2_PAD_TRI_L                                                 
P  NNAMEm2128 SMB_BIC_I2C9_MUX1_SSD12_R_SCL                                     
P  NNAMEm2129 UART_PEX3_CLI_BUF_TX                                              
P  NNAMEm2130 CLK_100M_DB800ZL_SSD14_R_DN                                       
P  NNAMEm2131 SMB_BIC_I2C9_MUX1_SSD13_R_SCL                                     
P  NNAMEm2132 NIC6_AUX_PWR_EN                                                   
P  NNAMEm2133 UART_PEX1_SDB_BUF_TX                                              
P  NNAMEm2134 CLK_100M_DB800ZL_SSD10_R_DP                                       
P  NNAMEm2135 SMB_BIC_I2C9_MUX1_SSD14_R_SCL                                     
P  NNAMEm2136 NIC5_MAIN_PWR_BIC_EN                                              
P  NNAMEm2137 CLK_100M_DB800ZL_SSD15_R_DN                                       
P  NNAMEm2138 PU_PEX2_ATPG_MODE_L                                               
P  NNAMEm2139 SMB_BIC_I2C9_MUX1_SSD13_R_SDA                                     
P  NNAMEm2140 PRSNT_NIC2_FPGA_N                                                 
P  NNAMEm2141 UART_PEX0_SDB_BUF_TX                                              
P  NNAMEm2142 UART_PEX2_CLI_BUF_TX                                              
P  NNAMEm2143 SMB_BIC_I2C9_MUX1_SSD15_R_SDA                                     
P  NNAMEm2144 RST_PEX_NIC1_PERST_R_N                                            
P  NNAMEm2145 PWRGD_P12V_SSD10                                                  
P  NNAMEm2146 SMB_BIC_I2C9_MUX1_SSD10_SCL                                       
P  NNAMEm2147 RST_SSD5_PERST_N                                                  
P  NNAMEm2148 UART_PEX3_SDB_RX                                                  
P  NNAMEm2149 UART_PEX3_CLI_BUF_R_RX                                            
P  NNAMEm2150 SMB_BIC_I2C9_MUX1_SSD9_SDA                                        
P  NNAMEm2151 RST_SSD2_PERST_N                                                  
P  NNAMEm2152 PWRGD_P3V3_NIC7_R                                                 
P  NNAMEm2153 UART_PEX3_CLI_BUF_RX                                              
P  NNAMEm2154 SMB_BIC_I2C9_MUX1_SSD11_SDA                                       
P  NNAMEm2155 PWRGD_P12V_SSD7_R                                                 
P  NNAMEm2156 NIC1_MAIN_PWR_BIC_EN                                              
P  NNAMEm2157 UART_PEX2_SDB_RX                                                  
P  NNAMEm2158 SMB_BIC_I2C9_MUX1_SSD8_SDA                                        
P  NNAMEm2159 NIC1_PEX_PWR_EN_R                                                 
P  NNAMEm2160 UART_PEX2_CLI_BUF_R_RX                                            
P  NNAMEm2161 SMB_BIC_I2C9_MUX1_SSD9_SCL                                        
P  NNAMEm2162 MB_BIC_MON_BUF_R                                                  
P  NNAMEm2163 RST_SSD1_PERST_N                                                  
P  NNAMEm2164 UART_PEX1_SDB_RX                                                  
P  NNAMEm2165 UART_PEX2_CLI_BUF_RX                                              
P  NNAMEm2166 SMB_BIC_I2C9_MUX1_SSD10_SDA                                       
P  NNAMEm2167 PWRGD_P3V3_NIC3                                                   
P  NNAMEm2168 SMB_BIC_I2C9_MUX1_SSD8_SCL                                        
P  NNAMEm2169 RST_MB_BMC_BUF_N                                                  
P  NNAMEm2170 UART_PEX0_SDB_RX                                                  
P  NNAMEm2171 UART_PEX3_CLI_R_RX                                                
P  NNAMEm2172 PEX2_SYS_ERR_R_N                                                  
P  NNAMEm2173 PEX3_ADCTEMP_VINP1                                                
P  NNAMEm2174 SMB_BIC_I2C9_MUX1_SSD11_SCL                                       
P  NNAMEm2175 PWRGD_P12V_SSD8                                                   
P  NNAMEm2176 UART_PEX3_CLI_RX                                                  
P  NNAMEm2177 P3V3_CLK_BUFFER_9ZXL0451E_VZX3P3                                  
P  NNAMEm2178 PEX3_ADCTEMP_VINP0                                                
P  NNAMEm2179 SMB_BIC_I2C9_MUX1_SSD8_R_SDA                                      
P  NNAMEm2180 P3V3_CLK_BUFFER_9ZXL0451E_VZX3P3A                                 
P  NNAMEm2181 SMB_BIC_I2C9_MUX1_SSD10_R_SDA                                     
P  NNAMEm2182 MB_BIC_READY_BUF_R_N                                              
P  NNAMEm2183 UART_PEX2_CLI_R_RX                                                
P  NNAMEm2184 SMB_BIC_I2C9_MUX1_SSD9_R_SDA                                      
P  NNAMEm2185 MB_BIC_READY_BUF_N                                                
P  NNAMEm2186 SMB_PEX2_FPGA_SCL                                                 
P  NNAMEm2187 PWRGD_P3V3_NIC6                                                   
P  NNAMEm2188 UART_PEX2_CLI_RX                                                  
P  NNAMEm2189 SMB_BIC_I2C9_MUX1_SSD11_R_SDA                                     
P  NNAMEm2190 SMB_BIC_I2C9_MUX1_SSD10_R_SCL                                     
P  NNAMEm2191 RST_MB_BMC_BUF_R_N                                                
P  NNAMEm2192 UART_PEX1_CLI_R_TX                                                
P  NNAMEm2193 CLK_BUFFER_9ZXL0851E_8_15_OE2_N                                   
P  NNAMEm2194 SMB_BIC_I2C9_MUX1_SSD9_R_SCL                                      
P  NNAMEm2195 UART_PEX1_CLI_TX                                                  
P  NNAMEm2196 CLK_BUFFER_9ZXL0851E_0_7_OE1_N                                    
P  NNAMEm2197 SMB_BIC_I2C9_MUX1_SSD11_R_SCL                                     
P  NNAMEm2198 SYS_PWR_READY_N                                                   
P  NNAMEm2199 CLK_100M_DB800ZL_SSD13_DN                                         
P  NNAMEm2200 PEX2_MODE_SEL10                                                   
P  NNAMEm2201 SMB_BIC_I2C9_MUX1_SSD8_R_SCL                                      
P  NNAMEm2202 GPU_BASE_PWR_GD                                                   
P  NNAMEm2203 UART_PEX0_CLI_R_TX                                                
P  NNAMEm2204 CLK_100M_DB800ZL_SSD10_DP                                         
P  NNAMEm2205 SMB_BIC_I2C9_SSD_MUX0_SCL                                         
P  NNAMEm2206 UART_PEX0_CLI_TX                                                  
P  NNAMEm2207 CLK_100M_DB800ZL_SSD11_DN                                         
P  NNAMEm2208 PEX2_ADCTEMP_VINP0                                                
P  NNAMEm2209 SMB_BIC_I2C9_SSD_MUX0_SDA                                         
P  NNAMEm2210 CLK_100M_DB800ZL_SSD9_DP                                          
P  NNAMEm2211 PEX2_MODE_SEL11                                                   
P  NNAMEm2212 PEX2_ADCTEMP_VINP1                                                
P  NNAMEm2213 SMB_BIC_I2C9_SSD_MUX1_SCL                                         
P  NNAMEm2214 CLK_100M_DB800ZL_SSD8_DP                                          
P  NNAMEm2215 RST_BIC_I2C9_SSD_MUX1_R_N                                         
P  NNAMEm2216 SMB_BIC_I2C9_SSD_MUX1_SDA                                         
P  NNAMEm2217 UART_PEX1_CLI_BUF_TX                                              
P  NNAMEm2218 FM_DB2000QL_VSBEN                                                 
P  NNAMEm2219 CLK_100M_DB800ZL_SSD14_DN                                         
P  NNAMEm2220 SMB_BIC_I2C9_SSD_MUX_SDA                                          
P  NNAMEm2221 RST_GPU_PERST_1_BUF_R_N                                           
P  NNAMEm2222 CLK_100M_DB800ZL_SSD12_DP                                         
P  NNAMEm2223 SMB_BIC_I2C9_SSD_MUX_SCL                                          
P  NNAMEm2224 FPGA_HEARTBEAT_N                                                  
P  NNAMEm2225 CLK_100M_DB800ZL_SSD8_DN                                          
P  NNAMEm2226 PU_9ZXL0451E_HBW                                                  
P  NNAMEm2227 PEX2_MODE_SEL12                                                   
P  NNAMEm2228 SMB_BIC_I2C9_SSD_MUX_R_SCL                                        
P  NNAMEm2229 GPU_BASE_PWR_EN_R                                                 
P  NNAMEm2230 UART_PEX0_CLI_BUF_TX                                              
P  NNAMEm2231 CLK_100M_DB800ZL_SSD9_DN                                          
P  NNAMEm2232 SMB_BIC_I2C9_SSD_MUX_R_SDA                                        
P  NNAMEm2233 SMB_ISO_SSD1_R_SCL                                                
P  NNAMEm2234 FM_DB2000QL_SMB_SA0                                               
P  NNAMEm2235 CLK_100M_DB800ZL_SSD11_DP                                         
P  NNAMEm2236 BIC_I2C9_SSD_MUX1_A2                                              
P  NNAMEm2237 SMB_ISO_SSD7_R_SCL                                                
P  NNAMEm2238 UART_PEX1_CLI_BUF_R_RX                                            
P  NNAMEm2239 CLK_100M_DB800ZL_SSD12_DN                                         
P  NNAMEm2240 CLK_BUFFER_DB2000QL_OE0_N                                         
P  NNAMEm2241 BIC_I2C9_SSD_MUX1_A1                                              
P  NNAMEm2242 SMB_SSD8_ISO_EN                                                   
P  NNAMEm2243 SMB_ISO_SSD6_R_SCL                                                
P  NNAMEm2244 PWRGD_P3V3_NIC2                                                   
P  NNAMEm2245 UART_PEX1_CLI_BUF_RX                                              
P  NNAMEm2246 FM_DB2000QL_SMB_SA1                                               
P  NNAMEm2247 CLK_100M_DB800ZL_SSD15_DP                                         
P  NNAMEm2248 CLK_100M_MB_0_R_DN                                                
P  NNAMEm2249 BIC_I2C9_SSD_MUX1_A0                                              
P  NNAMEm2250 SMB_ISO_SSD8_SCL                                                  
P  NNAMEm2251 SMB_ISO_SSD2_R_SCL                                                
P  NNAMEm2252 CLK_100M_DB800ZL_SSD10_DN                                         
P  NNAMEm2253 FM_CK440Q_DEV_25M_EN                                              
P  NNAMEm2254 PEX1_ADCTEMP_VINP1                                                
P  NNAMEm2255 SMB_ISO_SSD8_SDA                                                  
P  NNAMEm2256 SMB_ISO_SSD7_R_SDA                                                
P  NNAMEm2257 UART_PEX0_CLI_BUF_R_RX                                            
P  NNAMEm2258 SPI_BIC1_CLK_LS23_DIR2                                            
P  NNAMEm2259 CLK_100M_DB800ZL_SSD14_DP                                         
P  NNAMEm2260 CLK_100M_CK440Q_0_DB2000QL_DN                                     
P  NNAMEm2261 CLK_CK440_SMB_ADDR1                                               
P  NNAMEm2262 CLK_100M_MB_0_R_DP                                                
P  NNAMEm2263 PEX1_ADCTEMP_VINP0                                                
P  NNAMEm2264 SMB_ISO_SSD3_R_SDA                                                
P  NNAMEm2265 UART_PEX0_CLI_BUF_RX                                              
P  NNAMEm2266 FT4232_CLI_EEPROM_R_SDA                                           
P  NNAMEm2267 SPI_BIC1_CS0_LS23_N_DIR1                                          
P  NNAMEm2268 CLK_100M_DB800ZL_SSD13_DP                                         
P  NNAMEm2269 SMB_ISO_SSD3_R_SCL                                                
P  NNAMEm2270 SPI_BIC1_MOSI_LS23_DIR3                                           
P  NNAMEm2271 CLK_100M_DB800ZL_SSD15_DN                                         
P  NNAMEm2272 CLK_100M_CK440Q_0_DB2000QL_DP                                     
P  NNAMEm2273 CLK_CK440_SMB_ADDR0                                               
P  NNAMEm2274 SMB_ISO_SSD0_R_SCL                                                
P  NNAMEm2275 UART_PEX1_CLI_R_RX                                                
P  NNAMEm2276 FT4232_CLI_EEPROM_R_CS                                            
P  NNAMEm2277 SPI_BIC1_MISO_LS23_DIR4                                           
P  NNAMEm2278 SMB_9ZXL0451E_ADDR0                                               
P  NNAMEm2279 SMB_ISO_SSD4_R_SCL                                                
P  NNAMEm2280 RST_GPU_PERST_2_BUF_R_N                                           
P  NNAMEm2281 PWRGD_P3V3_NIC5                                                   
P  NNAMEm2282 UART_PEX1_CLI_RX                                                  
P  NNAMEm2283 FT4232_CLI_EEPROM_R_SCL                                           
P  NNAMEm2284 CLK_100M_CK440Q_2_DB800ZL_R_DN                                    
P  NNAMEm2285 SMB_ISO_SSD0_R_SDA                                                
P  NNAMEm2286 PWRGD_P3V3_AUX_MUX_N                                              
P  NNAMEm2287 FT4232_CLI_EEPROM_DO                                              
P  NNAMEm2288 SMB_ISO_SSD2_R_SDA                                                
P  NNAMEm2289 UART_PEX0_CLI_RX                                                  
P  NNAMEm2290 RST_FT4232_CLI_R_N                                                
P  NNAMEm2291 P3V3_DB2000QL_FB_VDD                                              
P  NNAMEm2292 CLK_100M_CK440Q_2_DB800ZL_R_DP                                    
P  NNAMEm2293 PU_CK440_SHFT_LD_N                                                
P  NNAMEm2294 FM_CLK_CK440_SS_EN                                                
P  NNAMEm2295 SMB_ISO_SSD5_R_SCL                                                
P  NNAMEm2296 P3V3_DB2000QL_VDDR                                                
P  NNAMEm2297 SMB_ISO_SSD4_R_SDA                                                
P  NNAMEm2298 USB2_FT4232_MUX_D_DN                                              
P  NNAMEm2299 FT4232_CLI_EEPROM_SDA                                             
P  NNAMEm2300 P3V3_DB2000QL_VDD                                                 
P  NNAMEm2301 TP_CK440_SBI_DATA_OUT                                             
P  NNAMEm2302 SMB_ISO_SSD6_R_SDA                                                
P  NNAMEm2303 FT4232_CLI_EEPROM_SCL                                             
P  NNAMEm2304 P3V3_DB2000QL_VDDA                                                
P  NNAMEm2305 PD_CK440_SBI_DATA_IN                                              
P  NNAMEm2306 PEX0_ADCTEMP_VINP0                                                
P  NNAMEm2307 SMB_ISO_SSD5_R_SDA                                                
P  NNAMEm2308 USB2_FT4232_MUX_D_DP                                              
P  NNAMEm2309 FT4232_CLI_EEPROM_CS                                              
P  NNAMEm2310 CLK_100M_DB2000QL_NIC0_R_DP                                       
P  NNAMEm2311 PEX0_ADCTEMP_VINP1                                                
P  NNAMEm2312 SMB_ISO_SSD1_R_SDA                                                
P  NNAMEm2313 CLK_100M_DB2000QL_NIC3_R_DP                                       
P  NNAMEm2314 PD_CK440_SBI_CLK                                                  
P  NNAMEm2315 CLK_100M_DB2000QL_NIC4_R_DN                                       
P  NNAMEm2316 GPU_HGX_DETECT_N                                                  
P  NNAMEm2317 CLK_100M_DB2000QL_NIC3_R_DN                                       
P  NNAMEm2318 FM_CK440_MXCK_25M_100M                                            
P  NNAMEm2319 CLK_100M_GPU_FPGA_REF_DP                                          
P  NNAMEm2320 CLK_100M_DB2000QL_NIC7_R_DP                                       
P  NNAMEm2321 TP_CLK_100M_MB_2_DP                                               
P  NNAMEm2322 CLK_100M_DB2000QL_NIC0_R_DN                                       
P  NNAMEm2323 CLK_100M_DB2000QL_NIC2_R_DN                                       
P  NNAMEm2324 SMB_BIC_FPGA_SDA                                                  
P  NNAMEm2325 P2E_GPU_FPGA_PEX_TX_DP<0>                                         
P  NNAMEm2326 CLK_100M_DB2000QL_NIC5_R_DN                                       
P  NNAMEm2327 CLK_100M_DB800ZL_PEX0_S0_DP                                       
P  NNAMEm2328 CLK_100M_DB2000QL_NIC1_R_DP                                       
P  NNAMEm2329 PU_9ZXL0851_8_15_HBW                                              
P  NNAMEm2330 CLK_100M_DB800ZL_PEX3_S0_DN                                       
P  NNAMEm2331 SMB_BIC_FPGA_SCL                                                  
P  NNAMEm2332 P2E_GPU_FPGA_PEX_RX_DP<0>                                         
P  NNAMEm2333 CLK_100M_DB2000QL_NIC7_R_DN                                       
P  NNAMEm2334 CLK_100M_DB800ZL_PEX1_S0_DP                                       
P  NNAMEm2335 CLK_100M_DB2000QL_NIC1_R_DN                                       
P  NNAMEm2336 PU_9ZXL0851_8_15_100M                                             
P  NNAMEm2337 CLK_100M_DB800ZL_PEX2_S0_DN                                       
P  NNAMEm2338 CLK_100M_DB2000QL_NIC2_R_DP                                       
P  NNAMEm2339 CLK_100M_DB800ZL_PEX0_S0_DN                                       
P  NNAMEm2340 PWRGD_P3V3_NIC1                                                   
P  NNAMEm2341 CLK_100M_DB2000QL_NIC4_R_DP                                       
P  NNAMEm2342 CLK_100M_DB800ZL_PEX1_S0_DN                                       
P  NNAMEm2343 CLK_100M_MB_0_DP                                                  
P  NNAMEm2344 CLK_100M_DB2000QL_NIC6_R_DN                                       
P  NNAMEm2345 CLK_100M_DB800ZL_PEX2_S0_DP                                       
P  NNAMEm2346 RST_GPU_FPGA_PEX_RST_N                                            
P  NNAMEm2347 CLK_100M_DB2000QL_NIC5_R_DP                                       
P  NNAMEm2348 P3V3_CLK_GEN_VDDA100M_CK440                                       
P  NNAMEm2349 CLK_100M_DB800ZL_PEX3_S0_DP                                       
P  NNAMEm2350 GPU_THERM_OVERT_R_N                                               
P  NNAMEm2351 PWRGD_NIC5_PWR_GOOD_R                                             
P  NNAMEm2352 CLK_100M_DB2000QL_NIC6_R_DP                                       
P  NNAMEm2353 P3V3_CLK_GEN_VDD_CK440                                            
P  NNAMEm2354 CLK_100M_DB800ZL_PEX3_S0_R_DP                                     
P  NNAMEm2355 PWRGD_P3V3_NIC7                                                   
P  NNAMEm2356 P3V3_CLK_GEN_VDDPT_CK440                                          
P  NNAMEm2357 PWRGD_P3V3_NIC1_R                                                 
P  NNAMEm2358 P3V3_CLK_GEN_VDDMXCK_CK440                                        
P  NNAMEm2359 CLK_100M_DB800ZL_PEX3_S0_R_DN                                     
P  NNAMEm2360 RST_NIC2_PERST_N                                                  
P  NNAMEm2361 PWRGD_P3V3_AUX_MUX_R_N                                            
P  NNAMEm2362 P3V3_VDD_9ZXL0851_8_15                                            
P  NNAMEm2363 CLK_100M_DB800ZL_PEX2_S0_R_DN                                     
P  NNAMEm2364 PEX_USB_HUB_PGANG                                                 
P  NNAMEm2365 P3V3_VDDAR_9ZXL0851_8_15                                          
P  NNAMEm2366 CLK_100M_DB800ZL_PEX2_S0_R_DP                                     
P  NNAMEm2367 NIC0_MAIN_PWR_EN                                                  
P  NNAMEm2368 NIC5_MAIN_PWR_EN                                                  
P  NNAMEm2369 PWRGD_P3V3_NIC4                                                   
P  NNAMEm2370 CLK_100M_DB800ZL_PEX1_S0_R_DN                                     
P  NNAMEm2371 PWRGD_NIC0_PWR_GOOD_R                                             
P  NNAMEm2372 PWRGD_P3V3_NIC5_R                                                 
P  NNAMEm2373 CLK_100M_DB800ZL_PEX1_S0_R_DP                                     
P  NNAMEm2374 NIC0_AUX_PWR_EN                                                   
P  NNAMEm2375 CLK_100M_DB800ZL_PEX0_S0_R_DN                                     
P  NNAMEm2376 CLK_100M_DB800ZL_PEX0_S0_R_DP                                     
P  NNAMEm2377 RST_NIC4_PERST_N                                                  
P  NNAMEm2378 CLK_100M_DB2000QL_NIC5_DN                                         
P  NNAMEm2379 SMB_NIC7_LS_SDA                                                   
P  NNAMEm2380 NIC5_AUX_PWR_EN                                                   
P  NNAMEm2381 CLK_100M_DB2000QL_NIC7_DP                                         
P  NNAMEm2382 PWRGD_NIC4_PWR_GOOD_R                                             
P  NNAMEm2383 CLK_100M_DB2000QL_NIC7_DN                                         
P  NNAMEm2384 SMB_NIC7_LS_SCL                                                   
P  NNAMEm2385 NIC4_AUX_PWR_EN                                                   
P  NNAMEm2386 CLK_100M_DB2000QL_NIC4_DP                                         
P  NNAMEm2387 GPU_3V3IO_RSVD4                                                   
P  NNAMEm2388 SPI_BIC1_MISO_LS01_DIR4                                           
P  NNAMEm2389 CLK_100M_DB2000QL_NIC4_DN                                         
P  NNAMEm2390 CLK_100M_DB2000QL_NIC5_DP                                         
P  NNAMEm2391 LED_PEX1_SYS_ERR_N                                                
P  NNAMEm2392 SMB_NIC6_LS_SDA                                                   
P  NNAMEm2393 GPU_WP_HW_CTRL_R_N                                                
P  NNAMEm2394 NIC3_AUX_PWR_EN                                                   
P  NNAMEm2395 PEX_USB_HUB_RREF                                                  
P  NNAMEm2396 SPI_BIC1_MOSI_LS01_DIR3                                           
P  NNAMEm2397 CLK_100M_DB2000QL_NIC6_DN                                         
P  NNAMEm2398 PEX1_SYS_ERR_3V3_N                                                
P  NNAMEm2399 CLK_100M_DB2000QL_NIC6_DP                                         
P  NNAMEm2400 PEX1_SYS_ERR_N_G                                                  
P  NNAMEm2401 SMB_NIC6_LS_SCL                                                   
P  NNAMEm2402 PWRGD_NIC3_PWR_GOOD_R                                             
P  NNAMEm2403 SPI_BIC1_CLK_LS01_DIR2                                            
P  NNAMEm2404 GPU_3V3IO_RSVD3                                                   
P  NNAMEm2405 NIC4_MAIN_PWR_EN                                                  
P  NNAMEm2406 BIC_I2C9_SSD_MUX0_A2                                              
P  NNAMEm2407 GPU_BASE_FPGA_READY_R                                             
P  NNAMEm2408 USB2_PEX_HUB_DN                                                   
P  NNAMEm2409 SPI_BIC1_CS0_LS01_N_DIR1                                          
P  NNAMEm2410 SMB_NIC5_LS_SDA                                                   
P  NNAMEm2411 GPU_3V3IO_RSVD1                                                   
P  NNAMEm2412 BIC_I2C9_SSD_MUX0_A1                                              
P  NNAMEm2413 PWRGD_NIC1_PWR_GOOD_R                                             
P  NNAMEm2414 USB2_PEX_HUB_DP                                                   
P  NNAMEm2415 SMB_NIC5_LS_SCL                                                   
P  NNAMEm2416 SMB_SSD7_ISO_EN                                                   
P  NNAMEm2417 NIC1_MAIN_PWR_EN                                                  
P  NNAMEm2418 BIC_I2C9_SSD_MUX0_A0                                              
P  NNAMEm2419 SMB_ISO_SSD7_SCL                                                  
P  NNAMEm2420 P2E_GPU_FPGA_PEX_TX_DN<0>                                         
P  NNAMEm2421 NIC3_MAIN_PWR_EN                                                  
P  NNAMEm2422 USB2_PEX_HUB_R_DN                                                 
P  NNAMEm2423 SMB_ISO_SSD7_SDA                                                  
P  NNAMEm2424 USB2_PEX_HUB_R_DP                                                 
P  NNAMEm2425 CLK_100M_DB2000QL_NIC3_DN                                         
P  NNAMEm2426 GPU_WP_HW_CTRL_N                                                  
P  NNAMEm2427 SMB_SSD6_ISO_EN                                                   
P  NNAMEm2428 SMB_BIC_I2C6_MUX_FRU_SCL                                          
P  NNAMEm2429 PWRGD_P3V3_NIC4_R                                                 
P  NNAMEm2430 CLK_100M_DB2000QL_NIC3_DP                                         
P  NNAMEm2431 SMB_ISO_SSD6_SDA                                                  
P  NNAMEm2432 SMB_ISO_SSD11_R_SDA                                               
P  NNAMEm2433 SMB_BIC_I2C6_MUX_FRU_SDA                                          
P  NNAMEm2434 SMB_BMC_9FGL0451E_SCL                                             
P  NNAMEm2435 NIC2_AUX_PWR_EN                                                   
P  NNAMEm2436 SMB_ISO_SSD6_SCL                                                  
P  NNAMEm2437 SMB_ISO_SSD12_R_SCL                                               
P  NNAMEm2438 SMB_BIC_I2C6_MUX_FRU_R_SCL                                        
P  NNAMEm2439 SMB_BMC_9FGL0451E_SDA                                             
P  NNAMEm2440 PWRGD_NIC2_PWR_GOOD_R                                             
P  NNAMEm2441 CLK_100M_DB2000QL_NIC2_DN                                         
P  NNAMEm2442 SMB_ISO_SSD15_R_SCL                                               
P  NNAMEm2443 SMB_BIC_I2C6_MUX_FRU_R_SDA                                        
P  NNAMEm2444 SMB_BIC_I2C6_MUX_VR_SCL                                           
P  NNAMEm2445 PWRGD_P3V3_NIC2_R                                                 
P  NNAMEm2446 USB2_FT4232_CLI_R_DN                                              
P  NNAMEm2447 CLK_100M_DB2000QL_NIC2_DP                                         
P  NNAMEm2448 SMB_SSD5_ISO_EN                                                   
P  NNAMEm2449 SMB_BIC_I2C6_MUX_VR_SDA                                           
P  NNAMEm2450 GPU_BB_RSVD_1_R                                                   
P  NNAMEm2451 USB2_FT4232_CLI_R_DP                                              
P  NNAMEm2452 SMB_ISO_SSD5_SDA                                                  
P  NNAMEm2453 SMB_ISO_SSD10_R_SDA                                               
P  NNAMEm2454 SMB_BIC_I2C6_MUX_VR_R_SCL                                         
P  NNAMEm2455 NIC2_MAIN_PWR_EN                                                  
P  NNAMEm2456 USB2_FT4232_SDB_DP                                                
P  NNAMEm2457 CLK_100M_DB2000QL_NIC1_DN                                         
P  NNAMEm2458 SMB_ISO_SSD5_SCL                                                  
P  NNAMEm2459 SMB_BIC_I2C6_MUX_VR_R_SDA                                         
P  NNAMEm2460 GPU_FPGA_OVERT_R_N                                                
P  NNAMEm2461 RST_NIC3_PERST_N                                                  
P  NNAMEm2462 USB2_FT4232_SDB_R_DP                                              
P  NNAMEm2463 SMB_BIC_I2C6_MUX_CLK_SCL                                          
P  NNAMEm2464 P2E_GPU_FPGA_PEX_RX_DN<0>                                         
P  NNAMEm2465 PWRGD_P3V3_NIC3_R                                                 
P  NNAMEm2466 USB2_FT4232_CLI_DN                                                
P  NNAMEm2467 CLK_100M_DB2000QL_NIC1_DP                                         
P  NNAMEm2468 SMB_BIC_I2C6_MUX_CLK_SDA                                          
P  NNAMEm2469 GPU_3V3IO_RSVD5_FFU_R                                             
P  NNAMEm2470 RST_MB_BIC_ISO_R_N                                                
P  NNAMEm2471 NIC1_AUX_PWR_EN                                                   
P  NNAMEm2472 USB2_FT4232_SDB_DN                                                
P  NNAMEm2473 SMB_SSD4_ISO_EN                                                   
P  NNAMEm2474 SMB_ISO_SSD8_R_SDA                                                
P  NNAMEm2475 SMB_BIC_I2C6_MUX_CLK_R_SCL                                        
P  NNAMEm2476 CLK_100M_GPU_FPGA_REF_DN                                          
P  NNAMEm2477 USB2_FT4232_SDB_R_DN                                              
P  NNAMEm2478 CLK_100M_DB2000QL_NIC0_DN                                         
P  NNAMEm2479 PEX0_SYS_ERR_N_G                                                  
P  NNAMEm2480 SMB_ISO_SSD4_SDA                                                  
P  NNAMEm2481 SMB_ISO_SSD9_R_SCL                                                
P  NNAMEm2482 SMB_BIC_I2C6_MUX_CLK_R_SDA                                        
P  NNAMEm2483 RST_MB_BIC_ISO_N                                                  
P  NNAMEm2484 RST_NIC0_PERST_N                                                  
P  NNAMEm2485 USB2_FT4232_CLI_DP                                                
P  NNAMEm2486 PEX0_SYS_ERR_3V3_N                                                
P  NNAMEm2487 SMB_ISO_SSD4_SCL                                                  
P  NNAMEm2488 SMB_ISO_SSD14_R_SCL                                               
P  NNAMEm2489 SMB_BIC_I2C6_MUX_SSD_8_15_ADC_SCL                                 
P  NNAMEm2490 MB_BMC_MON_ISO_R                                                  
P  NNAMEm2491 CLK_100M_DB2000QL_NIC0_DP                                         
P  NNAMEm2492 LED_PEX0_SYS_ERR_N                                                
P  NNAMEm2493 SMB_ISO_SSD10_R_SCL                                               
P  NNAMEm2494 SMB_BIC_I2C6_MUX_SSD_8_15_ADC_SDA                                 
P  NNAMEm2495 GPU_3V3IO_RSVD3_FFU_R                                             
P  NNAMEm2496 RST_NIC5_PERST_N                                                  
P  NNAMEm2497 SMB_BIC_I2C6_MUX_SSD_8_15_ADC_R_SCL                               
P  NNAMEm2498 RST_NIC1_PERST_N                                                  
P  NNAMEm2499 CLK_100M_DB2000QL_PEX3_S1_R_DN                                    
P  NNAMEm2500 SMB_SSD3_ISO_EN                                                   
P  NNAMEm2501 SMB_BIC_I2C6_MUX_SSD_8_15_ADC_R_SDA                               
P  NNAMEm2502 GPU_FPGA_OVERT_N                                                  
P  NNAMEm2503 SMB_ISO_SSD3_SDA                                                  
P  NNAMEm2504 SMB_BIC_I2C6_MUX_PEX_ADC_SDA                                      
P  NNAMEm2505 RST_MB_PERST_0_N                                                  
P  NNAMEm2506 CLK_100M_DB2000QL_PEX3_S1_R_DP                                    
P  NNAMEm2507 P3V3_CLK_GEN_VDDA25M_CK440                                        
P  NNAMEm2508 SMB_ISO_SSD3_SCL                                                  
P  NNAMEm2509 SMB_ISO_SSD12_R_SDA                                               
P  NNAMEm2510 SMB_BIC_I2C6_MUX_SSD_0_7_ADC_SCL                                  
P  NNAMEm2511 GPU_3V3IO_RSVD5_FFU                                               
P  NNAMEm2512 P3V3_CLK_GEN_VDDXTAL_CK440                                        
P  NNAMEm2513 SMB_ISO_SSD8_R_SCL                                                
P  NNAMEm2514 SMB_BIC_I2C6_MUX_SSD_0_7_ADC_SDA                                  
P  NNAMEm2515 CLK_100M_DB2000QL_PEX2_S1_R_DN                                    
P  NNAMEm2516 PU_PEX1_PAD_TRI_L                                                 
P  NNAMEm2517 SMB_SSD2_ISO_EN                                                   
P  NNAMEm2518 CLK_100M_DB2000QL_PEX2_S1_R_DP                                    
P  NNAMEm2519 SMB_ISO_SSD2_SCL                                                  
P  NNAMEm2520 SMB_ISO_SSD13_R_SDA                                               
P  NNAMEm2521 SMB_BIC_I2C6_MUX_THERMAL_SCL                                      
P  NNAMEm2522 GPU_3V3IO_RSVD3_FFU                                               
P  NNAMEm2523 PRSNT_SSD1_FPGA_N                                                 
P  NNAMEm2524 SMB_ISO_SSD2_SDA                                                  
P  NNAMEm2525 SMB_ISO_SSD11_R_SCL                                               
P  NNAMEm2526 SMB_BIC_I2C6_MUX_THERMAL_SDA                                      
P  NNAMEm2527 CLK_100M_DB2000QL_PEX1_S1_R_DN                                    
P  NNAMEm2528 CLK_100M_CK440Q_1_DB800ZL_R_DN                                    
P  NNAMEm2529 TP_CLK_CK440_PFT_OUT_DN                                           
P  NNAMEm2530 SMB_BIC_I2C6_MUX_THERMAL_R_SCL                                    
P  NNAMEm2531 RST_GPU_FPGA_EROT_R_N                                             
P  NNAMEm2532 SSD1_PEX_PWR_EN_R                                                 
P  NNAMEm2533 TP_CLK_CK440_PFT_OUT_DP                                           
P  NNAMEm2534 SMB_BIC_I2C6_MUX_THERMAL_R_SDA                                    
P  NNAMEm2535 CLK_100M_DB2000QL_PEX1_S1_R_DP                                    
P  NNAMEm2536 CLK_100M_CK440Q_1_DB800ZL_R_DP                                    
P  NNAMEm2537 SMB_ISO_SSD1_SDA                                                  
P  NNAMEm2538 SMB_BIC_I2C6_MUX_PEX_ADC_SCL                                      
P  NNAMEm2539 GPU_RSVD_PARTNER0                                                 
P  NNAMEm2540 SSD5_PWRDIS_BIC_R                                                 
P  NNAMEm2541 PEX0_MODE_SEL12                                                   
P  NNAMEm2542 SMB_ISO_SSD1_SCL                                                  
P  NNAMEm2543 SMB_ISO_SSD15_R_SDA                                               
P  NNAMEm2544 SMB_BIC_I2C6_MUX_PEX_ADC_R_SCL                                    
P  NNAMEm2545 RST_PEX_SSD0_PERST_R_N                                            
P  NNAMEm2546 CLK_100M_DB2000QL_PEX0_S1_R_DN                                    
P  NNAMEm2547 CLK_100M_CK440Q_0_DB2000QL_R_DP                                   
P  NNAMEm2548 SMB_BIC_I2C6_MUX_PEX_ADC_R_SDA                                    
P  NNAMEm2549 GPU_FPGA_BOOT_EN_R                                                
P  NNAMEm2550 CLK_100M_CK440Q_0_DB2000QL_R_DN                                   
P  NNAMEm2551 PEX0_MODE_SEL11                                                   
P  NNAMEm2552 PU_PEX1_ATPG_MODE_L                                               
P  NNAMEm2553 SMB_ISO_SSD13_R_SCL                                               
P  NNAMEm2554 SMB_BIC_I2C6_MUX_NIC_ADC_SCL                                      
P  NNAMEm2555 PEX_USB_HUB_TEST                                                  
P  NNAMEm2556 CLK_100M_DB2000QL_PEX0_S1_R_DP                                    
P  NNAMEm2557 SMB_SSD1_ISO_EN                                                   
P  NNAMEm2558 SMB_ISO_SSD14_R_SDA                                               
P  NNAMEm2559 SMB_BIC_I2C6_MUX_NIC_ADC_SDA                                      
P  NNAMEm2560 GPU_RSVD_PARTNER1                                                 
P  NNAMEm2561 SSD0_PEX_PWR_EN_R                                                 
P  NNAMEm2562 PEX0_MODE_SEL10                                                   
P  NNAMEm2563 SMB_ISO_SSD9_R_SDA                                                
P  NNAMEm2564 SMB_BIC_I2C6_MUX_NIC_ADC_R_SCL                                    
P  NNAMEm2565 RST_PEX_SSD6_PERST_R_N                                            
P  NNAMEm2566 SMB_BIC_I2C6_MUX_NIC_ADC_R_SDA                                    
P  NNAMEm2567 SMB_GPU1_ALERT_N                                                  
P  NNAMEm2568 PWRGD_P3V3_SSD15_R                                                
P  NNAMEm2569 P12V_SSD1_VIN_P                                                   
P  NNAMEm2570 P12V_SSD1_VIN_N                                                   
P  NNAMEm2571 SMB_SSD1_ADC_SDA                                                  
P  NNAMEm2572 SMB_BMC_FRU_SDA                                                   
P  NNAMEm2573 SMB_BMC_FRU_SCL                                                   
P  NNAMEm2574 PWRGD_P1V25_PEX3_R                                                
P  NNAMEm2575 PEX_P1V8_ADC_A0                                                   
P  NNAMEm2576 P12V_PEX_P1V8_VIN_N                                               
P  NNAMEm2577 PEX_P1V8_ADC_ALERT_N                                              
P  NNAMEm2578 PEX_P1V8_ADC_A1                                                   
P  NNAMEm2579 SMB_PEX_P1V8_ADC_SDA                                              
P  NNAMEm2580 P12V_PEX_P1V8_VIN_P                                               
P  NNAMEm2581 PEX1_P1V25_ADC_A1                                                 
P  NNAMEm2582 SMB_PEX3_P1V25_ADC_SDA                                            
P  NNAMEm2583 SMB_PEX2_P1V25_ADC_SCL                                            
P  NNAMEm2584 SMB_PEX1_P1V25_ADC_SCL                                            
P  NNAMEm2585 P12V_PEX0_P1V25_VIN_P                                             
P  NNAMEm2586 PEX3_P1V25_ADC_A1                                                 
P  NNAMEm2587 P12V_PEX2_P1V25_VIN_N                                             
P  NNAMEm2588 P12V_PEX2_P1V25_VIN_P                                             
P  NNAMEm2589 SMB_PEX1_P1V25_ADC_SDA                                            
P  NNAMEm2590 PEX3_P1V25_ADC_ALERT_N                                            
P  NNAMEm2591 SMB_PEX0_P1V25_ADC_SDA                                            
P  NNAMEm2592 PEX0_P1V25_ADC_A0                                                 
P  NNAMEm2593 P12V_PEX1_P1V25_VIN_P                                             
P  NNAMEm2594 PEX3_P1V25_ADC_A0                                                 
P  NNAMEm2595 P12V_PEX0_P1V25_VIN_N                                             
P  NNAMEm2596 PWRGD_P3V3_AUX_R                                                  
P  NNAMEm2597 P12V_PEX3_P1V25_VIN_N                                             
P  NNAMEm2598 PEX1_P1V25_ADC_A0                                                 
P  NNAMEm2599 PEX1_P1V25_ADC_ALERT_N                                            
P  NNAMEm2600 PEX2_P1V25_ADC_A0                                                 
P  NNAMEm2601 PEX2_P1V25_ADC_A1                                                 
P  NNAMEm2602 PEX0_P1V25_ADC_ALERT_N                                            
P  NNAMEm2603 SMB_PEX0_P1V25_ADC_SCL                                            
P  NNAMEm2604 PEX0_P1V25_ADC_A1                                                 
P  NNAMEm2605 SMB_NIC7_ADC_SDA                                                  
P  NNAMEm2606 P12V_PEX1_P1V25_VIN_N                                             
P  NNAMEm2607 SMB_NIC6_ADC_SCL                                                  
P  NNAMEm2608 PEX2_P1V25_ADC_ALERT_N                                            
P  NNAMEm2609 NIC4_ADC_ALERT_N                                                  
P  NNAMEm2610 P12V_PEX3_P1V25_VIN_P                                             
P  NNAMEm2611 SMB_NIC4_ADC_SDA                                                  
P  NNAMEm2612 P12V_NIC4_VIN_P                                                   
P  NNAMEm2613 NIC7_ADC_ALERT_N                                                  
P  NNAMEm2614 PWRGD_P1V25_PEX0_R                                                
P  NNAMEm2615 P12V_NIC7_VIN_N                                                   
P  NNAMEm2616 SMB_NIC5_ADC_SCL                                                  
P  NNAMEm2617 P3V3_AUX_SCALED                                                   
P  NNAMEm2618 P12V_NIC5_VIN_P                                                   
P  NNAMEm2619 P12V_NIC4_VIN_N                                                   
P  NNAMEm2620 P1V2_AUX_SCALED                                                   
P  NNAMEm2621 PWRGD_P1V25_PEX2_R                                                
P  NNAMEm2622 P12V_NIC7_VIN_P                                                   
P  NNAMEm2623 P12V_NIC5_VIN_N                                                   
P  NNAMEm2624 SMB_NIC5_ADC_SDA                                                  
P  NNAMEm2625 P12V_NIC6_VIN_N                                                   
P  NNAMEm2626 P12V_NIC6_VIN_P                                                   
P  NNAMEm2627 P12V_NIC0_VIN_P                                                   
P  NNAMEm2628 SMB_NIC4_ADC_SCL                                                  
P  NNAMEm2629 P12V_NIC1_VIN_N                                                   
P  NNAMEm2630 NIC5_ADC_ALERT_N                                                  
P  NNAMEm2631 P12V_NIC2_VIN_P                                                   
P  NNAMEm2632 NIC6_ADC_ALERT_N                                                  
P  NNAMEm2633 SMB_NIC0_ADC_SDA                                                  
P  NNAMEm2634 SMB_NIC2_ADC_SCL                                                  
P  NNAMEm2635 NIC0_ADC_ALERT_N                                                  
P  NNAMEm2636 P12V_NIC0_VIN_N                                                   
P  NNAMEm2637 NIC2_ADC_ALERT_N                                                  
P  NNAMEm2638 SMB_NIC3_ADC_SDA                                                  
P  NNAMEm2639 NIC3_ADC_ALERT_N                                                  
P  NNAMEm2640 SMB_NIC0_ADC_SCL                                                  
P  NNAMEm2641 SMB_NIC1_ADC_SCL                                                  
P  NNAMEm2642 SMB_NIC1_ADC_SDA                                                  
P  NNAMEm2643 P12V_SSD13_VIN_N                                                  
P  NNAMEm2644 P12V_NIC2_VIN_N                                                   
P  NNAMEm2645 P12V_NIC3_VIN_P                                                   
P  NNAMEm2646 PWRGD_P1V8_PEX_R                                                  
P  NNAMEm2647 SMB_SSD14_ADC_SCL                                                 
P  NNAMEm2648 P12V_SSD13_VIN_P                                                  
P  NNAMEm2649 P12V_NIC1_VIN_P                                                   
P  NNAMEm2650 P12V_SSD14_VIN_P                                                  
P  NNAMEm2651 SMB_SSD14_ADC_SDA                                                 
P  NNAMEm2652 P12V_NIC3_VIN_N                                                   
P  NNAMEm2653 NIC1_ADC_ALERT_N                                                  
P  NNAMEm2654 BUF_UART_MB_BIC_TX_EN                                             
P  NNAMEm2655 SMB_SSD12_ADC_SCL                                                 
P  NNAMEm2656 SMB_SSD13_ADC_SCL                                                 
P  NNAMEm2657 P12V_SSD12_VIN_P                                                  
P  NNAMEm2658 UART_MB_BIC_R_TX                                                  
P  NNAMEm2659 SSD15_ADC_ALERT_N                                                 
P  NNAMEm2660 UART_MB_BIC_TX_BUF                                                
P  NNAMEm2661 SMB_SSD15_ADC_SDA                                                 
P  NNAMEm2662 SMB_SSD13_ADC_SDA                                                 
P  NNAMEm2663 SSD14_ADC_ALERT_N                                                 
P  NNAMEm2664 SMB_SSD15_ADC_SCL                                                 
P  NNAMEm2665 P12V_SSD15_VIN_P                                                  
P  NNAMEm2666 P12V_SSD12_VIN_N                                                  
P  NNAMEm2667 USB_DEBUG_PWR_BTN_N                                               
P  NNAMEm2668 SMB_SSD11_ADC_SCL                                                 
P  NNAMEm2669 SSD13_ADC_ALERT_N                                                 
P  NNAMEm2670 SMB_SSD11_ADC_SDA                                                 
P  NNAMEm2671 P12V_SSD14_VIN_N                                                  
P  NNAMEm2672 SSD8_ADC_ALERT_N                                                  
P  NNAMEm2673 SSD12_ADC_ALERT_N                                                 
P  NNAMEm2674 SSD10_ADC_ALERT_N                                                 
P  NNAMEm2675 SMB_SSD12_ADC_SDA                                                 
P  NNAMEm2676 P12V_SSD15_VIN_N                                                  
P  NNAMEm2677 SMB_SSD8_ADC_SCL                                                  
P  NNAMEm2678 TP_FSA3357K8X_B2_TX                                               
P  NNAMEm2679 SSD11_ADC_ALERT_N                                                 
P  NNAMEm2680 P12V_SSD10_VIN_N                                                  
P  NNAMEm2681 TP_FSA3357K8X_B2_RX                                               
P  NNAMEm2682 SMB_SSD8_ADC_SDA                                                  
P  NNAMEm2683 P12V_SSD10_VIN_P                                                  
P  NNAMEm2684 SMB_SSD7_ADC_SDA                                                  
P  NNAMEm2685 P12V_SSD11_VIN_P                                                  
P  NNAMEm2686 P12V_SSD6_VIN_N                                                   
P  NNAMEm2687 P12V_SSD8_VIN_N                                                   
P  NNAMEm2688 SMB_SSD10_ADC_SCL                                                 
P  NNAMEm2689 SSD5_ADC_ALERT_N                                                  
P  NNAMEm2690 P12V_SSD4_VIN_N                                                   
P  NNAMEm2691 P12V_SSD11_VIN_N                                                  
P  NNAMEm2692 SMB_SSD5_ADC_SCL                                                  
P  NNAMEm2693 P12V_SSD8_VIN_P                                                   
P  NNAMEm2694 P12V_SSD7_VIN_P                                                   
P  NNAMEm2695 P12V_SSD6_VIN_P                                                   
P  NNAMEm2696 SSD4_ADC_ALERT_N                                                  
P  NNAMEm2697 SMB_SSD4_ADC_SCL                                                  
P  NNAMEm2698 SSD7_ADC_ALERT_N                                                  
P  NNAMEm2699 P12V_SSD7_VIN_N                                                   
P  NNAMEm2700 PWRGD_P5V_AUX_R                                                   
P  NNAMEm2701 SSD6_ADC_ALERT_N                                                  
P  NNAMEm2702 SMB_SSD7_ADC_SCL                                                  
P  NNAMEm2703 SMB_SSD5_ADC_SDA                                                  
P  NNAMEm2704 P12V_SSD5_VIN_P                                                   
P  NNAMEm2705 SMB_SSD6_ADC_SDA                                                  
P  NNAMEm2706 SMB_SSD3_ADC_SDA                                                  
P  NNAMEm2707 SMB_SSD2_ADC_SDA                                                  
P  NNAMEm2708 SMB_SSD6_ADC_SCL                                                  
P  NNAMEm2709 SSD0_ADC_ALERT_N                                                  
P  NNAMEm2710 P12V_SSD4_VIN_P                                                   
P  NNAMEm2711 P12V_SSD2_VIN_N                                                   
P  NNAMEm2712 P12V_SSD5_VIN_N                                                   
P  NNAMEm2713 SMB_SSD3_ADC_SCL                                                  
P  NNAMEm2714 SMB_SSD4_ADC_SDA                                                  
P  NNAMEm2715 SMB_SSD1_ADC_SCL                                                  
P  NNAMEm2716 SSD3_ADC_ALERT_N                                                  
P  NNAMEm2717 SMB_SSD0_ADC_SDA                                                  
P  NNAMEm2718 SSD2_ADC_ALERT_N                                                  
P  NNAMEm2719 P12V_SSD0_VIN_P                                                   
P  NNAMEm2720 P12V_SSD3_VIN_P                                                   
P  NNAMEm2721 P12V_SSD0_VIN_N                                                   
P  NNAMEm2722 SMB_SSD2_ADC_SCL                                                  
P  NNAMEm2723 PWRGD_P1V25_PEX1_R                                                
P  NNAMEm2724 SSD1_ADC_ALERT_N                                                  
P  NNAMEm2725 P12V_SSD3_VIN_N                                                   
P  NNAMEm2726 SMB_SSD0_ADC_SCL                                                  
P  NNAMEm2727 P12V_SSD2_VIN_P                                                   
P  NNAMEm2728 P5E_PEX0_STN2_TX_C_DN<43>                                         
P  NNAMEm2729 P5E_PEX0_STN2_TX_C_DN<45>                                         
P  NNAMEm2730 P5E_PEX0_STN2_TX_C_DP<45>                                         
P  NNAMEm2731 P5E_PEX0_STN2_TX_C_DP<40>                                         
P  NNAMEm2732 DUALPORT_N_SSD3                                                   
P  NNAMEm2733 DUALPORT_N_SSD2                                                   
P  NNAMEm2734 P5E_PEX0_STN2_TX_C_DP<42>                                         
P  NNAMEm2735 P5E_PEX0_STN2_TX_C_DP<35>                                         
P  NNAMEm2736 P5E_PEX0_STN2_TX_C_DP<37>                                         
P  NNAMEm2737 P5E_PEX0_STN2_TX_C_DN<38>                                         
P  NNAMEm2738 P5E_PEX0_STN2_TX_C_DN<44>                                         
P  NNAMEm2739 P5E_PEX0_STN2_TX_C_DP<36>                                         
P  NNAMEm2740 P5E_PEX0_STN2_TX_C_DN<46>                                         
P  NNAMEm2741 P5E_PEX0_STN2_TX_C_DN<36>                                         
P  NNAMEm2742 DUALPORT_N_SSD1                                                   
P  NNAMEm2743 P5E_PEX0_STN2_TX_C_DP<46>                                         
P  NNAMEm2744 P5E_PEX0_STN2_TX_C_DP<41>                                         
P  NNAMEm2745 P5E_PEX0_STN2_TX_C_DN<41>                                         
P  NNAMEm2746 P5E_PEX0_STN2_TX_C_DN<32>                                         
P  NNAMEm2747 P5E_PEX0_STN2_TX_C_DP<38>                                         
P  NNAMEm2748 P5E_PEX0_STN2_TX_C_DN<37>                                         
P  NNAMEm2749 P5E_PEX0_STN2_TX_C_DN<42>                                         
P  NNAMEm2750 P5E_PEX0_STN2_TX_C_DN<34>                                         
P  NNAMEm2751 DUALPORT_N_SSD0                                                   
P  NNAMEm2752 P5E_PEX0_STN2_TX_C_DP<33>                                         
P  NNAMEm2753 P5E_PEX0_STN2_TX_C_DN<47>                                         
P  NNAMEm2754 P5E_PEX0_STN2_TX_C_DN<33>                                         
P  NNAMEm2755 P5E_PEX0_STN2_TX_C_DP<43>                                         
P  NNAMEm2756 P5E_PEX0_STN2_TX_C_DP<32>                                         
P  NNAMEm2757 P5E_PEX0_STN2_TX_C_DP<44>                                         
P  NNAMEm2758 P5E_PEX0_STN2_TX_C_DP<39>                                         
P  NNAMEm2759 P5E_PEX0_STN2_TX_C_DN<40>                                         
P  NNAMEm2760 P5E_PEX0_STN2_TX_C_DN<39>                                         
P  NNAMEm2761 P5E_PEX0_STN2_TX_C_DP<34>                                         
P  NNAMEm2762 P5E_PEX0_STN2_TX_C_DN<35>                                         
P  NNAMEm2763 P5E_PEX0_STN2_TX_C_DP<47>                                         
P  NNAMEm2764 PWRGD_P12V_NIC3_R                                                 
P  NNAMEm2765 PWRGD_P12V_NIC1                                                   
P  NNAMEm2766 PWRGD_P12V_NIC2                                                   
P  NNAMEm2767 PWRGD_P12V_NIC4                                                   
P  NNAMEm2768 PWRGD_P12V_NIC7                                                   
P  NNAMEm2769 PWRGD_P12V_NIC6_R                                                 
P  NNAMEm2770 PWRGD_P12V_NIC1_R                                                 
P  NNAMEm2771 PWRGD_P12V_NIC2_R                                                 
P  NNAMEm2772 PWRGD_P12V_NIC4_R                                                 
P  NNAMEm2773 PWRGD_P12V_NIC3                                                   
P  NNAMEm2774 PWRGD_P12V_NIC6                                                   
P  NNAMEm2775 PWRGD_P12V_NIC5                                                   
P  NNAMEm2776 PWRGD_P12V_NIC7_R                                                 
P  NNAMEm2777 PWRGD_P12V_NIC5_R                                                 
P  NNAMEm2778 P5E_PEX1_STN4_TX_C_DN<68>                                         
P  NNAMEm2779 P5E_PEX1_STN4_RX_DP<64>                                           
P  NNAMEm2780 P5E_PEX1_STN4_TX_C_DN<71>                                         
P  NNAMEm2781 P5E_PEX1_STN4_RX_DP<65>                                           
P  NNAMEm2782 P5E_PEX1_STN4_RX_DP<68>                                           
P  NNAMEm2783 P5E_PEX1_STN4_RX_DN<72>                                           
P  NNAMEm2784 P5E_PEX1_STN4_TX_C_DP<70>                                         
P  NNAMEm2785 P5E_PEX1_STN4_RX_DN<77>                                           
P  NNAMEm2786 P5E_PEX1_STN4_TX_C_DN<73>                                         
P  NNAMEm2787 P5E_PEX1_STN4_TX_C_DN<76>                                         
P  NNAMEm2788 P5E_PEX1_STN4_TX_C_DP<74>                                         
P  NNAMEm2789 P5E_PEX1_STN4_RX_DN<69>                                           
P  NNAMEm2790 P5E_PEX1_STN4_TX_C_DN<69>                                         
P  NNAMEm2791 P5E_PEX1_STN4_TX_C_DP<67>                                         
P  NNAMEm2792 P5E_PEX1_STN4_RX_DP<79>                                           
P  NNAMEm2793 P5E_PEX1_STN4_TX_C_DP<65>                                         
P  NNAMEm2794 P5E_PEX1_STN4_RX_DP<76>                                           
P  NNAMEm2795 P5E_PEX1_STN4_TX_C_DN<77>                                         
P  NNAMEm2796 P5E_PEX1_STN4_RX_DN<74>                                           
P  NNAMEm2797 P5E_PEX1_STN4_RX_DP<72>                                           
P  NNAMEm2798 P5E_PEX1_STN4_RX_DN<79>                                           
P  NNAMEm2799 P5E_PEX1_STN4_TX_C_DN<64>                                         
P  NNAMEm2800 P5E_PEX1_STN4_TX_C_DP<64>                                         
P  NNAMEm2801 P5E_PEX1_STN4_RX_DN<65>                                           
P  NNAMEm2802 P5E_PEX1_STN4_RX_DP<69>                                           
P  NNAMEm2803 P5E_PEX1_STN4_TX_C_DP<76>                                         
P  NNAMEm2804 P5E_PEX1_STN4_TX_C_DP<77>                                         
P  NNAMEm2805 P5E_PEX1_STN4_RX_DN<73>                                           
P  NNAMEm2806 P5E_PEX1_STN4_TX_C_DP<78>                                         
P  NNAMEm2807 P5E_PEX1_STN4_TX_C_DP<75>                                         
P  NNAMEm2808 P5E_PEX1_STN4_TX_C_DN<70>                                         
P  NNAMEm2809 P5E_PEX1_STN4_RX_DN<66>                                           
P  NNAMEm2810 P5E_PEX1_STN4_RX_DN<70>                                           
P  NNAMEm2811 P5E_PEX1_STN4_TX_C_DN<79>                                         
P  NNAMEm2812 P5E_PEX1_STN4_RX_DN<76>                                           
P  NNAMEm2813 P5E_PEX1_STN4_RX_DN<71>                                           
P  NNAMEm2814 P5E_PEX1_STN4_TX_C_DP<79>                                         
P  NNAMEm2815 P5E_PEX1_STN4_RX_DN<78>                                           
P  NNAMEm2816 P5E_PEX1_STN4_TX_C_DN<67>                                         
P  NNAMEm2817 P5E_PEX1_STN4_RX_DP<70>                                           
P  NNAMEm2818 P5E_PEX1_STN4_TX_C_DP<69>                                         
P  NNAMEm2819 P5E_PEX1_STN4_TX_C_DN<78>                                         
P  NNAMEm2820 P5E_PEX1_STN4_RX_DN<67>                                           
P  NNAMEm2821 P5E_PEX1_STN4_RX_DP<78>                                           
P  NNAMEm2822 P5E_PEX1_STN4_RX_DN<68>                                           
P  NNAMEm2823 P5E_PEX1_STN4_TX_C_DN<75>                                         
P  NNAMEm2824 P5E_PEX1_STN4_RX_DP<67>                                           
P  NNAMEm2825 P5E_PEX1_STN4_TX_C_DP<73>                                         
P  NNAMEm2826 P5E_PEX1_STN4_TX_C_DP<66>                                         
P  NNAMEm2827 P5E_PEX1_STN4_TX_C_DN<74>                                         
P  NNAMEm2828 P5E_PEX1_STN4_RX_DP<73>                                           
P  NNAMEm2829 P5E_PEX1_STN4_RX_DN<64>                                           
P  NNAMEm2830 P5E_PEX1_STN4_TX_C_DP<72>                                         
P  NNAMEm2831 P5E_PEX1_STN4_TX_C_DP<68>                                         
P  NNAMEm2832 P5E_PEX1_STN4_RX_DN<75>                                           
P  NNAMEm2833 P5E_PEX1_STN4_RX_DP<71>                                           
P  NNAMEm2834 P5E_PEX1_STN4_RX_DP<75>                                           
P  NNAMEm2835 P5E_PEX1_STN4_RX_DP<66>                                           
P  NNAMEm2836 P5E_PEX1_STN4_RX_DP<77>                                           
P  NNAMEm2837 P5E_PEX1_STN4_TX_C_DP<71>                                         
P  NNAMEm2838 P5E_PEX1_STN4_RX_DP<74>                                           
P  NNAMEm2839 P5E_PEX1_STN4_TX_C_DN<72>                                         
P  NNAMEm2840 P5E_PEX1_STN4_TX_C_DN<65>                                         
P  NNAMEm2841 P5E_PEX1_STN4_TX_C_DN<66>                                         
P  NNAMEm2842 P5E_PEX1_STN4_TX_DP<77>                                           
P  NNAMEm2843 P5E_PEX1_STN4_TX_DN<66>                                           
P  NNAMEm2844 P5E_PEX1_STN4_TX_DP<67>                                           
P  NNAMEm2845 P5E_PEX1_STN4_TX_DN<71>                                           
P  NNAMEm2846 P5E_PEX1_STN4_TX_DP<64>                                           
P  NNAMEm2847 P5E_PEX1_STN4_TX_DN<76>                                           
P  NNAMEm2848 P5E_PEX1_STN4_TX_DP<69>                                           
P  NNAMEm2849 P5E_PEX1_STN4_TX_DP<75>                                           
P  NNAMEm2850 P5E_PEX1_STN4_TX_DP<65>                                           
P  NNAMEm2851 P5E_PEX1_STN4_TX_DN<79>                                           
P  NNAMEm2852 P5E_PEX1_STN4_TX_DP<76>                                           
P  NNAMEm2853 P5E_PEX1_STN4_TX_DN<74>                                           
P  NNAMEm2854 P5E_PEX1_STN4_TX_DN<72>                                           
P  NNAMEm2855 P5E_PEX1_STN4_TX_DP<66>                                           
P  NNAMEm2856 P5E_PEX1_STN4_TX_DP<71>                                           
P  NNAMEm2857 P5E_PEX1_STN4_TX_DP<74>                                           
P  NNAMEm2858 P5E_PEX1_STN4_TX_DP<78>                                           
P  NNAMEm2859 P5E_PEX1_STN4_TX_DN<75>                                           
P  NNAMEm2860 P5E_PEX1_STN4_TX_DN<78>                                           
P  NNAMEm2861 P5E_PEX1_STN4_TX_DP<72>                                           
P  NNAMEm2862 P5E_PEX1_STN4_TX_DP<70>                                           
P  NNAMEm2863 P5E_PEX1_STN4_TX_DN<64>                                           
P  NNAMEm2864 P5E_PEX1_STN4_TX_DN<68>                                           
P  NNAMEm2865 P5E_PEX1_STN4_TX_DN<67>                                           
P  NNAMEm2866 P5E_PEX1_STN4_TX_DP<73>                                           
P  NNAMEm2867 P5E_PEX1_STN4_TX_DN<77>                                           
P  NNAMEm2868 P5E_PEX1_STN4_TX_DP<79>                                           
P  NNAMEm2869 P5E_PEX1_STN4_TX_DP<68>                                           
P  NNAMEm2870 P5E_PEX1_STN4_TX_DN<69>                                           
P  NNAMEm2871 P5E_PEX1_STN4_TX_DN<70>                                           
P  NNAMEm2872 P5E_PEX1_STN4_TX_DN<65>                                           
P  NNAMEm2873 P5E_PEX1_STN4_TX_DN<73>                                           
P  NNAMEm2874 SPI_PEX1_SDIO3_R                                                  
P  NNAMEm2875 SPI_PEX1_SDIO0_MUX                                                
P  NNAMEm2876 SPI_PEX1_CLK_MUX                                                  
P  NNAMEm2877 SPI_PEX1_CS_MUX_N                                                 
P  NNAMEm2878 SPI_PEX1_CS_R_N                                                   
P  NNAMEm2879 SPI_PEX1_SDIO1_R                                                  
P  NNAMEm2880 SPI_PEX1_SDIO0_R                                                  
P  NNAMEm2881 SPI_PEX1_SDIO1_MUX                                                
P  NNAMEm2882 SPI_PEX1_SDIO2_R                                                  
P  NNAMEm2883 SPI_PEX3_SDIO2_R                                                  
P  NNAMEm2884 SPI_PEX3_CS_R_N                                                   
P  NNAMEm2885 SPI_PEX3_SDIO0_R                                                  
P  NNAMEm2886 SPI_PEX3_SDIO1_MUX                                                
P  NNAMEm2887 SPI_PEX3_CLK_MUX                                                  
P  NNAMEm2888 SPI_PEX3_CS_MUX_N                                                 
P  NNAMEm2889 SPI_PEX3_SDIO3_R                                                  
P  NNAMEm2890 SPI_PEX3_SDIO0_MUX                                                
P  NNAMEm2891 SPI_PEX3_SDIO1_R                                                  
P  NNAMEm2892 P5E_PEX0_STN4_TX_C_DP<64>                                         
P  NNAMEm2893 P5E_PEX2_STN4_RX_DP<69>                                           
P  NNAMEm2894 P5E_PEX0_STN4_TX_C_DN<68>                                         
P  NNAMEm2895 P5E_PEX2_STN4_TX_C_DP<72>                                         
P  NNAMEm2896 P5E_PEX0_STN4_TX_C_DN<70>                                         
P  NNAMEm2897 P5E_PEX0_STN4_TX_DN<76>                                           
P  NNAMEm2898 P5E_PEX2_STN4_TX_C_DP<76>                                         
P  NNAMEm2899 PWRGD_P3V3_NIC0                                                   
P  NNAMEm2900 P5E_PEX0_STN4_RX_DP<69>                                           
P  NNAMEm2901 P5E_PEX0_STN4_TX_DP<66>                                           
P  NNAMEm2902 P5E_PEX2_STN4_TX_C_DP<71>                                         
P  NNAMEm2903 P5E_PEX0_STN4_TX_C_DP<77>                                         
P  NNAMEm2904 P5E_PEX2_STN4_RX_DP<66>                                           
P  NNAMEm2905 P5E_PEX2_STN4_TX_C_DN<64>                                         
P  NNAMEm2906 PWRGD_P3V3_NIC0_R                                                 
P  NNAMEm2907 P5E_PEX0_STN4_TX_DP<70>                                           
P  NNAMEm2908 P5E_PEX2_STN4_TX_C_DN<68>                                         
P  NNAMEm2909 P5E_PEX0_STN4_TX_DN<73>                                           
P  NNAMEm2910 P5E_PEX2_STN4_RX_DP<76>                                           
P  NNAMEm2911 P5E_PEX2_STN4_TX_C_DN<70>                                         
P  NNAMEm2912 P5E_PEX3_STN4_TX_DP<69>                                           
P  NNAMEm2913 P5E_PEX0_STN4_TX_DP<72>                                           
P  NNAMEm2914 P5E_PEX2_STN4_TX_C_DN<74>                                         
P  NNAMEm2915 P5E_PEX3_STN4_TX_DN<72>                                           
P  NNAMEm2916 P5E_PEX0_STN4_TX_DP<75>                                           
P  NNAMEm2917 P5E_PEX2_STN4_TX_C_DP<64>                                         
P  NNAMEm2918 P5E_PEX3_STN4_TX_DP<77>                                           
P  NNAMEm2919 P5E_PEX0_STN4_TX_DN<70>                                           
P  NNAMEm2920 P5E_PEX2_STN4_TX_C_DP<77>                                         
P  NNAMEm2921 P5E_PEX2_STN4_RX_DP<71>                                           
P  NNAMEm2922 P5E_PEX3_STN4_TX_DP<72>                                           
P  NNAMEm2923 P5E_PEX2_STN4_RX_DP<72>                                           
P  NNAMEm2924 P5E_PEX2_STN4_TX_C_DN<67>                                         
P  NNAMEm2925 P5E_PEX2_STN4_TX_C_DN<69>                                         
P  NNAMEm2926 P5E_PEX3_STN4_TX_DP<75>                                           
P  NNAMEm2927 P5E_PEX2_STN4_TX_C_DP<68>                                         
P  NNAMEm2928 P5E_PEX2_STN4_RX_DP<65>                                           
P  NNAMEm2929 P5E_PEX3_STN4_TX_DN<64>                                           
P  NNAMEm2930 P5E_PEX2_STN4_RX_DN<69>                                           
P  NNAMEm2931 P5E_PEX3_STN4_TX_DN<73>                                           
P  NNAMEm2932 P5E_PEX2_STN4_RX_DP<64>                                           
P  NNAMEm2933 P5E_PEX2_STN4_RX_DN<76>                                           
P  NNAMEm2934 P5E_PEX3_STN4_TX_DP<73>                                           
P  NNAMEm2935 P5E_PEX2_STN4_RX_DP<73>                                           
P  NNAMEm2936 P5E_PEX2_STN4_TX_C_DN<78>                                         
P  NNAMEm2937 P5E_PEX2_STN4_TX_C_DN<76>                                         
P  NNAMEm2938 P5E_PEX2_STN4_RX_DP<78>                                           
P  NNAMEm2939 P5E_PEX3_STN4_TX_DN<70>                                           
P  NNAMEm2940 P5E_PEX3_STN4_TX_DP<64>                                           
P  NNAMEm2941 P5E_PEX3_STN4_TX_DP<79>                                           
P  NNAMEm2942 P5E_PEX3_STN4_TX_DP<70>                                           
P  NNAMEm2943 P5E_PEX3_STN4_TX_DP<74>                                           
P  NNAMEm2944 P5E_PEX3_STN4_TX_DP<68>                                           
P  NNAMEm2945 P5E_PEX3_STN4_TX_DN<65>                                           
P  NNAMEm2946 P5E_PEX3_STN4_TX_DN<66>                                           
P  NNAMEm2947 P5E_PEX3_STN4_TX_DN<74>                                           
P  NNAMEm2948 P5E_PEX3_STN4_TX_C_DP<73>                                         
P  NNAMEm2949 P5E_PEX3_STN4_TX_DP<67>                                           
P  NNAMEm2950 P5E_PEX3_STN4_TX_C_DP<72>                                         
P  NNAMEm2951 P5E_PEX3_STN4_TX_DN<78>                                           
P  NNAMEm2952 P5E_PEX3_STN4_TX_C_DN<79>                                         
P  NNAMEm2953 P5E_PEX3_STN4_TX_C_DN<74>                                         
P  NNAMEm2954 P5E_PEX3_STN4_TX_C_DN<68>                                         
P  NNAMEm2955 P5E_PEX3_STN4_RX_DP<74>                                           
P  NNAMEm2956 P5E_PEX3_STN4_RX_DN<64>                                           
P  NNAMEm2957 P5E_PEX3_STN4_TX_DP<78>                                           
P  NNAMEm2958 P5E_PEX3_STN4_RX_DN<71>                                           
P  NNAMEm2959 P5E_PEX3_STN4_TX_DN<68>                                           
P  NNAMEm2960 P5E_PEX3_STN4_RX_DP<77>                                           
P  NNAMEm2961 P5E_PEX3_STN4_RX_DN<69>                                           
P  NNAMEm2962 P5E_PEX3_STN4_TX_DP<65>                                           
P  NNAMEm2963 P5E_PEX3_STN4_TX_C_DN<65>                                         
P  NNAMEm2964 P5E_PEX3_STN4_TX_DP<76>                                           
P  NNAMEm2965 P5E_PEX3_STN4_TX_C_DP<66>                                         
P  NNAMEm2966 P5E_PEX3_STN4_TX_DN<69>                                           
P  NNAMEm2967 P5E_PEX3_STN4_RX_DN<77>                                           
P  NNAMEm2968 P5E_PEX3_STN4_TX_DN<77>                                           
P  NNAMEm2969 P5E_PEX3_STN4_RX_DN<66>                                           
P  NNAMEm2970 SPI_PEX2_CS_MUX_R_N                                               
P  NNAMEm2971 P5E_PEX3_STN4_RX_DN<74>                                           
P  NNAMEm2972 P5E_PEX3_STN4_TX_DP<71>                                           
P  NNAMEm2973 SPI_PEX2_SDIO0_MUX_R                                              
P  NNAMEm2974 P5E_PEX3_STN4_RX_DN<67>                                           
P  NNAMEm2975 P5E_PEX3_STN4_RX_DP<70>                                           
P  NNAMEm2976 P5E_PEX3_STN4_RX_DP<78>                                           
P  NNAMEm2977 P5E_PEX3_STN4_TX_DN<79>                                           
P  NNAMEm2978 SPI_PEX2_SDIO1_MUX_R                                              
P  NNAMEm2979 P5E_PEX3_STN4_TX_C_DN<69>                                         
P  NNAMEm2980 P5E_PEX3_STN4_TX_C_DP<74>                                         
P  NNAMEm2981 PWRGD_P12V_SSD0                                                   
P  NNAMEm2982 SPI_PEX2_SDIO3_R1                                                 
P  NNAMEm2983 P5E_PEX3_STN4_RX_DP<72>                                           
P  NNAMEm2984 P5E_PEX3_STN4_TX_DP<66>                                           
P  NNAMEm2985 PWRGD_P12V_SSD0_R                                                 
P  NNAMEm2986 SPI_PEX2_SDIO2_R1                                                 
P  NNAMEm2987 P5E_PEX3_STN4_TX_C_DP<65>                                         
P  NNAMEm2988 SPI_PEX2_CLK_MUX_R                                                
P  NNAMEm2989 P5E_PEX3_STN4_TX_C_DP<71>                                         
P  NNAMEm2990 P5E_PEX3_STN4_TX_DN<75>                                           
P  NNAMEm2991 SPI_MUX_PEX2_EN_N                                                 
P  NNAMEm2992 P5E_PEX3_STN4_TX_C_DN<67>                                         
P  NNAMEm2993 P5E_PEX3_STN4_TX_DN<67>                                           
P  NNAMEm2994 P5E_PEX3_STN4_RX_DN<72>                                           
P  NNAMEm2995 P5E_PEX3_STN4_TX_C_DN<72>                                         
P  NNAMEm2996 P5E_PEX3_STN4_TX_DN<71>                                           
P  NNAMEm2997 P5E_PEX3_STN4_TX_C_DP<75>                                         
P  NNAMEm2998 P5E_PEX3_STN4_TX_DN<76>                                           
P  NNAMEm2999 P5E_PEX3_STN4_RX_DP<66>                                           
P  NNAMEm3000 P5E_PEX3_STN4_TX_C_DN<76>                                         
P  NNAMEm3001 P5E_PEX3_STN4_RX_DN<75>                                           
P  NNAMEm3002 SPI_PEX0_SDIO2_R1                                                 
P  NNAMEm3003 P5E_PEX3_STN4_TX_C_DN<78>                                         
P  NNAMEm3004 P5E_PEX3_STN4_RX_DP<79>                                           
P  NNAMEm3005 P5E_PEX3_STN4_TX_C_DP<77>                                         
P  NNAMEm3006 P5E_PEX3_STN4_RX_DN<68>                                           
P  NNAMEm3007 SPI_MUX_PEX0_EN_N                                                 
P  NNAMEm3008 P5E_PEX3_STN4_RX_DP<67>                                           
P  NNAMEm3009 SPI_PEX0_SDIO1_MUX_R                                              
P  NNAMEm3010 P5E_PEX3_STN4_TX_C_DP<67>                                         
P  NNAMEm3011 SPI_PEX0_SDIO0_MUX_R                                              
P  NNAMEm3012 P5E_PEX3_STN4_RX_DN<70>                                           
P  NNAMEm3013 SPI_PEX0_SDIO3_R1                                                 
P  NNAMEm3014 P5E_PEX3_STN4_RX_DN<76>                                           
P  NNAMEm3015 P5E_PEX3_STN4_RX_DN<73>                                           
P  NNAMEm3016 P5E_PEX3_STN4_TX_C_DP<64>                                         
P  NNAMEm3017 SPI_PEX0_CLK_MUX_R                                                
P  NNAMEm3018 P5E_PEX3_STN4_TX_C_DP<68>                                         
P  NNAMEm3019 P5E_PEX3_STN4_TX_C_DP<76>                                         
P  NNAMEm3020 SPI_PEX0_CS_MUX_R_N                                               
P  NNAMEm3021 P5E_PEX3_STN4_TX_C_DN<64>                                         
P  NNAMEm3022 P5E_PEX3_STN4_RX_DP<69>                                           
P  NNAMEm3023 P5E_PEX3_STN4_RX_DP<71>                                           
P  NNAMEm3024 P5E_PEX3_STN4_RX_DP<75>                                           
P  NNAMEm3025 P5E_PEX3_STN4_TX_C_DN<75>                                         
P  NNAMEm3026 P5E_PEX3_STN4_RX_DN<65>                                           
P  NNAMEm3027 P5E_PEX3_STN4_RX_DN<78>                                           
P  NNAMEm3028 SPI_PEX1_CLK_MUX_R                                                
P  NNAMEm3029 P5E_PEX3_STN4_RX_DP<64>                                           
P  NNAMEm3030 P5E_PEX3_STN4_RX_DP<68>                                           
P  NNAMEm3031 SEL_FLASH_PEX3_BUF_R                                              
P  NNAMEm3032 SPI_PEX1_CS_MUX_R_N                                               
P  NNAMEm3033 P5E_PEX3_STN4_TX_C_DN<73>                                         
P  NNAMEm3034 SPI_PEX1_SDIO3_R1                                                 
P  NNAMEm3035 P5E_PEX3_STN4_RX_DP<65>                                           
P  NNAMEm3036 SPI_MUX_PEX1_EN_N                                                 
P  NNAMEm3037 P5E_PEX3_STN4_TX_C_DN<70>                                         
P  NNAMEm3038 SPI_PEX1_SDIO2_R1                                                 
P  NNAMEm3039 P5E_PEX3_STN4_TX_C_DP<78>                                         
P  NNAMEm3040 P5E_PEX3_STN4_RX_DP<73>                                           
P  NNAMEm3041 SPI_PEX1_SDIO0_MUX_R                                              
P  NNAMEm3042 P5E_PEX3_STN4_TX_C_DP<70>                                         
P  NNAMEm3043 SPI_PEX1_SDIO1_MUX_R                                              
P  NNAMEm3044 P5E_PEX3_STN4_TX_C_DP<69>                                         
P  NNAMEm3045 P5E_PEX3_STN4_RX_DN<79>                                           
P  NNAMEm3046 P5E_PEX3_STN4_TX_C_DN<66>                                         
P  NNAMEm3047 P5E_PEX3_STN4_TX_C_DN<77>                                         
P  NNAMEm3048 P5E_PEX3_STN4_RX_DP<76>                                           
P  NNAMEm3049 P5E_PEX3_STN4_TX_C_DP<79>                                         
P  NNAMEm3050 P5E_PEX3_STN4_TX_C_DN<71>                                         
P  NNAMEm3051 PWRGD_P12V_NIC0_R                                                 
P  NNAMEm3052 PWRGD_P12V_NIC0                                                   
P  NNAMEm3053 SPI_PEX3_CLK_MUX_R                                                
P  NNAMEm3054 SPI_PEX3_SDIO1_MUX_R                                              
P  NNAMEm3055 SPI_PEX3_SDIO3_R1                                                 
P  NNAMEm3056 SPI_PEX3_SDIO2_R1                                                 
P  NNAMEm3057 SPI_PEX3_CS_MUX_R_N                                               
P  NNAMEm3058 P5E_PEX2_STN4_TX_DN<78>                                           
P  NNAMEm3059 P5E_PEX2_STN4_TX_DP<67>                                           
P  NNAMEm3060 P5E_PEX2_STN4_TX_DP<68>                                           
P  NNAMEm3061 P5E_PEX2_STN4_TX_DP<66>                                           
P  NNAMEm3062 SPI_BIC1_CLK_LS23_R2                                              
P  NNAMEm3063 P5E_PEX2_STN4_TX_DP<71>                                           
P  NNAMEm3064 SPI_BIC1_CS0_LS23_R2_N                                            
P  NNAMEm3065 P5E_PEX2_STN4_TX_DN<68>                                           
P  NNAMEm3066 SPI_BIC1_MISO_LS23_R2                                             
P  NNAMEm3067 SPI_BIC1_MOSI_LS23_R2                                             
P  NNAMEm3068 P5E_PEX2_STN4_TX_DN<75>                                           
P  NNAMEm3069 P5E_PEX2_STN4_TX_DP<69>                                           
P  NNAMEm3070 SPI_BIC1_MOSI_LS23_R1                                             
P  NNAMEm3071 SPI_BIC1_MOSI_LS01_R2                                             
P  NNAMEm3072 SPI_BIC1_MISO_LS23_R1                                             
P  NNAMEm3073 SPI_BIC1_CLK_LS01_R2                                              
P  NNAMEm3074 SPI_BIC1_CS0_LS23_R1_N                                            
P  NNAMEm3075 SPI_BIC1_CS0_LS01_R2_N                                            
P  NNAMEm3076 P5E_PEX2_STN4_TX_DP<74>                                           
P  NNAMEm3077 SPI_BIC1_CLK_LS23_R1                                              
P  NNAMEm3078 SPI_BIC1_MISO_LS01_R2                                             
P  NNAMEm3079 P5E_PEX2_STN4_TX_DP<70>                                           
P  NNAMEm3080 SPI_BIC1_MISO_LS23                                                
P  NNAMEm3081 SPI_BIC1_MOSI_R4                                                  
P  NNAMEm3082 P5E_PEX2_STN4_TX_DP<77>                                           
P  NNAMEm3083 SPI_BIC1_CS0_LS23_N                                               
P  NNAMEm3084 SPI_BIC1_CLK_R4                                                   
P  NNAMEm3085 SPI_BIC1_CLK_LS23                                                 
P  NNAMEm3086 SPI_BIC1_CS0_R3_N                                                 
P  NNAMEm3087 P5E_PEX2_STN4_TX_DP<76>                                           
P  NNAMEm3088 SPI_BIC1_MOSI_LS23                                                
P  NNAMEm3089 SPI_BIC1_MISO_R4                                                  
P  NNAMEm3090 SPI_BIC1_MOSI_LS23_R                                              
P  NNAMEm3091 P5E_PEX2_STN4_TX_DN<76>                                           
P  NNAMEm3092 SPI_BIC1_CLK_LS23_R                                               
P  NNAMEm3093 P5E_PEX2_STN4_TX_DN<72>                                           
P  NNAMEm3094 SPI_BIC1_MISO_LS23_R                                              
P  NNAMEm3095 P5E_PEX2_STN4_TX_DN<66>                                           
P  NNAMEm3096 SPI_BIC1_CS0_LS23_R_N                                             
P  NNAMEm3097 P5E_PEX2_STN4_TX_DN<74>                                           
P  NNAMEm3098 P5E_PEX2_STN4_TX_DP<79>                                           
P  NNAMEm3099 P5E_PEX2_STN4_TX_DP<73>                                           
P  NNAMEm3100 P5E_PEX2_STN4_TX_DN<67>                                           
P  NNAMEm3101 P5E_PEX2_STN4_TX_DN<79>                                           
P  NNAMEm3102 P5E_PEX2_STN4_TX_DP<78>                                           
P  NNAMEm3103 P5E_PEX2_STN4_TX_DN<65>                                           
P  NNAMEm3104 P5E_PEX0_STN4_TX_C_DP<70>                                         
P  NNAMEm3105 P5E_PEX2_STN4_TX_DN<73>                                           
P  NNAMEm3106 P5E_PEX0_STN4_TX_C_DN<76>                                         
P  NNAMEm3107 P5E_PEX0_STN4_RX_DN<71>                                           
P  NNAMEm3108 P5E_PEX2_STN4_TX_DN<70>                                           
P  NNAMEm3109 P5E_PEX0_STN4_RX_DN<66>                                           
P  NNAMEm3110 P5E_PEX2_STN4_TX_DN<77>                                           
P  NNAMEm3111 SEL_FLASH_PEX2_BUF_R                                              
P  NNAMEm3112 P5E_PEX0_STN4_RX_DN<70>                                           
P  NNAMEm3113 P5E_PEX2_STN4_TX_DP<65>                                           
P  NNAMEm3114 P5E_PEX0_STN4_RX_DP<76>                                           
P  NNAMEm3115 P5E_PEX2_STN4_TX_DP<75>                                           
P  NNAMEm3116 P5E_PEX0_STN4_TX_C_DN<78>                                         
P  NNAMEm3117 P5E_PEX2_STN4_TX_DP<64>                                           
P  NNAMEm3118 P5E_PEX0_STN4_TX_C_DN<75>                                         
P  NNAMEm3119 P5E_PEX0_STN4_RX_DN<76>                                           
P  NNAMEm3120 PWRGD_P3V3_SSD0                                                   
P  NNAMEm3121 P5E_PEX0_STN4_RX_DP<73>                                           
P  NNAMEm3122 P5E_PEX0_STN4_TX_DN<75>                                           
P  NNAMEm3123 P5E_PEX0_STN4_TX_C_DP<67>                                         
P  NNAMEm3124 P5E_PEX0_STN4_TX_DN<74>                                           
P  NNAMEm3125 P5E_PEX2_STN4_TX_DN<64>                                           
P  NNAMEm3126 P5E_PEX0_STN4_RX_DP<79>                                           
P  NNAMEm3127 P5E_PEX0_STN4_RX_DN<75>                                           
P  NNAMEm3128 P5E_PEX0_STN4_TX_DP<73>                                           
P  NNAMEm3129 P5E_PEX2_STN4_TX_DN<69>                                           
P  NNAMEm3130 PWRGD_P3V3_SSD0_R                                                 
P  NNAMEm3131 P5E_PEX0_STN4_TX_C_DN<65>                                         
P  NNAMEm3132 P5E_PEX2_STN4_TX_DN<71>                                           
P  NNAMEm3133 SPI_PEX0_SDIO3_R                                                  
P  NNAMEm3134 P5E_PEX0_STN4_TX_C_DP<78>                                         
P  NNAMEm3135 P5E_PEX0_STN4_TX_DP<69>                                           
P  NNAMEm3136 P5E_PEX2_STN4_TX_DP<72>                                           
P  NNAMEm3137 SPI_PEX0_SDIO2_R                                                  
P  NNAMEm3138 P5E_PEX0_STN4_RX_DP<68>                                           
P  NNAMEm3139 P5E_PEX0_STN4_TX_DP<71>                                           
P  NNAMEm3140 P5E_PEX0_STN4_TX_C_DP<65>                                         
P  NNAMEm3141 P5E_PEX0_STN4_RX_DP<66>                                           
P  NNAMEm3142 P5E_PEX0_STN4_RX_DN<65>                                           
P  NNAMEm3143 P5E_PEX0_STN4_TX_DN<77>                                           
P  NNAMEm3144 P5E_PEX0_STN4_RX_DN<64>                                           
P  NNAMEm3145 SPI_PEX3_SDIO0_MUX_R                                              
P  NNAMEm3146 P5E_PEX0_STN4_TX_C_DP<72>                                         
P  NNAMEm3147 P5E_PEX2_STN4_RX_DP<74>                                           
P  NNAMEm3148 P5E_PEX0_STN4_TX_C_DN<71>                                         
P  NNAMEm3149 P5E_PEX0_STN4_TX_DN<66>                                           
P  NNAMEm3150 P5E_PEX2_STN4_TX_C_DN<65>                                         
P  NNAMEm3151 P5E_PEX0_STN4_RX_DN<79>                                           
P  NNAMEm3152 P5E_PEX0_STN4_TX_DN<79>                                           
P  NNAMEm3153 P5E_PEX2_STN4_RX_DN<79>                                           
P  NNAMEm3154 P5E_PEX0_STN4_RX_DP<65>                                           
P  NNAMEm3155 P5E_PEX2_STN4_RX_DP<70>                                           
P  NNAMEm3156 P5E_PEX0_STN4_TX_C_DN<69>                                         
P  NNAMEm3157 P5E_PEX0_STN4_TX_DP<78>                                           
P  NNAMEm3158 P5E_PEX2_STN4_RX_DN<78>                                           
P  NNAMEm3159 P5E_PEX0_STN4_TX_C_DP<74>                                         
P  NNAMEm3160 P5E_PEX2_STN4_TX_C_DP<78>                                         
P  NNAMEm3161 P5E_PEX0_STN4_RX_DP<75>                                           
P  NNAMEm3162 P5E_PEX0_STN4_TX_DP<77>                                           
P  NNAMEm3163 P5E_PEX2_STN4_TX_C_DP<66>                                         
P  NNAMEm3164 P5E_PEX0_STN4_TX_C_DN<77>                                         
P  NNAMEm3165 P5E_PEX0_STN4_TX_DP<64>                                           
P  NNAMEm3166 P5E_PEX2_STN4_RX_DN<68>                                           
P  NNAMEm3167 P5E_PEX0_STN4_TX_C_DP<75>                                         
P  NNAMEm3168 P5E_PEX2_STN4_RX_DN<64>                                           
P  NNAMEm3169 P5E_PEX0_STN4_TX_C_DP<76>                                         
P  NNAMEm3170 P5E_PEX0_STN4_TX_DP<79>                                           
P  NNAMEm3171 P5E_PEX2_STN4_TX_C_DP<70>                                         
P  NNAMEm3172 SPI_BIC1_LS23_EN_R_N                                              
P  NNAMEm3173 P5E_PEX0_STN4_RX_DP<77>                                           
P  NNAMEm3174 P5E_PEX2_STN4_RX_DN<77>                                           
P  NNAMEm3175 SPI_BIC1_LS23_EN_N                                                
P  NNAMEm3176 P5E_PEX0_STN4_RX_DP<74>                                           
P  NNAMEm3177 P5E_PEX2_STN4_TX_C_DP<75>                                         
P  NNAMEm3178 P5E_PEX0_STN4_RX_DP<64>                                           
P  NNAMEm3179 P5E_PEX2_STN4_RX_DP<79>                                           
P  NNAMEm3180 P5E_PEX0_STN4_TX_C_DN<66>                                         
P  NNAMEm3181 P5E_PEX0_STN4_TX_DP<67>                                           
P  NNAMEm3182 P5E_PEX2_STN4_RX_DN<71>                                           
P  NNAMEm3183 P5E_PEX0_STN4_RX_DP<67>                                           
P  NNAMEm3184 P5E_PEX0_STN4_TX_DN<69>                                           
P  NNAMEm3185 P5E_PEX2_STN4_TX_C_DN<77>                                         
P  NNAMEm3186 P5E_PEX0_STN4_TX_C_DN<72>                                         
P  NNAMEm3187 P5E_PEX2_STN4_TX_C_DP<73>                                         
P  NNAMEm3188 P5E_PEX0_STN4_RX_DP<72>                                           
P  NNAMEm3189 P5E_PEX2_STN4_TX_C_DN<73>                                         
P  NNAMEm3190 P5E_PEX0_STN4_TX_C_DN<79>                                         
P  NNAMEm3191 P5E_PEX2_STN4_RX_DN<65>                                           
P  NNAMEm3192 P5E_PEX0_STN4_RX_DP<71>                                           
P  NNAMEm3193 P5E_PEX0_STN4_TX_DP<65>                                           
P  NNAMEm3194 P5E_PEX2_STN4_RX_DP<67>                                           
P  NNAMEm3195 P5E_PEX0_STN4_RX_DN<73>                                           
P  NNAMEm3196 P5E_PEX2_STN4_RX_DN<66>                                           
P  NNAMEm3197 P5E_PEX0_STN4_RX_DN<77>                                           
P  NNAMEm3198 P5E_PEX2_STN4_RX_DN<74>                                           
P  NNAMEm3199 P5E_PEX0_STN4_RX_DP<70>                                           
P  NNAMEm3200 P5E_PEX0_STN4_TX_DN<78>                                           
P  NNAMEm3201 P5E_PEX2_STN4_RX_DN<72>                                           
P  NNAMEm3202 P5E_PEX0_STN4_TX_C_DN<74>                                         
P  NNAMEm3203 P5E_PEX2_STN4_TX_C_DN<71>                                         
P  NNAMEm3204 P5E_PEX0_STN4_RX_DN<68>                                           
P  NNAMEm3205 P5E_PEX0_STN4_TX_DN<72>                                           
P  NNAMEm3206 P5E_PEX2_STN4_TX_C_DP<79>                                         
P  NNAMEm3207 P5E_PEX0_STN4_TX_C_DP<79>                                         
P  NNAMEm3208 P5E_PEX2_STN4_TX_C_DP<67>                                         
P  NNAMEm3209 P5E_PEX0_STN4_RX_DN<67>                                           
P  NNAMEm3210 P5E_PEX2_STN4_RX_DP<75>                                           
P  NNAMEm3211 P5E_PEX0_STN4_TX_C_DP<68>                                         
P  NNAMEm3212 P5E_PEX0_STN4_TX_DN<71>                                           
P  NNAMEm3213 P5E_PEX2_STN4_TX_C_DN<72>                                         
P  NNAMEm3214 P5E_PEX0_STN4_TX_C_DN<67>                                         
P  NNAMEm3215 P5E_PEX0_STN4_TX_DP<68>                                           
P  NNAMEm3216 P5E_PEX2_STN4_RX_DN<67>                                           
P  NNAMEm3217 P5E_PEX0_STN4_RX_DN<69>                                           
P  NNAMEm3218 P5E_PEX2_STN4_TX_C_DN<75>                                         
P  NNAMEm3219 P5E_PEX0_STN4_RX_DP<78>                                           
P  NNAMEm3220 P5E_PEX0_STN4_TX_DN<67>                                           
P  NNAMEm3221 P5E_PEX2_STN4_RX_DN<75>                                           
P  NNAMEm3222 P5E_PEX0_STN4_RX_DN<74>                                           
P  NNAMEm3223 P5E_PEX0_STN4_TX_DN<65>                                           
P  NNAMEm3224 P5E_PEX2_STN4_TX_C_DN<79>                                         
P  NNAMEm3225 P5E_PEX0_STN4_TX_C_DN<73>                                         
P  NNAMEm3226 P5E_PEX2_STN4_RX_DP<77>                                           
P  NNAMEm3227 P5E_PEX0_STN4_TX_C_DP<73>                                         
P  NNAMEm3228 P5E_PEX2_STN4_TX_C_DP<69>                                         
P  NNAMEm3229 P5E_PEX0_STN4_RX_DN<72>                                           
P  NNAMEm3230 P5E_PEX0_STN4_TX_DN<64>                                           
P  NNAMEm3231 P5E_PEX2_STN4_RX_DN<70>                                           
P  NNAMEm3232 P5E_PEX0_STN4_TX_C_DP<69>                                         
P  NNAMEm3233 P5E_PEX0_STN4_TX_DP<74>                                           
P  NNAMEm3234 P5E_PEX2_STN4_RX_DN<73>                                           
P  NNAMEm3235 P5E_PEX0_STN4_TX_C_DP<71>                                         
P  NNAMEm3236 P5E_PEX2_STN4_TX_C_DP<65>                                         
P  NNAMEm3237 P5E_PEX0_STN4_TX_C_DP<66>                                         
P  NNAMEm3238 P5E_PEX0_STN4_TX_DP<76>                                           
P  NNAMEm3239 P5E_PEX2_STN4_TX_C_DP<74>                                         
P  NNAMEm3240 P5E_PEX0_STN4_TX_C_DN<64>                                         
P  NNAMEm3241 P5E_PEX0_STN4_TX_DN<68>                                           
P  NNAMEm3242 P5E_PEX2_STN4_RX_DP<68>                                           
P  NNAMEm3243 P5E_PEX0_STN4_RX_DN<78>                                           
P  NNAMEm3244 P5E_PEX2_STN4_TX_C_DN<66>                                         
P  NNAMEm3245 SPI_BIC1_MISO_R1                                                  
P  NNAMEm3246 SPI_BIC1_MOSI_R1                                                  
P  NNAMEm3247 SPI_BIC1_CLK_R1                                                   
P  NNAMEm3248 SPI_PEX0_SDIO0_MUX                                                
P  NNAMEm3249 SPI_PEX0_SDIO1_MUX                                                
P  NNAMEm3250 SPI_BIC1_MISO_R                                                   
P  NNAMEm3251 SPI_BIC1_LS01_EN_R_N                                              
P  NNAMEm3252 SPI_BIC1_LS01_EN_N                                                
P  NNAMEm3253 SW_P12V_P5V_AUX_FLT                                               
P  NNAMEm3254 SW_P12V_P3V3_AUX_FLT                                              
P  NNAMEm3255 SW_P12V_P1V8_PEX_FLT                                              
P  NNAMEm3256 A_P12V_AUX_FP_TRIGGER                                             
P  NNAMEm3257 A_P12V_AUX_ADR_TRIGGER                                            
P  NNAMEm3258 A_P12V_AUX_FPH_GATE                                               
P  NNAMEm3259 SPI_BIC1_CS0_R1_N                                                 
P  NNAMEm3260 SPI_BIC1_CLK_R2                                                   
P  NNAMEm3261 SPI_BIC1_MISO_R2                                                  
P  NNAMEm3262 SPI_BIC1_MOSI_R2                                                  
P  NNAMEm3263 SPI_BIC1_CS0_R2_N                                                 
P  NNAMEm3264 SPI_BIC1_CLK_R3                                                   
P  NNAMEm3265 SPI_BIC1_MOSI_R3                                                  
P  NNAMEm3266 SPI_BIC1_MISO_R3                                                  
P  NNAMEm3267 SPI_BIC1_MISO_LS01_R                                              
P  NNAMEm3268 SPI_BIC1_MOSI_LS01_R                                              
P  NNAMEm3269 SPI_BIC1_CLK_LS01_R                                               
P  NNAMEm3270 SPI_BIC1_CS0_LS01_R_N                                             
P  NNAMEm3271 SPI_BIC1_MISO_LS01                                                
P  NNAMEm3272 SPI_BIC1_MOSI_LS01                                                
P  NNAMEm3273 SPI_BIC1_CLK_LS01                                                 
P  NNAMEm3274 SPI_BIC1_CS0_LS01_N                                               
P  NNAMEm3275 SEL_FLASH_PEX1_BUF_R                                              
P  NNAMEm3276 SPI_MUX_PEX3_EN_N                                                 
P  NNAMEm3277 SPI_PEX0_CLK_MUX                                                  
P  NNAMEm3278 SPI_BIC1_MOSI_R                                                   
P  NNAMEm3279 SPI_BIC1_CS0_R_N                                                  
P  NNAMEm3280 SPI_PEX0_SDIO0_R                                                  
P  NNAMEm3281 SPI_PEX0_SDIO1_R                                                  
P  NNAMEm3282 SPI_PEX0_CS_R_N                                                   
P  NNAMEm3283 P5E_PEX1_STN6_RX_DP<107>                                          
P  NNAMEm3284 P5E_PEX1_STN6_RX_DN<107>                                          
P  NNAMEm3285 P5E_PEX0_STN6_RX_DP<107>                                          
P  NNAMEm3286 P5E_PEX0_STN6_RX_DN<107>                                          
P  NNAMEm3287 P5E_PEX1_STN6_TX_C_DP<107>                                        
P  NNAMEm3288 P5E_PEX1_STN6_TX_C_DN<107>                                        
P  NNAMEm3289 P5E_PEX0_STN6_TX_C_DP<107>                                        
P  NNAMEm3290 P5E_PEX0_STN6_TX_C_DN<107>                                        
P  NNAMEm3291 P5E_PEX1_STN6_TX_C_DP<106>                                        
P  NNAMEm3292 P5E_PEX1_STN6_RX_DP<106>                                          
P  NNAMEm3293 P5E_PEX1_STN6_RX_DN<106>                                          
P  NNAMEm3294 P5E_PEX0_STN6_RX_DP<106>                                          
P  NNAMEm3295 P5E_PEX0_STN6_RX_DN<106>                                          
P  NNAMEm3296 P5E_PEX1_STN6_TX_C_DN<106>                                        
P  NNAMEm3297 P5E_PEX0_STN6_TX_C_DP<106>                                        
P  NNAMEm3298 P5E_PEX0_STN6_TX_C_DN<106>                                        
P  NNAMEm3299 P5E_PEX1_STN6_TX_C_DP<105>                                        
P  NNAMEm3300 P5E_PEX1_STN6_RX_DP<105>                                          
P  NNAMEm3301 P5E_PEX1_STN6_RX_DN<105>                                          
P  NNAMEm3302 P5E_PEX0_STN6_RX_DP<105>                                          
P  NNAMEm3303 P5E_PEX0_STN6_RX_DN<105>                                          
P  NNAMEm3304 P5E_PEX1_STN6_TX_C_DN<105>                                        
P  NNAMEm3305 P5E_PEX0_STN6_TX_C_DP<105>                                        
P  NNAMEm3306 P5E_PEX0_STN6_TX_C_DN<105>                                        
P  NNAMEm3307 P5E_PEX1_STN6_TX_C_DP<104>                                        
P  NNAMEm3308 P5E_PEX1_STN6_RX_DP<104>                                          
P  NNAMEm3309 P5E_PEX1_STN6_RX_DN<104>                                          
P  NNAMEm3310 P5E_PEX0_STN6_RX_DP<104>                                          
P  NNAMEm3311 P5E_PEX0_STN6_RX_DN<104>                                          
P  NNAMEm3312 P5E_PEX1_STN6_TX_C_DN<104>                                        
P  NNAMEm3313 P5E_PEX0_STN6_TX_C_DP<104>                                        
P  NNAMEm3314 P5E_PEX0_STN6_TX_C_DN<104>                                        
P  NNAMEm3315 SPI_BIC1_MISO_LS01_R1                                             
P  NNAMEm3316 SPI_BIC1_CLK_LS01_R1                                              
P  NNAMEm3317 SPI_PEX0_CS_MUX_N                                                 
P  NNAMEm3318 SEL_FLASH_PEX0_BUF_R                                              
P  NNAMEm3319 SPI_BIC1_CS0_LS01_R1_N                                            
P  NNAMEm3320 SPI_BIC1_MOSI_LS01_R1                                             
P  NNAMEm3321 NC_P0V8_PEX0_PWM2                                                 
P  NNAMEm3322 SH_P0V8_PEX2_VSEN2_R                                              
P  NNAMEm3323 P0V8_PEX3_BVRRDY                                                  
P  NNAMEm3324 P0V8_PEX2_PINALRT                                                 
P  NNAMEm3325 P0V8_PEX2_VSEN2                                                   
P  NNAMEm3326 P0V8_PEX3_TSEN_R                                                  
P  NNAMEm3327 P0V8_PEX2_AVRRDY                                                  
P  NNAMEm3328 P0V8_PEX2_VRHOT_R                                                 
P  NNAMEm3329 NC_P0V8_PEX0_ISEN3                                                
P  NNAMEm3330 P0V8_PEX0_ISEN2                                                   
P  NNAMEm3331 PWRGD_P1V25_PEX3                                                  
P  NNAMEm3332 SW_P12V_P0V8_PEX2_FLT                                             
P  NNAMEm3333 SW_P12V_P1V25_PEX3_FLT                                            
P  NNAMEm3334 P1V25_SERDES_VDDPLL_PEX2                                          
P  NNAMEm3335 P0V8_PEX1_ISEN2                                                   
P  NNAMEm3336 NC_P0V8_PEX0_PWM3                                                 
P  NNAMEm3337 P0V8_PEX3_VSEN3                                                   
P  NNAMEm3338 SW_P1V25_PEX3_BT                                                  
P  NNAMEm3339 P0V8_PEX0_ISEN1                                                   
P  NNAMEm3340 VSENSE_P0V8_PEX3_SKT_VSEN                                         
P  NNAMEm3341 SH_P1V25_PEX3_FB_N                                                
P  NNAMEm3342 P0V8_PEX2_SMBALERT                                                
P  NNAMEm3343 SW_P1V25_PEX3_PH                                                  
P  NNAMEm3344 SH_P0V8_PEX3_VSEN3_R                                              
P  NNAMEm3345 SH_P1V25_PEX3_FB_P                                                
P  NNAMEm3346 FM_P0V8_PEX2_EN_R                                                 
P  NNAMEm3347 VSENSE_P0V8_PEX2_SKT_VRTN                                         
P  NNAMEm3348 FM_P0V8_PEX3_EN_R                                                 
P  NNAMEm3349 SMB_VR_P0V8_PEX2_SDA                                              
P  NNAMEm3350 P0V8_PEX1_ISEN1                                                   
P  NNAMEm3351 P0V8_PEX2_TSEN_R                                                  
P  NNAMEm3352 VSENSE_P0V8_PEX2_SKT_VSEN                                         
P  NNAMEm3353 NC_P0V8_PEX2_SVID_ALERT_N_R                                       
P  NNAMEm3354 P0V8_PEX2_IINSEN                                                  
P  NNAMEm3355 SW_P0V8_PEX2_PHASE2                                               
P  NNAMEm3356 SW_P0V8_PEX2_PH1                                                  
P  NNAMEm3357 SW_P0V8_PEX2_BOOT1_R                                              
P  NNAMEm3358 NC_P0V8_PEX0_PH2_NC3                                              
P  NNAMEm3359 NC_P0V8_PEX0_PH1_NC1                                              
P  NNAMEm3360 SW_P0V8_PEX2_BOOT1                                                
P  NNAMEm3361 NC_P0V8_PEX0_PH2_NC1                                              
P  NNAMEm3362 SW_P0V8_PEX2_BOOT2_R                                              
P  NNAMEm3363 SW_P0V8_PEX2_VOS2                                                 
P  NNAMEm3364 TDR_DIFF_85_IN1_DIN                                               
P  NNAMEm3365 SW_P0V8_PEX2_PHASE1                                               
P  NNAMEm3366 NC_P0V8_PEX0_PH1_NC3                                              
P  NNAMEm3367 TDR_SE_50_OHM_IN5                                                 
P  NNAMEm3368 P0V8_PEX2_LSET1                                                   
P  NNAMEm3369 NC_P0V8_PEX0_PH1_NC2                                              
P  NNAMEm3370 SW_P0V8_PEX2_VOS1                                                 
P  NNAMEm3371 TDR_DIFF_85_IN5_DIP                                               
P  NNAMEm3372 SW_P0V8_PEX2_BOOT2                                                
P  NNAMEm3373 SW_P0V8_PEX2_PH2                                                  
P  NNAMEm3374 P0V8_PEX2_LSET2                                                   
P  NNAMEm3375 TDR_DIFF_85_BOT_DIP                                               
P  NNAMEm3376 NC_P0V8_PEX0_PH2_NC2                                              
P  NNAMEm3377 TDR_SE_50_OHM_IN3                                                 
P  NNAMEm3378 TDR_SE_50_OHM_BOT                                                 
P  NNAMEm3379 TDR_DIFF_85_TOP_DIN                                               
P  NNAMEm3380 TDR_SE_50_OHM_IN2                                                 
P  NNAMEm3381 TDR_DIFF_85_IN4_DIN                                               
P  NNAMEm3382 TDR_DIFF_85_IN6_DIN                                               
P  NNAMEm3383 TDR_DIFF_85_IN4_DIP                                               
P  NNAMEm3384 TDR_SE_50_OHM_IN1                                                 
P  NNAMEm3385 TDR_DIFF_85_IN2_DIN                                               
P  NNAMEm3386 TDR_DIFF_85_TOP_DIP                                               
P  NNAMEm3387 TDR_DIFF_85_IN3_DIP                                               
P  NNAMEm3388 TDR_SE_50_OHM_IN4                                                 
P  NNAMEm3389 TDR_DIFF_85_IN1_DIP                                               
P  NNAMEm3390 SH_P1V25_PEX0_FB_N                                                
P  NNAMEm3391 TDR_DIFF_85_IN5_DIN                                               
P  NNAMEm3392 SW_P12V_P1V25_PEX0_FLT                                            
P  NNAMEm3393 TDR_SE_50_OHM_IN6                                                 
P  NNAMEm3394 PWRGD_P1V25_PEX0                                                  
P  NNAMEm3395 TDR_DIFF_85_IN3_DIN                                               
P  NNAMEm3396 SW_P1V25_PEX0_PH                                                  
P  NNAMEm3397 TDR_SE_50_OHM_TOP                                                 
P  NNAMEm3398 TDR_DIFF_85_BOT_DIN                                               
P  NNAMEm3399 SW_P1V25_PEX0_BT                                                  
P  NNAMEm3400 TDR_DIFF_85_IN2_DIP                                               
P  NNAMEm3401 SH_P1V25_PEX0_FB_P                                                
P  NNAMEm3402 TDR_DIFF_85_IN6_DIP                                               
P  NNAMEm3403 P0V8_PEX3_LSET1                                                   
P  NNAMEm3404 NC_P0V8_PEX1_PH2_NC1                                              
P  NNAMEm3405 SW_P0V8_PEX3_PH1                                                  
P  NNAMEm3406 NC_P0V8_PEX1_PH2_NC3                                              
P  NNAMEm3407 SW_P0V8_PEX3_VOS1                                                 
P  NNAMEm3408 SW_P0V8_PEX3_PH2                                                  
P  NNAMEm3409 SW_P0V8_PEX3_PHASE1                                               
P  NNAMEm3410 P0V8_PEX3_LSET2                                                   
P  NNAMEm3411 NC_P0V8_PEX1_PH1_NC2                                              
P  NNAMEm3412 NC_P0V8_PEX1_PH2_NC2                                              
P  NNAMEm3413 SW_P0V8_PEX3_BOOT2                                                
P  NNAMEm3414 NC_P0V8_PEX1_PH1_NC3                                              
P  NNAMEm3415 SW_P0V8_PEX3_BOOT1_R                                              
P  NNAMEm3416 SW_P0V8_PEX3_BOOT2_R                                              
P  NNAMEm3417 SW_P0V8_PEX3_VOS2                                                 
P  NNAMEm3418 P0V8_SERDES_VDDA_PEX3                                             
P  NNAMEm3419 SW_P0V8_PEX3_BOOT1                                                
P  NNAMEm3420 NC_P0V8_PEX1_PH1_NC1                                              
P  NNAMEm3421 P0V8_SERDES_VDDA_PEX2                                             
P  NNAMEm3422 SW_P0V8_PEX3_PHASE2                                               
P  NNAMEm3423 SW_P12V_P1V25_PEX2_FLT                                            
P  NNAMEm3424 SW_P1V25_PEX2_BT                                                  
P  NNAMEm3425 SH_P1V25_PEX2_FB_P                                                
P  NNAMEm3426 SH_P1V25_PEX2_FB_N                                                
P  NNAMEm3427 PWRGD_P1V25_PEX2                                                  
P  NNAMEm3428 SW_P1V25_PEX2_PH                                                  
P  NNAMEm3429 P1V25_SERDES_VDDPLL_PEX3                                          
P  NNAMEm3430 SW_P1V25_PEX1_BT                                                  
P  NNAMEm3431 PWRGD_P1V25_PEX1                                                  
P  NNAMEm3432 SH_P1V25_PEX1_FB_P                                                
P  NNAMEm3433 SW_P1V25_PEX1_PH                                                  
P  NNAMEm3434 SW_P12V_P1V25_PEX1_FLT                                            
P  NNAMEm3435 P0V8_SERDES_VDDA_PEX1                                             
P  NNAMEm3436 SH_P1V25_PEX1_FB_N                                                
P  NNAMEm3437 P1V25_SERDES_VDDPLL_PEX1                                          
P  NNAMEm3438 SMB_VR_P0V8_PEX2_SCL                                              
P  NNAMEm3439 VSENSE_P0V8_PEX3_SKT_VRTN                                         
P  NNAMEm3440 NC_P0V8_PEX0_ISEN2                                                
P  NNAMEm3441 P0V8_PEX2_VR_CONFIG                                               
P  NNAMEm3442 P0V8_PEX2_VINSEN                                                  
P  NNAMEm3443 SW_P0V8_PEX0_PHASE1                                               
P  NNAMEm3444 P0V8_PEX0_LSET1                                                   
P  NNAMEm3445 SW_P0V8_PEX0_BOOT1_R                                              
P  NNAMEm3446 SW_P0V8_PEX0_PH2                                                  
P  NNAMEm3447 SW_P0V8_PEX0_PHASE2                                               
P  NNAMEm3448 SW_P0V8_PEX1_VOS1                                                 
P  NNAMEm3449 SW_P0V8_PEX1_VOS2                                                 
P  NNAMEm3450 SW_P0V8_PEX1_PHASE1                                               
P  NNAMEm3451 SW_P0V8_PEX1_PH1                                                  
P  NNAMEm3452 SW_P12V_P0V8_PEX1_FLT                                             
P  NNAMEm3453 SW_P0V8_PEX1_PH2                                                  
P  NNAMEm3454 SW_P0V8_PEX1_BOOT1                                                
P  NNAMEm3455 P0V8_PEX1_LSET2                                                   
P  NNAMEm3456 SW_P0V8_PEX1_BOOT1_R                                              
P  NNAMEm3457 SW_P0V8_PEX1_PHASE2                                               
P  NNAMEm3458 SW_P0V8_PEX1_BOOT2_R                                              
P  NNAMEm3459 SW_P0V8_PEX1_BOOT2                                                
P  NNAMEm3460 P0V8_PEX1_LSET1                                                   
P  NNAMEm3461 P0V8_PEX0_VSEN0                                                   
P  NNAMEm3462 VSENSE_P0V8_PEX1_SKT_VSEN                                         
P  NNAMEm3463 FM_P0V8_PEX0_EN_R                                                 
P  NNAMEm3464 SMB_VR_P0V8_PEX0_SDA                                              
P  NNAMEm3465 SMB_HOTSWAP_SCL_R                                                 
P  NNAMEm3466 P0V8_PEX0_IINSEN                                                  
P  NNAMEm3467 P0V8_PEX0_AVRRDY                                                  
P  NNAMEm3468 P0V8_PEX0_VR_CONFIG                                               
P  NNAMEm3469 P0V8_PEX0_VINSEN                                                  
P  NNAMEm3470 SH_P0V8_PEX1_VSEN1_R                                              
P  NNAMEm3471 SMB_VR_P0V8_PEX0_SCL                                              
P  NNAMEm3472 FM_P0V8_PEX1_EN_R                                                 
P  NNAMEm3473 P0V8_PEX0_VRHOT_R                                                 
P  NNAMEm3474 VSENSE_P0V8_PEX0_SKT_VRTN                                         
P  NNAMEm3475 VSENSE_P0V8_PEX0_SKT_VSEN                                         
P  NNAMEm3476 P0V8_PEX1_BVRRDY                                                  
P  NNAMEm3477 NC_P0V8_PEX0_SVID_ALERT_N_R                                       
P  NNAMEm3478 P0V8_PEX1_VSEN1                                                   
P  NNAMEm3479 P0V8_PEX1_TSEN_R                                                  
P  NNAMEm3480 SW_P12V_P0V8_PEX0_FLT                                             
P  NNAMEm3481 VSENSE_P0V8_PEX1_SKT_VRTN                                         
P  NNAMEm3482 P0V8_PEX0_PINALRT                                                 
P  NNAMEm3483 SH_P0V8_PEX0_VSEN0_R                                              
P  NNAMEm3484 P0V8_PEX0_TSEN_R                                                  
P  NNAMEm3485 SW_P0V8_PEX0_BOOT2_R                                              
P  NNAMEm3486 SW_P0V8_PEX0_BOOT2                                                
P  NNAMEm3487 SW_P0V8_PEX0_PH1                                                  
P  NNAMEm3488 P0V8_PEX0_LSET2                                                   
P  NNAMEm3489 SW_P0V8_PEX0_BOOT1                                                
P  NNAMEm3490 SW_P0V8_PEX0_VOS1                                                 
P  NNAMEm3491 SW_P0V8_PEX0_VOS2                                                 
P  NNAMEm3492 P1V25_SERDES_VDDPLL_PEX0                                          
P  NNAMEm3493 P5E_PEX2_STN5_TX_C_DN<82>                                         
P  NNAMEm3494 P5E_PEX2_STN5_TX_C_DP<82>                                         
P  NNAMEm3495 P0V8_SERDES_VDDA_PEX0                                             
P  NNAMEm3496 P5E_PEX3_STN5_TX_C_DP<82>                                         
P  NNAMEm3497 P5E_PEX3_STN5_TX_C_DN<82>                                         
P  NNAMEm3498 P5E_PEX1_STN0_TX_C_DN<8>                                          
P  NNAMEm3499 P5E_PEX1_STN0_RX_DP<1>                                            
P  NNAMEm3500 P5E_PEX1_STN0_RX_DP<15>                                           
P  NNAMEm3501 P5E_PEX1_STN0_TX_C_DP<2>                                          
P  NNAMEm3502 P5E_PEX1_STN0_TX_C_DN<4>                                          
P  NNAMEm3503 P5E_PEX1_STN0_TX_C_DN<6>                                          
P  NNAMEm3504 P5E_PEX1_STN0_TX_C_DP<12>                                         
P  NNAMEm3505 P5E_PEX1_STN0_TX_C_DP<7>                                          
P  NNAMEm3506 P5E_PEX1_STN0_RX_DN<12>                                           
P  NNAMEm3507 P5E_PEX1_STN0_TX_C_DP<14>                                         
P  NNAMEm3508 P5E_PEX1_STN0_RX_DN<14>                                           
P  NNAMEm3509 P5E_PEX1_STN0_RX_DP<13>                                           
P  NNAMEm3510 P5E_PEX1_STN0_TX_C_DN<3>                                          
P  NNAMEm3511 P5E_PEX1_STN0_TX_C_DP<11>                                         
P  NNAMEm3512 P5E_PEX1_STN0_RX_DP<14>                                           
P  NNAMEm3513 P5E_PEX1_STN0_TX_C_DN<0>                                          
P  NNAMEm3514 P5E_PEX1_STN0_TX_C_DP<0>                                          
P  NNAMEm3515 P5E_PEX1_STN0_TX_C_DP<8>                                          
P  NNAMEm3516 P5E_PEX1_STN0_RX_DP<8>                                            
P  NNAMEm3517 P5E_PEX1_STN0_TX_C_DN<13>                                         
P  NNAMEm3518 P5E_PEX1_STN0_TX_C_DN<12>                                         
P  NNAMEm3519 P5E_PEX1_STN0_RX_DP<11>                                           
P  NNAMEm3520 P5E_PEX1_STN0_RX_DN<4>                                            
P  NNAMEm3521 P5E_PEX1_STN0_TX_C_DP<1>                                          
P  NNAMEm3522 P5E_PEX1_STN0_TX_C_DP<5>                                          
P  NNAMEm3523 P5E_PEX1_STN0_RX_DP<5>                                            
P  NNAMEm3524 P5E_PEX1_STN0_TX_C_DN<5>                                          
P  NNAMEm3525 P5E_PEX1_STN0_RX_DN<0>                                            
P  NNAMEm3526 P5E_PEX1_STN0_RX_DN<10>                                           
P  NNAMEm3527 P5E_PEX1_STN0_RX_DN<9>                                            
P  NNAMEm3528 P5E_PEX1_STN0_RX_DP<10>                                           
P  NNAMEm3529 P5E_PEX1_STN0_TX_C_DN<9>                                          
P  NNAMEm3530 P5E_PEX1_STN0_RX_DN<13>                                           
P  NNAMEm3531 P5E_PEX1_STN0_RX_DN<7>                                            
P  NNAMEm3532 P5E_PEX1_STN0_RX_DN<11>                                           
P  NNAMEm3533 P5E_PEX1_STN0_RX_DP<4>                                            
P  NNAMEm3534 P5E_PEX1_STN0_RX_DP<7>                                            
P  NNAMEm3535 P5E_PEX1_STN0_RX_DP<12>                                           
P  NNAMEm3536 P5E_PEX1_STN0_TX_C_DN<15>                                         
P  NNAMEm3537 P5E_PEX1_STN0_RX_DP<9>                                            
P  NNAMEm3538 P5E_PEX1_STN0_RX_DN<5>                                            
P  NNAMEm3539 P5E_PEX1_STN0_TX_C_DN<1>                                          
P  NNAMEm3540 P5E_PEX1_STN0_TX_C_DP<4>                                          
P  NNAMEm3541 P5E_PEX1_STN0_TX_C_DP<3>                                          
P  NNAMEm3542 P5E_PEX1_STN0_RX_DN<15>                                           
P  NNAMEm3543 P5E_PEX1_STN0_TX_C_DN<14>                                         
P  NNAMEm3544 P5E_PEX1_STN0_RX_DP<3>                                            
P  NNAMEm3545 P5E_PEX1_STN0_TX_C_DN<7>                                          
P  NNAMEm3546 P5E_PEX1_STN0_RX_DN<2>                                            
P  NNAMEm3547 P5E_PEX1_STN0_RX_DN<3>                                            
P  NNAMEm3548 P5E_PEX1_STN0_RX_DN<1>                                            
P  NNAMEm3549 P5E_PEX1_STN0_RX_DP<6>                                            
P  NNAMEm3550 P5E_PEX1_STN0_RX_DP<0>                                            
P  NNAMEm3551 P5E_PEX1_STN0_RX_DN<8>                                            
P  NNAMEm3552 P5E_PEX1_STN0_TX_C_DP<9>                                          
P  NNAMEm3553 P5E_PEX1_STN0_TX_C_DN<11>                                         
P  NNAMEm3554 P5E_PEX1_STN0_TX_C_DP<10>                                         
P  NNAMEm3555 P5E_PEX1_STN0_TX_C_DP<15>                                         
P  NNAMEm3556 P5E_PEX1_STN0_TX_C_DP<6>                                          
P  NNAMEm3557 P5E_PEX1_STN0_TX_C_DN<10>                                         
P  NNAMEm3558 P5E_PEX1_STN0_TX_C_DP<13>                                         
P  NNAMEm3559 P5E_PEX1_STN0_RX_DN<6>                                            
P  NNAMEm3560 P5E_PEX1_STN0_TX_C_DN<2>                                          
P  NNAMEm3561 P5E_PEX1_STN0_RX_DP<2>                                            
P  NNAMEm3562 RST_NIC5_PERST1_R_N                                               
P  NNAMEm3563 NCSI_NIC5_TX_EN                                                   
P  NNAMEm3564 P5E_PEX0_STN2_RX_DP<34>                                           
P  NNAMEm3565 P5E_PEX3_STN2_TX_C_DN<37>                                         
P  NNAMEm3566 P5E_PEX2_STN7_RX_DN<113>                                          
P  NNAMEm3567 P5E_PEX3_STN2_RX_DN<43>                                           
P  NNAMEm3568 P5E_PEX3_STN2_RX_DP<44>                                           
P  NNAMEm3569 P5E_PEX3_STN2_TX_C_DN<44>                                         
P  NNAMEm3570 DUALPORT_N_SSD7                                                   
P  NNAMEm3571 P5E_PEX0_STN2_RX_DP<39>                                           
P  NNAMEm3572 P5E_PEX3_STN2_RX_DP<39>                                           
P  NNAMEm3573 DUALPORT_N_SSD6                                                   
P  NNAMEm3574 P5E_PEX0_STN2_RX_DP<38>                                           
P  NNAMEm3575 P5E_PEX2_STN7_TX_C_DN<112>                                        
P  NNAMEm3576 P5E_PEX3_STN2_TX_C_DP<38>                                         
P  NNAMEm3577 P5E_PEX2_STN7_RX_DN<116>                                          
P  NNAMEm3578 P5E_PEX3_STN2_TX_C_DN<40>                                         
P  NNAMEm3579 P5E_PEX3_STN2_TX_C_DN<32>                                         
P  NNAMEm3580 P5E_PEX2_STN7_TX_C_DN<114>                                        
P  NNAMEm3581 P5E_PEX3_STN2_TX_C_DN<45>                                         
P  NNAMEm3582 PWRGD_NIC5_PWR_GOOD                                               
P  NNAMEm3583 P5E_PEX2_STN7_RX_DN<119>                                          
P  NNAMEm3584 P5E_PEX3_STN2_RX_DP<33>                                           
P  NNAMEm3585 DUALPORT_N_SSD14                                                  
P  NNAMEm3586 P5E_PEX2_STN7_TX_C_DN<113>                                        
P  NNAMEm3587 P5E_PEX3_STN2_RX_DN<41>                                           
P  NNAMEm3588 NIC5_AUX_PWR_EN_R                                                 
P  NNAMEm3589 DUALPORT_N_SSD15                                                  
P  NNAMEm3590 P5E_PEX0_STN0_TX_C_DN<3>                                          
P  NNAMEm3591 P5E_PEX3_STN2_TX_C_DN<39>                                         
P  NNAMEm3592 NCSI_NIC5_CRS_DV                                                  
P  NNAMEm3593 P5E_PEX0_STN0_TX_C_DN<11>                                         
P  NNAMEm3594 P5E_PEX2_STN7_RX_DN<112>                                          
P  NNAMEm3595 P5E_PEX3_STN2_TX_C_DP<40>                                         
P  NNAMEm3596 P5E_PEX0_STN0_TX_C_DP<1>                                          
P  NNAMEm3597 P5E_PEX3_STN2_RX_DN<39>                                           
P  NNAMEm3598 P5E_PEX0_STN0_RX_DN<11>                                           
P  NNAMEm3599 P5E_PEX3_STN2_TX_C_DP<42>                                         
P  NNAMEm3600 HP_NIC2_PWRGD_R                                                   
P  NNAMEm3601 NIC5_MAIN_PWR_EN_R                                                
P  NNAMEm3602 P5E_PEX0_STN0_RX_DP<1>                                            
P  NNAMEm3603 P5E_PEX2_STN7_RX_DN<117>                                          
P  NNAMEm3604 P5E_PEX3_STN2_RX_DP<35>                                           
P  NNAMEm3605 P5E_PEX0_STN0_TX_C_DN<2>                                          
P  NNAMEm3606 P5E_PEX2_STN7_TX_C_DP<115>                                        
P  NNAMEm3607 P5E_PEX3_STN2_TX_C_DN<42>                                         
P  NNAMEm3608 P5E_PEX0_STN0_RX_DP<8>                                            
P  NNAMEm3609 P5E_PEX2_STN7_TX_C_DN<116>                                        
P  NNAMEm3610 P5E_PEX3_STN2_RX_DP<36>                                           
P  NNAMEm3611 RST_NIC5_PERST2_R_N                                               
P  NNAMEm3612 P5E_PEX0_STN0_TX_C_DP<14>                                         
P  NNAMEm3613 P5E_PEX2_STN7_RX_DN<118>                                          
P  NNAMEm3614 P5E_PEX3_STN2_TX_C_DN<41>                                         
P  NNAMEm3615 P5E_PEX0_STN0_TX_C_DP<12>                                         
P  NNAMEm3616 P5E_PEX3_STN2_TX_C_DN<43>                                         
P  NNAMEm3617 P5E_PEX0_STN0_RX_DN<2>                                            
P  NNAMEm3618 P5E_PEX3_STN2_RX_DN<40>                                           
P  NNAMEm3619 P5E_PEX0_STN0_TX_C_DP<4>                                          
P  NNAMEm3620 P5E_PEX2_STN7_TX_C_DP<112>                                        
P  NNAMEm3621 P5E_PEX3_STN2_RX_DP<38>                                           
P  NNAMEm3622 NIC5_RBT_ARB_IN                                                   
P  NNAMEm3623 P5E_PEX0_STN0_RX_DP<3>                                            
P  NNAMEm3624 P5E_PEX2_STN7_TX_C_DP<114>                                        
P  NNAMEm3625 P5E_PEX3_STN2_RX_DN<45>                                           
P  NNAMEm3626 P5E_PEX3_STN7_TX_C_DN<118>                                        
P  NNAMEm3627 CLK_50M_NIC5_RBT_REF                                              
P  NNAMEm3628 P5E_PEX0_STN0_TX_C_DN<9>                                          
P  NNAMEm3629 P5E_PEX3_STN2_TX_C_DP<34>                                         
P  NNAMEm3630 P5E_PEX3_STN7_TX_C_DP<113>                                        
P  NNAMEm3631 NIC5_RBT_ARB_OUT                                                  
P  NNAMEm3632 P5E_PEX0_STN0_RX_DN<13>                                           
P  NNAMEm3633 P5E_PEX3_STN2_RX_DN<46>                                           
P  NNAMEm3634 P5E_PEX3_STN7_RX_DP<112>                                          
P  NNAMEm3635 P5E_PEX0_STN0_TX_C_DN<14>                                         
P  NNAMEm3636 P5E_PEX2_STN1_RX_DP<26>                                           
P  NNAMEm3637 P5E_PEX3_STN2_RX_DP<42>                                           
P  NNAMEm3638 P5E_PEX3_STN7_RX_DN<123>                                          
P  NNAMEm3639 P5E_PEX0_STN0_RX_DP<5>                                            
P  NNAMEm3640 P5E_PEX2_STN1_TX_C_DP<26>                                         
P  NNAMEm3641 P5E_PEX3_STN2_RX_DN<36>                                           
P  NNAMEm3642 P5E_PEX3_STN7_TX_C_DP<124>                                        
P  NNAMEm3643 P5E_PEX0_STN0_TX_C_DP<0>                                          
P  NNAMEm3644 P5E_PEX2_STN1_TX_C_DP<28>                                         
P  NNAMEm3645 P5E_PEX2_STN7_RX_DP<119>                                          
P  NNAMEm3646 P5E_PEX3_STN2_TX_C_DP<39>                                         
P  NNAMEm3647 P5E_PEX3_STN7_RX_DP<119>                                          
P  NNAMEm3648 P5E_PEX0_STN0_TX_C_DP<10>                                         
P  NNAMEm3649 P5E_PEX2_STN1_RX_DP<29>                                           
P  NNAMEm3650 P5E_PEX3_STN2_RX_DN<42>                                           
P  NNAMEm3651 P5E_PEX3_STN7_RX_DP<123>                                          
P  NNAMEm3652 RST_NIC5_PERST0_R_N                                               
P  NNAMEm3653 P5E_PEX0_STN0_RX_DN<4>                                            
P  NNAMEm3654 P5E_PEX1_STN5_TX_C_DP<81>                                         
P  NNAMEm3655 P5E_PEX2_STN1_RX_DN<25>                                           
P  NNAMEm3656 P5E_PEX2_STN7_TX_C_DN<117>                                        
P  NNAMEm3657 P5E_PEX3_STN2_RX_DP<34>                                           
P  NNAMEm3658 P5E_PEX3_STN7_TX_C_DN<126>                                        
P  NNAMEm3659 RST_NIC5_PERST3_R_N                                               
P  NNAMEm3660 P5E_PEX0_STN0_RX_DN<14>                                           
P  NNAMEm3661 P5E_PEX2_STN1_RX_DN<21>                                           
P  NNAMEm3662 P5E_PEX2_STN7_RX_DP<116>                                          
P  NNAMEm3663 P5E_PEX3_STN2_RX_DP<46>                                           
P  NNAMEm3664 P5E_PEX3_STN7_TX_C_DP<117>                                        
P  NNAMEm3665 RST_SMB_NIC2_MUX_ISO_R_N                                          
P  NNAMEm3666 P5E_PEX0_STN0_TX_C_DP<8>                                          
P  NNAMEm3667 P5E_PEX2_STN1_RX_DN<30>                                           
P  NNAMEm3668 P5E_PEX3_STN2_RX_DP<43>                                           
P  NNAMEm3669 P5E_PEX3_STN7_RX_DN<125>                                          
P  NNAMEm3670 RST_SMB_NIC5_MUX_ISO_R_N                                          
P  NNAMEm3671 P5E_PEX0_STN0_TX_C_DP<13>                                         
P  NNAMEm3672 P5E_PEX2_STN1_RX_DN<17>                                           
P  NNAMEm3673 P5E_PEX3_STN2_TX_C_DN<47>                                         
P  NNAMEm3674 P5E_PEX3_STN7_TX_C_DN<116>                                        
P  NNAMEm3675 NIC2_RBT_ARB_OUT                                                  
P  NNAMEm3676 P5E_PEX0_STN0_TX_C_DP<5>                                          
P  NNAMEm3677 P5E_PEX2_STN1_TX_C_DN<16>                                         
P  NNAMEm3678 P5E_PEX3_STN2_RX_DP<37>                                           
P  NNAMEm3679 P5E_PEX3_STN7_RX_DN<120>                                          
P  NNAMEm3680 NCSI_NIC2_CRS_DV                                                  
P  NNAMEm3681 P5E_PEX0_STN0_TX_C_DN<13>                                         
P  NNAMEm3682 P5E_PEX2_STN1_TX_C_DP<24>                                         
P  NNAMEm3683 P5E_PEX2_STN7_RX_DP<118>                                          
P  NNAMEm3684 P5E_PEX3_STN2_TX_C_DP<32>                                         
P  NNAMEm3685 P5E_PEX3_STN7_TX_C_DP<112>                                        
P  NNAMEm3686 P5E_PEX0_STN0_TX_C_DN<5>                                          
P  NNAMEm3687 P5E_PEX2_STN1_TX_C_DN<28>                                         
P  NNAMEm3688 P5E_PEX3_STN2_RX_DN<38>                                           
P  NNAMEm3689 P5E_PEX3_STN7_RX_DN<126>                                          
P  NNAMEm3690 P5E_PEX0_STN0_TX_C_DP<15>                                         
P  NNAMEm3691 P5E_PEX2_STN1_RX_DN<26>                                           
P  NNAMEm3692 P5E_PEX3_STN2_TX_C_DN<33>                                         
P  NNAMEm3693 P5E_PEX3_STN7_RX_DP<118>                                          
P  NNAMEm3694 NIC2_RBT_ARB_IN                                                   
P  NNAMEm3695 P5E_PEX0_STN0_RX_DP<10>                                           
P  NNAMEm3696 P5E_PEX2_STN1_RX_DP<22>                                           
P  NNAMEm3697 P5E_PEX2_STN7_RX_DP<117>                                          
P  NNAMEm3698 P5E_PEX3_STN2_TX_C_DP<37>                                         
P  NNAMEm3699 P5E_PEX3_STN7_TX_C_DN<119>                                        
P  NNAMEm3700 P5E_PEX0_STN0_TX_C_DN<6>                                          
P  NNAMEm3701 P5E_PEX2_STN1_TX_C_DP<30>                                         
P  NNAMEm3702 P5E_PEX2_STN7_RX_DP<114>                                          
P  NNAMEm3703 P5E_PEX3_STN2_RX_DP<45>                                           
P  NNAMEm3704 P5E_PEX3_STN7_RX_DN<124>                                          
P  NNAMEm3705 NIC2_MAIN_PWR_EN_R                                                
P  NNAMEm3706 P5E_PEX0_STN0_RX_DN<9>                                            
P  NNAMEm3707 P5E_PEX2_STN1_TX_C_DN<18>                                         
P  NNAMEm3708 P5E_PEX2_STN7_TX_C_DP<118>                                        
P  NNAMEm3709 P5E_PEX3_STN2_RX_DN<35>                                           
P  NNAMEm3710 P5E_PEX3_STN7_TX_C_DP<125>                                        
P  NNAMEm3711 P5E_PEX0_STN0_RX_DP<14>                                           
P  NNAMEm3712 P5E_PEX2_STN1_RX_DN<19>                                           
P  NNAMEm3713 P5E_PEX2_STN7_TX_C_DP<117>                                        
P  NNAMEm3714 P5E_PEX3_STN2_TX_C_DP<45>                                         
P  NNAMEm3715 P5E_PEX3_STN7_RX_DP<124>                                          
P  NNAMEm3716 P5E_PEX0_STN0_RX_DN<10>                                           
P  NNAMEm3717 P5E_PEX2_STN1_RX_DP<30>                                           
P  NNAMEm3718 P5E_PEX3_STN2_RX_DN<44>                                           
P  NNAMEm3719 P5E_PEX3_STN7_TX_C_DN<125>                                        
P  NNAMEm3720 P5E_PEX0_STN0_TX_C_DP<2>                                          
P  NNAMEm3721 P5E_PEX2_STN1_TX_C_DN<22>                                         
P  NNAMEm3722 P5E_PEX3_STN2_TX_C_DP<47>                                         
P  NNAMEm3723 P5E_PEX3_STN7_RX_DP<113>                                          
P  NNAMEm3724 P5E_PEX0_STN0_RX_DP<6>                                            
P  NNAMEm3725 P5E_PEX1_STN5_TX_C_DP<82>                                         
P  NNAMEm3726 P5E_PEX2_STN1_TX_C_DN<23>                                         
P  NNAMEm3727 P5E_PEX3_STN2_TX_C_DN<35>                                         
P  NNAMEm3728 P5E_PEX3_STN7_RX_DP<125>                                          
P  NNAMEm3729 P5E_PEX0_STN0_RX_DN<1>                                            
P  NNAMEm3730 P5E_PEX1_STN5_TX_C_DN<81>                                         
P  NNAMEm3731 P5E_PEX2_STN1_TX_C_DN<29>                                         
P  NNAMEm3732 P5E_PEX3_STN2_TX_C_DN<38>                                         
P  NNAMEm3733 P5E_PEX3_STN7_TX_C_DN<121>                                        
P  NNAMEm3734 RST_NIC2_PERST2_R_N                                               
P  NNAMEm3735 P5E_PEX0_STN0_TX_C_DN<15>                                         
P  NNAMEm3736 P5E_PEX2_STN1_TX_C_DP<20>                                         
P  NNAMEm3737 P5E_PEX3_STN2_TX_C_DP<35>                                         
P  NNAMEm3738 P5E_PEX3_STN7_RX_DP<114>                                          
P  NNAMEm3739 P5E_PEX0_STN0_TX_C_DP<7>                                          
P  NNAMEm3740 P5E_PEX2_STN1_TX_C_DP<25>                                         
P  NNAMEm3741 P5E_PEX3_STN2_TX_C_DN<34>                                         
P  NNAMEm3742 P5E_PEX3_STN7_TX_C_DN<115>                                        
P  NNAMEm3743 CLK_50M_NIC2_RBT_REF                                              
P  NNAMEm3744 P5E_PEX0_STN0_RX_DN<5>                                            
P  NNAMEm3745 P5E_PEX1_STN5_TX_C_DN<82>                                         
P  NNAMEm3746 P5E_PEX2_STN1_TX_C_DP<21>                                         
P  NNAMEm3747 P5E_PEX2_STN5_TX_C_DP<86>                                         
P  NNAMEm3748 P5E_PEX3_STN2_RX_DN<33>                                           
P  NNAMEm3749 P5E_PEX3_STN7_TX_C_DN<113>                                        
P  NNAMEm3750 HP_NIC7_PWRGD_R                                                   
P  NNAMEm3751 P5E_PEX0_STN0_RX_DN<6>                                            
P  NNAMEm3752 P5E_PEX2_STN1_RX_DP<17>                                           
P  NNAMEm3753 P5E_PEX3_STN2_TX_C_DP<33>                                         
P  NNAMEm3754 P5E_PEX3_STN7_RX_DP<116>                                          
P  NNAMEm3755 P5E_PEX0_STN0_RX_DP<7>                                            
P  NNAMEm3756 P5E_PEX2_STN1_RX_DP<31>                                           
P  NNAMEm3757 P5E_PEX3_STN2_RX_DN<34>                                           
P  NNAMEm3758 P5E_PEX3_STN7_TX_C_DP<114>                                        
P  NNAMEm3759 NCSI_NIC2_TX_EN                                                   
P  NNAMEm3760 P5E_PEX0_STN0_RX_DP<11>                                           
P  NNAMEm3761 P5E_PEX2_STN1_RX_DN<22>                                           
P  NNAMEm3762 P5E_PEX3_STN2_RX_DP<32>                                           
P  NNAMEm3763 P5E_PEX3_STN7_TX_C_DP<127>                                        
P  NNAMEm3764 P5E_PEX0_STN0_TX_C_DN<12>                                         
P  NNAMEm3765 P5E_PEX1_STN6_RX_DN<108>                                          
P  NNAMEm3766 P5E_PEX2_STN1_RX_DP<28>                                           
P  NNAMEm3767 P5E_PEX3_STN2_RX_DN<32>                                           
P  NNAMEm3768 P5E_PEX3_STN7_TX_C_DP<122>                                        
P  NNAMEm3769 NIC2_AUX_PWR_EN_R                                                 
P  NNAMEm3770 P5E_PEX0_STN0_RX_DP<15>                                           
P  NNAMEm3771 P5E_PEX1_STN6_TX_C_DN<100>                                        
P  NNAMEm3772 P5E_PEX2_STN1_TX_C_DN<27>                                         
P  NNAMEm3773 P5E_PEX2_STN5_TX_C_DN<83>                                         
P  NNAMEm3774 P5E_PEX3_STN2_RX_DP<47>                                           
P  NNAMEm3775 P5E_PEX3_STN7_TX_C_DP<123>                                        
P  NNAMEm3776 P5E_PEX0_STN0_RX_DP<9>                                            
P  NNAMEm3777 P5E_PEX1_STN6_TX_C_DN<111>                                        
P  NNAMEm3778 P5E_PEX2_STN1_RX_DN<16>                                           
P  NNAMEm3779 P5E_PEX2_STN5_RX_DP<83>                                           
P  NNAMEm3780 P5E_PEX3_STN2_RX_DN<37>                                           
P  NNAMEm3781 P5E_PEX3_STN7_TX_C_DP<118>                                        
P  NNAMEm3782 P5E_PEX0_STN0_RX_DP<12>                                           
P  NNAMEm3783 P5E_PEX1_STN6_TX_C_DP<102>                                        
P  NNAMEm3784 P5E_PEX2_STN1_TX_C_DN<30>                                         
P  NNAMEm3785 P5E_PEX2_STN5_RX_DP<81>                                           
P  NNAMEm3786 P5E_PEX3_STN2_TX_C_DN<46>                                         
P  NNAMEm3787 P5E_PEX3_STN7_RX_DN<121>                                          
P  NNAMEm3788 P5E_PEX0_STN0_RX_DP<13>                                           
P  NNAMEm3789 P5E_PEX1_STN6_TX_C_DN<98>                                         
P  NNAMEm3790 P5E_PEX2_STN1_TX_C_DN<24>                                         
P  NNAMEm3791 P5E_PEX3_STN2_RX_DP<40>                                           
P  NNAMEm3792 P5E_PEX3_STN7_TX_C_DN<127>                                        
P  NNAMEm3793 P5E_PEX0_STN0_RX_DN<7>                                            
P  NNAMEm3794 P5E_PEX1_STN6_RX_DP<103>                                          
P  NNAMEm3795 P5E_PEX2_STN1_RX_DP<18>                                           
P  NNAMEm3796 P5E_PEX3_STN2_TX_C_DN<36>                                         
P  NNAMEm3797 P5E_PEX3_STN7_RX_DN<118>                                          
P  NNAMEm3798 P5E_PEX0_STN0_TX_C_DN<7>                                          
P  NNAMEm3799 P5E_PEX1_STN6_TX_C_DP<109>                                        
P  NNAMEm3800 P5E_PEX2_STN1_TX_C_DN<21>                                         
P  NNAMEm3801 P5E_PEX3_STN2_RX_DN<47>                                           
P  NNAMEm3802 P5E_PEX3_STN7_RX_DP<120>                                          
P  NNAMEm3803 P5E_PEX0_STN0_RX_DP<0>                                            
P  NNAMEm3804 P5E_PEX1_STN6_TX_C_DN<108>                                        
P  NNAMEm3805 P5E_PEX2_STN1_RX_DP<24>                                           
P  NNAMEm3806 P5E_PEX2_STN5_RX_DN<82>                                           
P  NNAMEm3807 P5E_PEX3_STN2_RX_DP<41>                                           
P  NNAMEm3808 P5E_PEX3_STN7_TX_C_DP<116>                                        
P  NNAMEm3809 P5E_PEX0_STN0_TX_C_DP<3>                                          
P  NNAMEm3810 P5E_PEX1_STN6_TX_C_DN<97>                                         
P  NNAMEm3811 P5E_PEX2_STN1_TX_C_DN<26>                                         
P  NNAMEm3812 P5E_PEX3_STN2_TX_C_DP<46>                                         
P  NNAMEm3813 P5E_PEX3_STN7_TX_C_DP<126>                                        
P  NNAMEm3814 RST_NIC2_PERST0_R_N                                               
P  NNAMEm3815 NIC7_AUX_PWR_EN_R                                                 
P  NNAMEm3816 P5E_PEX0_STN0_RX_DN<0>                                            
P  NNAMEm3817 P5E_PEX2_STN1_RX_DP<20>                                           
P  NNAMEm3818 P5E_PEX3_STN2_TX_C_DP<41>                                         
P  NNAMEm3819 P5E_PEX3_STN7_TX_C_DN<117>                                        
P  NNAMEm3820 PWRGD_NIC7_PWR_GOOD                                               
P  NNAMEm3821 P5E_PEX0_STN0_RX_DN<15>                                           
P  NNAMEm3822 P5E_PEX1_STN6_RX_DP<97>                                           
P  NNAMEm3823 P5E_PEX2_STN1_TX_C_DP<22>                                         
P  NNAMEm3824 P5E_PEX2_STN5_TX_C_DP<83>                                         
P  NNAMEm3825 P5E_PEX3_STN2_TX_C_DP<44>                                         
P  NNAMEm3826 P5E_PEX3_STN7_TX_C_DN<112>                                        
P  NNAMEm3827 RST_NIC2_PERST3_R_N                                               
P  NNAMEm3828 RST_NIC7_PERST3_R_N                                               
P  NNAMEm3829 P5E_PEX0_STN0_TX_C_DP<9>                                          
P  NNAMEm3830 P5E_PEX1_STN6_RX_DN<100>                                          
P  NNAMEm3831 P5E_PEX2_STN1_RX_DP<21>                                           
P  NNAMEm3832 P5E_PEX2_STN5_TX_C_DP<84>                                         
P  NNAMEm3833 P5E_PEX3_STN2_TX_C_DP<36>                                         
P  NNAMEm3834 P5E_PEX3_STN7_TX_C_DP<120>                                        
P  NNAMEm3835 PWRGD_NIC2_PWR_GOOD                                               
P  NNAMEm3836 P5E_PEX0_STN0_TX_C_DN<10>                                         
P  NNAMEm3837 P5E_PEX1_STN6_RX_DN<111>                                          
P  NNAMEm3838 P5E_PEX2_STN1_TX_C_DP<16>                                         
P  NNAMEm3839 P5E_PEX3_STN2_TX_C_DP<43>                                         
P  NNAMEm3840 P5E_PEX3_STN7_RX_DP<117>                                          
P  NNAMEm3841 RST_NIC2_PERST1_R_N                                               
P  NNAMEm3842 RST_NIC7_PERST0_R_N                                               
P  NNAMEm3843 P5E_PEX0_STN0_RX_DN<8>                                            
P  NNAMEm3844 P5E_PEX2_STN1_RX_DN<23>                                           
P  NNAMEm3845 P5E_PEX2_STN5_TX_C_DN<81>                                         
P  NNAMEm3846 P5E_PEX3_STN7_RX_DN<117>                                          
P  NNAMEm3847 P5E_PEX0_STN0_RX_DN<3>                                            
P  NNAMEm3848 P5E_PEX2_STN1_RX_DN<20>                                           
P  NNAMEm3849 P5E_PEX3_STN7_RX_DP<126>                                          
P  NNAMEm3850 NIC7_RBT_ARB_IN                                                   
P  NNAMEm3851 P5E_PEX0_STN0_RX_DP<2>                                            
P  NNAMEm3852 P5E_PEX1_STN1_RX_DN<31>                                           
P  NNAMEm3853 P5E_PEX1_STN6_TX_C_DP<97>                                         
P  NNAMEm3854 P5E_PEX2_STN1_RX_DN<29>                                           
P  NNAMEm3855 P5E_PEX2_STN5_TX_C_DN<86>                                         
P  NNAMEm3856 P5E_PEX3_STN7_TX_C_DN<122>                                        
P  NNAMEm3857 NCSI_NIC7_TX_EN                                                   
P  NNAMEm3858 P5E_PEX0_STN0_RX_DN<12>                                           
P  NNAMEm3859 P5E_PEX1_STN1_RX_DN<25>                                           
P  NNAMEm3860 P5E_PEX1_STN6_TX_C_DN<96>                                         
P  NNAMEm3861 P5E_PEX2_STN1_RX_DP<19>                                           
P  NNAMEm3862 P5E_PEX3_STN7_RX_DN<122>                                          
P  NNAMEm3863 P5E_PEX0_STN0_RX_DP<4>                                            
P  NNAMEm3864 P5E_PEX1_STN1_RX_DN<26>                                           
P  NNAMEm3865 P5E_PEX1_STN6_RX_DP<101>                                          
P  NNAMEm3866 P5E_PEX2_STN1_RX_DN<27>                                           
P  NNAMEm3867 P5E_PEX3_STN7_RX_DN<113>                                          
P  NNAMEm3868 RST_NIC7_PERST1_R_N                                               
P  NNAMEm3869 P5E_PEX0_STN0_TX_C_DN<8>                                          
P  NNAMEm3870 P5E_PEX1_STN1_TX_C_DP<25>                                         
P  NNAMEm3871 P5E_PEX2_STN1_TX_C_DN<19>                                         
P  NNAMEm3872 P5E_PEX3_STN0_TX_C_DN<0>                                          
P  NNAMEm3873 P5E_PEX3_STN7_RX_DN<116>                                          
P  NNAMEm3874 NIC7_MAIN_PWR_EN_R                                                
P  NNAMEm3875 P5E_PEX0_STN0_TX_C_DN<4>                                          
P  NNAMEm3876 P5E_PEX1_STN1_RX_DN<30>                                           
P  NNAMEm3877 P5E_PEX2_STN1_RX_DP<25>                                           
P  NNAMEm3878 P5E_PEX2_STN5_RX_DP<80>                                           
P  NNAMEm3879 P5E_PEX3_STN0_TX_C_DN<14>                                         
P  NNAMEm3880 P5E_PEX3_STN7_RX_DN<127>                                          
P  NNAMEm3881 P5E_PEX0_STN0_TX_C_DP<11>                                         
P  NNAMEm3882 P5E_PEX1_STN1_TX_C_DP<24>                                         
P  NNAMEm3883 P5E_PEX2_STN1_TX_C_DP<29>                                         
P  NNAMEm3884 P5E_PEX2_STN5_RX_DN<83>                                           
P  NNAMEm3885 P5E_PEX3_STN0_RX_DN<0>                                            
P  NNAMEm3886 P5E_PEX3_STN7_TX_C_DP<115>                                        
P  NNAMEm3887 P5E_PEX0_STN0_TX_C_DP<6>                                          
P  NNAMEm3888 P5E_PEX1_STN1_RX_DN<22>                                           
P  NNAMEm3889 P5E_PEX2_STN1_TX_C_DP<27>                                         
P  NNAMEm3890 P5E_PEX3_STN0_TX_C_DN<13>                                         
P  NNAMEm3891 P5E_PEX3_STN7_RX_DP<115>                                          
P  NNAMEm3892 DUALPORT_N_SSD5                                                   
P  NNAMEm3893 P5E_PEX0_STN0_TX_C_DN<0>                                          
P  NNAMEm3894 P5E_PEX1_STN1_RX_DN<24>                                           
P  NNAMEm3895 P5E_PEX1_STN6_RX_DP<102>                                          
P  NNAMEm3896 P5E_PEX2_STN1_TX_C_DN<25>                                         
P  NNAMEm3897 P5E_PEX2_STN5_TX_C_DN<87>                                         
P  NNAMEm3898 P5E_PEX3_STN0_RX_DN<6>                                            
P  NNAMEm3899 P5E_PEX3_STN7_RX_DN<114>                                          
P  NNAMEm3900 DUALPORT_N_SSD4                                                   
P  NNAMEm3901 P5E_PEX0_STN0_TX_C_DN<1>                                          
P  NNAMEm3902 P5E_PEX1_STN1_RX_DN<21>                                           
P  NNAMEm3903 P5E_PEX1_STN6_TX_C_DN<101>                                        
P  NNAMEm3904 P5E_PEX2_STN1_RX_DP<16>                                           
P  NNAMEm3905 P5E_PEX3_STN0_RX_DN<2>                                            
P  NNAMEm3906 P5E_PEX3_STN7_TX_C_DN<114>                                        
P  NNAMEm3907 P5E_PEX1_STN1_TX_C_DP<23>                                         
P  NNAMEm3908 P5E_PEX2_STN1_RX_DN<31>                                           
P  NNAMEm3909 P5E_PEX2_STN5_TX_C_DP<85>                                         
P  NNAMEm3910 P5E_PEX3_STN0_TX_C_DP<3>                                          
P  NNAMEm3911 P5E_PEX3_STN7_RX_DN<119>                                          
P  NNAMEm3912 P5E_PEX1_STN1_TX_C_DP<19>                                         
P  NNAMEm3913 P5E_PEX2_STN1_RX_DN<28>                                           
P  NNAMEm3914 P5E_PEX2_STN5_RX_DP<82>                                           
P  NNAMEm3915 P5E_PEX3_STN0_RX_DN<12>                                           
P  NNAMEm3916 P5E_PEX3_STN7_RX_DP<122>                                          
P  NNAMEm3917 P5E_PEX1_STN1_RX_DN<27>                                           
P  NNAMEm3918 P5E_PEX2_STN1_RX_DN<24>                                           
P  NNAMEm3919 P5E_PEX2_STN5_RX_DN<85>                                           
P  NNAMEm3920 P5E_PEX3_STN0_TX_C_DP<7>                                          
P  NNAMEm3921 P5E_PEX3_STN7_RX_DN<112>                                          
P  NNAMEm3922 DUALPORT_N_SSD13                                                  
P  NNAMEm3923 P5E_PEX1_STN1_TX_C_DN<20>                                         
P  NNAMEm3924 P5E_PEX1_STN6_TX_C_DN<103>                                        
P  NNAMEm3925 P5E_PEX2_STN1_RX_DN<18>                                           
P  NNAMEm3926 P5E_PEX3_STN0_RX_DN<7>                                            
P  NNAMEm3927 P5E_PEX3_STN7_RX_DP<127>                                          
P  NNAMEm3928 P5E_PEX1_STN1_TX_C_DP<16>                                         
P  NNAMEm3929 P5E_PEX2_STN1_TX_C_DN<17>                                         
P  NNAMEm3930 P5E_PEX3_STN0_TX_C_DP<13>                                         
P  NNAMEm3931 P5E_PEX3_STN7_RX_DN<115>                                          
P  NNAMEm3932 HP_NIC4_PWRGD_R                                                   
P  NNAMEm3933 DUALPORT_N_SSD12                                                  
P  NNAMEm3934 P5E_PEX1_STN1_RX_DP<28>                                           
P  NNAMEm3935 P5E_PEX1_STN6_TX_C_DP<99>                                         
P  NNAMEm3936 P5E_PEX2_STN1_RX_DP<23>                                           
P  NNAMEm3937 P5E_PEX2_STN5_TX_C_DN<84>                                         
P  NNAMEm3938 P5E_PEX3_STN0_RX_DN<14>                                           
P  NNAMEm3939 P5E_PEX3_STN7_TX_C_DN<123>                                        
P  NNAMEm3940 P5E_PEX1_STN1_TX_C_DN<23>                                         
P  NNAMEm3941 P5E_PEX1_STN6_TX_C_DP<96>                                         
P  NNAMEm3942 P5E_PEX2_STN1_TX_C_DP<31>                                         
P  NNAMEm3943 P5E_PEX2_STN5_RX_DN<87>                                           
P  NNAMEm3944 P5E_PEX3_STN0_TX_C_DN<6>                                          
P  NNAMEm3945 P5E_PEX3_STN7_TX_C_DN<124>                                        
P  NNAMEm3946 RST_NIC7_PERST2_R_N                                               
P  NNAMEm3947 P5E_PEX1_STN1_TX_C_DP<20>                                         
P  NNAMEm3948 P5E_PEX2_STN1_TX_C_DP<17>                                         
P  NNAMEm3949 P5E_PEX3_STN0_RX_DN<15>                                           
P  NNAMEm3950 P5E_PEX3_STN7_RX_DP<121>                                          
P  NNAMEm3951 P5E_PEX1_STN1_TX_C_DP<31>                                         
P  NNAMEm3952 P5E_PEX1_STN6_RX_DP<98>                                           
P  NNAMEm3953 P5E_PEX2_STN1_TX_C_DN<31>                                         
P  NNAMEm3954 P5E_PEX2_STN5_RX_DP<86>                                           
P  NNAMEm3955 P5E_PEX3_STN0_TX_C_DN<11>                                         
P  NNAMEm3956 P5E_PEX3_STN7_TX_C_DP<119>                                        
P  NNAMEm3957 NIC7_RBT_ARB_OUT                                                  
P  NNAMEm3958 P5E_PEX1_STN1_RX_DN<23>                                           
P  NNAMEm3959 P5E_PEX1_STN6_RX_DP<111>                                          
P  NNAMEm3960 P5E_PEX2_STN1_TX_C_DP<23>                                         
P  NNAMEm3961 P5E_PEX2_STN5_RX_DP<84>                                           
P  NNAMEm3962 P5E_PEX3_STN0_TX_C_DP<2>                                          
P  NNAMEm3963 P5E_PEX3_STN7_TX_C_DP<121>                                        
P  NNAMEm3964 P5E_PEX1_STN1_RX_DN<17>                                           
P  NNAMEm3965 P5E_PEX1_STN6_RX_DN<109>                                          
P  NNAMEm3966 P5E_PEX2_STN1_TX_C_DP<19>                                         
P  NNAMEm3967 P5E_PEX3_STN0_TX_C_DN<3>                                          
P  NNAMEm3968 P5E_PEX3_STN7_TX_C_DN<120>                                        
P  NNAMEm3969 CLK_50M_NIC7_RBT_REF                                              
P  NNAMEm3970 P5E_PEX1_STN1_TX_C_DP<18>                                         
P  NNAMEm3971 P5E_PEX1_STN6_RX_DN<98>                                           
P  NNAMEm3972 P5E_PEX2_STN1_RX_DP<27>                                           
P  NNAMEm3973 P5E_PEX3_STN0_RX_DN<5>                                            
P  NNAMEm3974 P5E_PEX1_STN1_TX_C_DP<28>                                         
P  NNAMEm3975 P5E_PEX1_STN6_TX_C_DN<99>                                         
P  NNAMEm3976 P5E_PEX2_STN1_TX_C_DP<18>                                         
P  NNAMEm3977 P5E_PEX3_STN0_RX_DP<1>                                            
P  NNAMEm3978 P5E_PEX1_STN1_RX_DP<26>                                           
P  NNAMEm3979 P5E_PEX1_STN6_RX_DP<96>                                           
P  NNAMEm3980 P5E_PEX2_STN1_TX_C_DN<20>                                         
P  NNAMEm3981 P5E_PEX3_STN0_RX_DN<8>                                            
P  NNAMEm3982 P5E_PEX1_STN1_TX_C_DN<25>                                         
P  NNAMEm3983 P5E_PEX1_STN6_RX_DN<103>                                          
P  NNAMEm3984 P5E_PEX3_STN0_TX_C_DP<8>                                          
P  NNAMEm3985 RST_NIC4_PERST1_R_N                                               
P  NNAMEm3986 P5E_PEX1_STN1_RX_DP<19>                                           
P  NNAMEm3987 P5E_PEX1_STN6_TX_C_DN<110>                                        
P  NNAMEm3988 P5E_PEX2_STN5_RX_DN<80>                                           
P  NNAMEm3989 P5E_PEX3_STN0_TX_C_DN<5>                                          
P  NNAMEm3990 P5E_PEX1_STN1_TX_C_DN<31>                                         
P  NNAMEm3991 P5E_PEX1_STN6_RX_DP<110>                                          
P  NNAMEm3992 P5E_PEX2_STN5_RX_DN<84>                                           
P  NNAMEm3993 P5E_PEX3_STN0_RX_DP<12>                                           
P  NNAMEm3994 P5E_PEX3_STN5_RX_DP<85>                                           
P  NNAMEm3995 P5E_PEX1_STN1_TX_C_DP<29>                                         
P  NNAMEm3996 P5E_PEX1_STN6_TX_C_DP<103>                                        
P  NNAMEm3997 P5E_PEX3_STN0_TX_C_DP<0>                                          
P  NNAMEm3998 P5E_PEX3_STN5_TX_C_DP<83>                                         
P  NNAMEm3999 RST_SMB_NIC7_MUX_ISO_R_N                                          
P  NNAMEm4000 P5E_PEX1_STN1_RX_DN<16>                                           
P  NNAMEm4001 P5E_PEX1_STN6_TX_C_DN<109>                                        
P  NNAMEm4002 P5E_PEX2_STN5_TX_C_DN<80>                                         
P  NNAMEm4003 P5E_PEX3_STN0_TX_C_DP<10>                                         
P  NNAMEm4004 P5E_PEX3_STN5_RX_DP<80>                                           
P  NNAMEm4005 P5E_PEX1_STN1_TX_C_DP<17>                                         
P  NNAMEm4006 P5E_PEX1_STN6_RX_DN<96>                                           
P  NNAMEm4007 P5E_PEX3_STN0_RX_DP<3>                                            
P  NNAMEm4008 P5E_PEX3_STN5_RX_DN<83>                                           
P  NNAMEm4009 NCSI_NIC7_CRS_DV                                                  
P  NNAMEm4010 P5E_PEX1_STN1_RX_DN<29>                                           
P  NNAMEm4011 P5E_PEX2_STN5_RX_DP<85>                                           
P  NNAMEm4012 P5E_PEX3_STN0_RX_DP<6>                                            
P  NNAMEm4013 P5E_PEX3_STN5_TX_C_DP<88>                                         
P  NNAMEm4014 P5E_PEX1_STN1_RX_DP<21>                                           
P  NNAMEm4015 P5E_PEX1_STN6_TX_C_DP<98>                                         
P  NNAMEm4016 P5E_PEX2_STN5_TX_C_DN<85>                                         
P  NNAMEm4017 P5E_PEX3_STN0_TX_C_DN<10>                                         
P  NNAMEm4018 P5E_PEX3_STN5_TX_C_DP<80>                                         
P  NNAMEm4019 NCSI_NIC4_CRS_DV                                                  
P  NNAMEm4020 P5E_PEX1_STN1_RX_DP<24>                                           
P  NNAMEm4021 P5E_PEX1_STN6_RX_DN<99>                                           
P  NNAMEm4022 P5E_PEX2_STN5_RX_DN<86>                                           
P  NNAMEm4023 P5E_PEX3_STN0_TX_C_DN<4>                                          
P  NNAMEm4024 P5E_PEX3_STN5_RX_DP<95>                                           
P  NNAMEm4025 RST_NIC4_PERST2_R_N                                               
P  NNAMEm4026 P5E_PEX1_STN1_RX_DN<19>                                           
P  NNAMEm4027 P5E_PEX1_STN6_TX_C_DP<108>                                        
P  NNAMEm4028 P5E_PEX3_STN0_RX_DP<2>                                            
P  NNAMEm4029 P5E_PEX3_STN5_RX_DN<91>                                           
P  NNAMEm4030 NIC4_AUX_PWR_EN_R                                                 
P  NNAMEm4031 P5E_PEX1_STN1_TX_C_DP<22>                                         
P  NNAMEm4032 P5E_PEX1_STN6_RX_DP<109>                                          
P  NNAMEm4033 P5E_PEX2_STN5_RX_DN<81>                                           
P  NNAMEm4034 P5E_PEX3_STN0_TX_C_DP<15>                                         
P  NNAMEm4035 P5E_PEX3_STN5_TX_C_DN<81>                                         
P  NNAMEm4036 NIC4_RBT_ARB_IN                                                   
P  NNAMEm4037 P5E_PEX1_STN1_TX_C_DN<17>                                         
P  NNAMEm4038 P5E_PEX3_STN0_RX_DP<13>                                           
P  NNAMEm4039 P5E_PEX3_STN5_TX_C_DN<83>                                         
P  NNAMEm4040 P5E_PEX1_STN1_RX_DP<29>                                           
P  NNAMEm4041 P5E_PEX1_STN6_TX_C_DP<111>                                        
P  NNAMEm4042 P5E_PEX3_STN0_TX_C_DN<7>                                          
P  NNAMEm4043 P5E_PEX3_STN5_TX_C_DN<80>                                         
P  NNAMEm4044 P5E_PEX0_STN1_RX_DN<26>                                           
P  NNAMEm4045 P5E_PEX1_STN1_RX_DP<31>                                           
P  NNAMEm4046 P5E_PEX1_STN6_RX_DP<100>                                          
P  NNAMEm4047 P5E_PEX2_STN5_TX_C_DP<81>                                         
P  NNAMEm4048 P5E_PEX3_STN0_TX_C_DN<1>                                          
P  NNAMEm4049 P5E_PEX3_STN5_TX_C_DN<93>                                         
P  NNAMEm4050 P5E_PEX0_STN1_RX_DN<24>                                           
P  NNAMEm4051 P5E_PEX1_STN1_RX_DP<22>                                           
P  NNAMEm4052 P5E_PEX1_STN6_TX_C_DP<100>                                        
P  NNAMEm4053 P5E_PEX3_STN0_RX_DN<4>                                            
P  NNAMEm4054 P5E_PEX3_STN5_TX_C_DP<94>                                         
P  NNAMEm4055 P5E_PEX0_STN1_TX_C_DN<25>                                         
P  NNAMEm4056 P5E_PEX1_STN1_RX_DP<23>                                           
P  NNAMEm4057 P5E_PEX3_STN0_RX_DN<1>                                            
P  NNAMEm4058 P5E_PEX3_STN5_RX_DN<87>                                           
P  NNAMEm4059 P5E_PEX0_STN1_TX_C_DP<25>                                         
P  NNAMEm4060 P5E_PEX1_STN1_RX_DP<27>                                           
P  NNAMEm4061 P5E_PEX1_STN6_TX_C_DN<102>                                        
P  NNAMEm4062 P5E_PEX2_STN5_RX_DP<87>                                           
P  NNAMEm4063 P5E_PEX3_STN0_TX_C_DP<5>                                          
P  NNAMEm4064 P5E_PEX3_STN5_RX_DN<80>                                           
P  NNAMEm4065 P5E_PEX0_STN1_TX_C_DN<17>                                         
P  NNAMEm4066 P5E_PEX1_STN1_TX_C_DN<29>                                         
P  NNAMEm4067 P5E_PEX1_STN6_RX_DP<108>                                          
P  NNAMEm4068 P5E_PEX2_STN5_TX_C_DP<80>                                         
P  NNAMEm4069 P5E_PEX3_STN0_RX_DN<9>                                            
P  NNAMEm4070 P5E_PEX3_STN5_TX_C_DN<92>                                         
P  NNAMEm4071 P5E_PEX0_STN1_TX_C_DP<23>                                         
P  NNAMEm4072 P5E_PEX1_STN1_RX_DP<20>                                           
P  NNAMEm4073 P5E_PEX2_STN5_TX_C_DP<87>                                         
P  NNAMEm4074 P5E_PEX3_STN0_TX_C_DP<9>                                          
P  NNAMEm4075 P5E_PEX3_STN5_RX_DN<95>                                           
P  NNAMEm4076 RST_SMB_NIC4_MUX_ISO_R_N                                          
P  NNAMEm4077 P5E_PEX0_STN1_TX_C_DP<31>                                         
P  NNAMEm4078 P5E_PEX1_STN1_TX_C_DN<16>                                         
P  NNAMEm4079 P5E_PEX1_STN6_RX_DN<97>                                           
P  NNAMEm4080 P5E_PEX3_STN0_RX_DP<9>                                            
P  NNAMEm4081 P5E_PEX3_STN5_RX_DN<90>                                           
P  NNAMEm4082 HP_NIC1_PWRGD_R                                                   
P  NNAMEm4083 P5E_PEX0_STN1_TX_C_DN<19>                                         
P  NNAMEm4084 P5E_PEX1_STN1_TX_C_DP<26>                                         
P  NNAMEm4085 P5E_PEX1_STN6_RX_DN<110>                                          
P  NNAMEm4086 P5E_PEX3_STN0_TX_C_DP<1>                                          
P  NNAMEm4087 P5E_PEX3_STN5_TX_C_DN<90>                                         
P  NNAMEm4088 P5E_PEX0_STN1_RX_DP<29>                                           
P  NNAMEm4089 P5E_PEX1_STN1_TX_C_DN<22>                                         
P  NNAMEm4090 P5E_PEX1_STN6_RX_DN<101>                                          
P  NNAMEm4091 P5E_PEX3_STN0_TX_C_DP<6>                                          
P  NNAMEm4092 P5E_PEX3_STN5_TX_C_DN<87>                                         
P  NNAMEm4093 CLK_50M_NIC4_RBT_REF                                              
P  NNAMEm4094 P5E_PEX0_STN1_TX_C_DP<26>                                         
P  NNAMEm4095 P5E_PEX1_STN1_TX_C_DN<27>                                         
P  NNAMEm4096 P5E_PEX1_STN6_RX_DN<102>                                          
P  NNAMEm4097 P5E_PEX3_STN0_RX_DP<11>                                           
P  NNAMEm4098 P5E_PEX3_STN5_TX_C_DN<95>                                         
P  NNAMEm4099 P5E_PEX0_STN1_RX_DP<24>                                           
P  NNAMEm4100 P5E_PEX1_STN1_TX_C_DN<26>                                         
P  NNAMEm4101 P5E_PEX1_STN6_TX_C_DP<110>                                        
P  NNAMEm4102 P5E_PEX3_STN0_RX_DN<11>                                           
P  NNAMEm4103 P5E_PEX3_STN5_RX_DN<84>                                           
P  NNAMEm4104 NIC4_MAIN_PWR_EN_R                                                
P  NNAMEm4105 P5E_PEX0_STN1_TX_C_DP<19>                                         
P  NNAMEm4106 P5E_PEX1_STN1_RX_DN<18>                                           
P  NNAMEm4107 P5E_PEX1_STN6_TX_C_DP<101>                                        
P  NNAMEm4108 P5E_PEX3_STN0_RX_DP<10>                                           
P  NNAMEm4109 P5E_PEX3_STN5_RX_DN<93>                                           
P  NNAMEm4110 P5E_PEX0_STN1_RX_DN<18>                                           
P  NNAMEm4111 P5E_PEX1_STN1_TX_C_DP<21>                                         
P  NNAMEm4112 P5E_PEX1_STN6_RX_DP<99>                                           
P  NNAMEm4113 P5E_PEX3_STN0_TX_C_DN<2>                                          
P  NNAMEm4114 P5E_PEX3_STN5_TX_C_DP<89>                                         
P  NNAMEm4115 NIC4_RBT_ARB_OUT                                                  
P  NNAMEm4116 P5E_PEX0_STN1_RX_DN<22>                                           
P  NNAMEm4117 P5E_PEX1_STN1_TX_C_DN<18>                                         
P  NNAMEm4118 P5E_PEX3_STN0_RX_DP<4>                                            
P  NNAMEm4119 P5E_PEX3_STN5_RX_DP<92>                                           
P  NNAMEm4120 P5E_PEX0_STN1_TX_C_DP<30>                                         
P  NNAMEm4121 P5E_PEX1_STN1_TX_C_DN<28>                                         
P  NNAMEm4122 P5E_PEX2_STN2_RX_DP<45>                                           
P  NNAMEm4123 P5E_PEX3_STN0_RX_DP<15>                                           
P  NNAMEm4124 P5E_PEX3_STN5_TX_C_DP<93>                                         
P  NNAMEm4125 P5E_PEX0_STN1_TX_C_DN<16>                                         
P  NNAMEm4126 P5E_PEX1_STN1_RX_DN<28>                                           
P  NNAMEm4127 P5E_PEX2_STN2_RX_DN<34>                                           
P  NNAMEm4128 P5E_PEX3_STN0_RX_DP<14>                                           
P  NNAMEm4129 P5E_PEX3_STN5_RX_DP<87>                                           
P  NNAMEm4130 NCSI_NIC4_TX_EN                                                   
P  NNAMEm4131 P5E_PEX0_STN1_RX_DP<28>                                           
P  NNAMEm4132 P5E_PEX1_STN1_RX_DP<25>                                           
P  NNAMEm4133 P5E_PEX2_STN2_TX_C_DP<33>                                         
P  NNAMEm4134 P5E_PEX3_STN0_TX_C_DN<9>                                          
P  NNAMEm4135 P5E_PEX3_STN5_RX_DP<82>                                           
P  NNAMEm4136 RST_NIC4_PERST3_R_N                                               
P  NNAMEm4137 P5E_PEX0_STN1_RX_DP<17>                                           
P  NNAMEm4138 P5E_PEX1_STN1_RX_DP<17>                                           
P  NNAMEm4139 P5E_PEX2_STN2_TX_C_DN<44>                                         
P  NNAMEm4140 P5E_PEX3_STN0_TX_C_DP<11>                                         
P  NNAMEm4141 P5E_PEX3_STN5_RX_DP<84>                                           
P  NNAMEm4142 P5E_PEX0_STN1_TX_C_DP<17>                                         
P  NNAMEm4143 P5E_PEX1_STN1_TX_C_DN<30>                                         
P  NNAMEm4144 P5E_PEX2_STN2_TX_C_DP<39>                                         
P  NNAMEm4145 P5E_PEX3_STN0_RX_DP<0>                                            
P  NNAMEm4146 P5E_PEX3_STN5_RX_DN<81>                                           
P  NNAMEm4147 P5E_PEX0_STN1_RX_DP<25>                                           
P  NNAMEm4148 P5E_PEX1_STN1_TX_C_DN<24>                                         
P  NNAMEm4149 P5E_PEX2_STN2_RX_DP<33>                                           
P  NNAMEm4150 P5E_PEX3_STN0_TX_C_DP<4>                                          
P  NNAMEm4151 P5E_PEX3_STN5_TX_C_DP<85>                                         
P  NNAMEm4152 NIC1_RBT_ARB_IN                                                   
P  NNAMEm4153 P5E_PEX0_STN1_TX_C_DN<31>                                         
P  NNAMEm4154 P5E_PEX1_STN1_RX_DP<18>                                           
P  NNAMEm4155 P5E_PEX2_STN2_TX_C_DP<46>                                         
P  NNAMEm4156 P5E_PEX3_STN0_TX_C_DN<15>                                         
P  NNAMEm4157 P5E_PEX3_STN5_RX_DN<94>                                           
P  NNAMEm4158 RST_NIC1_PERST3_R_N                                               
P  NNAMEm4159 P5E_PEX0_STN1_RX_DP<26>                                           
P  NNAMEm4160 P5E_PEX1_STN1_TX_C_DN<19>                                         
P  NNAMEm4161 P5E_PEX2_STN2_RX_DP<34>                                           
P  NNAMEm4162 P5E_PEX3_STN0_RX_DN<10>                                           
P  NNAMEm4163 P5E_PEX3_STN5_RX_DP<83>                                           
P  NNAMEm4164 RST_NIC4_PERST0_R_N                                               
P  NNAMEm4165 P5E_PEX0_STN1_RX_DN<23>                                           
P  NNAMEm4166 P5E_PEX1_STN1_RX_DN<20>                                           
P  NNAMEm4167 P5E_PEX2_STN2_TX_C_DN<45>                                         
P  NNAMEm4168 P5E_PEX3_STN0_RX_DN<13>                                           
P  NNAMEm4169 P5E_PEX3_STN5_RX_DN<85>                                           
P  NNAMEm4170 P5E_PEX0_STN1_RX_DP<21>                                           
P  NNAMEm4171 P5E_PEX0_STN6_TX_C_DN<96>                                         
P  NNAMEm4172 P5E_PEX1_STN1_TX_C_DP<27>                                         
P  NNAMEm4173 P5E_PEX2_STN2_RX_DN<35>                                           
P  NNAMEm4174 P5E_PEX3_STN0_RX_DP<8>                                            
P  NNAMEm4175 P5E_PEX3_STN5_TX_C_DP<95>                                         
P  NNAMEm4176 PWRGD_NIC1_PWR_GOOD                                               
P  NNAMEm4177 P5E_PEX0_STN1_RX_DP<19>                                           
P  NNAMEm4178 P5E_PEX1_STN1_TX_C_DN<21>                                         
P  NNAMEm4179 P5E_PEX2_STN2_RX_DN<36>                                           
P  NNAMEm4180 P5E_PEX3_STN0_RX_DP<7>                                            
P  NNAMEm4181 P5E_PEX3_STN5_RX_DP<86>                                           
P  NNAMEm4182 NIC1_RBT_ARB_OUT                                                  
P  NNAMEm4183 PWRGD_NIC4_PWR_GOOD                                               
P  NNAMEm4184 P5E_PEX0_STN1_TX_C_DN<20>                                         
P  NNAMEm4185 P5E_PEX1_STN1_RX_DP<30>                                           
P  NNAMEm4186 P5E_PEX2_STN2_RX_DP<36>                                           
P  NNAMEm4187 P5E_PEX3_STN0_TX_C_DN<8>                                          
P  NNAMEm4188 P5E_PEX3_STN5_RX_DN<92>                                           
P  NNAMEm4189 P5E_PEX0_STN1_TX_C_DP<16>                                         
P  NNAMEm4190 P5E_PEX0_STN6_TX_C_DP<96>                                         
P  NNAMEm4191 P5E_PEX1_STN1_TX_C_DP<30>                                         
P  NNAMEm4192 P5E_PEX2_STN2_RX_DN<38>                                           
P  NNAMEm4193 P5E_PEX3_STN0_TX_C_DN<12>                                         
P  NNAMEm4194 P5E_PEX3_STN5_RX_DP<81>                                           
P  NNAMEm4195 P5E_PEX0_STN1_RX_DN<28>                                           
P  NNAMEm4196 P5E_PEX0_STN6_RX_DP<109>                                          
P  NNAMEm4197 P5E_PEX1_STN1_RX_DP<16>                                           
P  NNAMEm4198 P5E_PEX2_STN2_RX_DN<39>                                           
P  NNAMEm4199 P5E_PEX3_STN0_TX_C_DP<12>                                         
P  NNAMEm4200 P5E_PEX3_STN5_TX_C_DP<84>                                         
P  NNAMEm4201 P5E_PEX0_STN1_RX_DN<29>                                           
P  NNAMEm4202 P5E_PEX0_STN6_RX_DN<110>                                          
P  NNAMEm4203 P5E_PEX2_STN2_TX_C_DP<36>                                         
P  NNAMEm4204 P5E_PEX3_STN0_RX_DP<5>                                            
P  NNAMEm4205 NCSI_NIC1_TX_EN                                                   
P  NNAMEm4206 P5E_PEX0_STN1_RX_DN<25>                                           
P  NNAMEm4207 P5E_PEX0_STN6_RX_DP<96>                                           
P  NNAMEm4208 P5E_PEX2_STN2_RX_DP<47>                                           
P  NNAMEm4209 P5E_PEX3_STN0_TX_C_DP<14>                                         
P  NNAMEm4210 P5E_PEX3_STN5_RX_DP<93>                                           
P  NNAMEm4211 P5E_PEX0_STN1_RX_DN<30>                                           
P  NNAMEm4212 P5E_PEX0_STN6_RX_DN<102>                                          
P  NNAMEm4213 P5E_PEX2_STN2_RX_DP<37>                                           
P  NNAMEm4214 P5E_PEX3_STN0_RX_DN<3>                                            
P  NNAMEm4215 P5E_PEX3_STN5_RX_DP<91>                                           
P  NNAMEm4216 P5E_PEX0_STN1_RX_DP<16>                                           
P  NNAMEm4217 P5E_PEX0_STN6_TX_C_DN<110>                                        
P  NNAMEm4218 P5E_PEX2_STN2_TX_C_DP<44>                                         
P  NNAMEm4219 P5E_PEX0_STN1_RX_DN<31>                                           
P  NNAMEm4220 P5E_PEX0_STN6_RX_DN<103>                                          
P  NNAMEm4221 P5E_PEX2_STN2_RX_DN<32>                                           
P  NNAMEm4222 P5E_PEX3_STN5_TX_C_DN<91>                                         
P  NNAMEm4223 P5E_PEX0_STN1_TX_C_DP<24>                                         
P  NNAMEm4224 P5E_PEX0_STN6_RX_DP<111>                                          
P  NNAMEm4225 P5E_PEX2_STN2_TX_C_DN<47>                                         
P  NNAMEm4226 P5E_PEX3_STN5_RX_DN<88>                                           
P  NNAMEm4227 P5E_PEX0_STN1_TX_C_DN<22>                                         
P  NNAMEm4228 P5E_PEX0_STN6_RX_DP<110>                                          
P  NNAMEm4229 P5E_PEX2_STN2_TX_C_DN<41>                                         
P  NNAMEm4230 P5E_PEX3_STN5_TX_C_DP<92>                                         
P  NNAMEm4231 RST_NIC1_PERST0_R_N                                               
P  NNAMEm4232 P5E_PEX0_STN1_RX_DN<17>                                           
P  NNAMEm4233 P5E_PEX2_STN2_RX_DP<46>                                           
P  NNAMEm4234 P5E_PEX3_STN5_TX_C_DN<88>                                         
P  NNAMEm4235 RST_NIC1_PERST2_R_N                                               
P  NNAMEm4236 P5E_PEX0_STN1_RX_DN<16>                                           
P  NNAMEm4237 P5E_PEX2_STN2_RX_DP<40>                                           
P  NNAMEm4238 P5E_PEX2_STN6_RX_DP<106>                                          
P  NNAMEm4239 P5E_PEX3_STN5_RX_DP<89>                                           
P  NNAMEm4240 P5E_PEX0_STN1_TX_C_DN<27>                                         
P  NNAMEm4241 P5E_PEX2_STN2_RX_DN<33>                                           
P  NNAMEm4242 P5E_PEX2_STN6_RX_DP<104>                                          
P  NNAMEm4243 P5E_PEX3_STN5_RX_DN<86>                                           
P  NNAMEm4244 P5E_PEX0_STN1_RX_DP<30>                                           
P  NNAMEm4245 P5E_PEX0_STN6_TX_C_DP<102>                                        
P  NNAMEm4246 P5E_PEX2_STN2_TX_C_DN<37>                                         
P  NNAMEm4247 P5E_PEX2_STN6_RX_DN<111>                                          
P  NNAMEm4248 P5E_PEX3_STN5_TX_C_DN<94>                                         
P  NNAMEm4249 HP_NIC6_PWRGD_R                                                   
P  NNAMEm4250 P5E_PEX0_STN1_RX_DN<19>                                           
P  NNAMEm4251 P5E_PEX2_STN2_RX_DP<35>                                           
P  NNAMEm4252 P5E_PEX2_STN6_RX_DN<107>                                          
P  NNAMEm4253 P5E_PEX3_STN5_TX_C_DN<86>                                         
P  NNAMEm4254 NIC1_MAIN_PWR_EN_R                                                
P  NNAMEm4255 P5E_PEX0_STN1_RX_DP<27>                                           
P  NNAMEm4256 P5E_PEX2_STN2_TX_C_DP<37>                                         
P  NNAMEm4257 P5E_PEX2_STN6_RX_DN<98>                                           
P  NNAMEm4258 P5E_PEX3_STN5_TX_C_DP<81>                                         
P  NNAMEm4259 P5E_PEX0_STN1_TX_C_DN<18>                                         
P  NNAMEm4260 P5E_PEX0_STN6_TX_C_DN<103>                                        
P  NNAMEm4261 P5E_PEX2_STN2_TX_C_DP<41>                                         
P  NNAMEm4262 P5E_PEX2_STN6_TX_C_DP<108>                                        
P  NNAMEm4263 P5E_PEX3_STN5_TX_C_DN<84>                                         
P  NNAMEm4264 CLK_50M_NIC1_RBT_REF                                              
P  NNAMEm4265 P5E_PEX0_STN1_TX_C_DN<23>                                         
P  NNAMEm4266 P5E_PEX0_STN6_TX_C_DP<98>                                         
P  NNAMEm4267 P5E_PEX2_STN2_TX_C_DN<40>                                         
P  NNAMEm4268 P5E_PEX2_STN6_TX_C_DP<107>                                        
P  NNAMEm4269 P5E_PEX3_STN5_TX_C_DN<85>                                         
P  NNAMEm4270 P5E_PEX0_STN1_TX_C_DP<28>                                         
P  NNAMEm4271 P5E_PEX2_STN2_TX_C_DN<32>                                         
P  NNAMEm4272 P5E_PEX2_STN6_TX_C_DN<104>                                        
P  NNAMEm4273 P5E_PEX3_STN5_TX_C_DP<91>                                         
P  NNAMEm4274 RST_NIC1_PERST1_R_N                                               
P  NNAMEm4275 P5E_PEX0_STN1_RX_DN<20>                                           
P  NNAMEm4276 P5E_PEX0_STN6_RX_DP<100>                                          
P  NNAMEm4277 P5E_PEX2_STN2_TX_C_DP<40>                                         
P  NNAMEm4278 P5E_PEX2_STN6_RX_DP<98>                                           
P  NNAMEm4279 P5E_PEX3_STN5_TX_C_DP<86>                                         
P  NNAMEm4280 P5E_PEX0_STN1_RX_DP<22>                                           
P  NNAMEm4281 P5E_PEX0_STN6_TX_C_DP<99>                                         
P  NNAMEm4282 P5E_PEX2_STN2_RX_DP<44>                                           
P  NNAMEm4283 P5E_PEX2_STN6_RX_DP<99>                                           
P  NNAMEm4284 P5E_PEX3_STN5_RX_DP<90>                                           
P  NNAMEm4285 DUALPORT_N_SSD11                                                  
P  NNAMEm4286 P5E_PEX0_STN1_TX_C_DN<24>                                         
P  NNAMEm4287 P5E_PEX2_STN2_TX_C_DP<35>                                         
P  NNAMEm4288 P5E_PEX2_STN6_TX_C_DN<98>                                         
P  NNAMEm4289 P5E_PEX3_STN5_RX_DP<94>                                           
P  NNAMEm4290 NCSI_NIC1_CRS_DV                                                  
P  NNAMEm4291 P5E_PEX0_STN1_TX_C_DN<30>                                         
P  NNAMEm4292 P5E_PEX0_STN6_RX_DN<96>                                           
P  NNAMEm4293 P5E_PEX2_STN2_RX_DP<41>                                           
P  NNAMEm4294 P5E_PEX2_STN6_TX_C_DN<100>                                        
P  NNAMEm4295 P5E_PEX3_STN5_RX_DN<89>                                           
P  NNAMEm4296 NIC1_AUX_PWR_EN_R                                                 
P  NNAMEm4297 P5E_PEX0_STN1_TX_C_DN<26>                                         
P  NNAMEm4298 P5E_PEX2_STN2_RX_DN<46>                                           
P  NNAMEm4299 P5E_PEX2_STN6_TX_C_DP<98>                                         
P  NNAMEm4300 P5E_PEX3_STN5_TX_C_DP<90>                                         
P  NNAMEm4301 DUALPORT_N_SSD10                                                  
P  NNAMEm4302 P5E_PEX0_STN1_TX_C_DP<27>                                         
P  NNAMEm4303 P5E_PEX0_STN6_TX_C_DP<111>                                        
P  NNAMEm4304 P5E_PEX2_STN2_RX_DN<47>                                           
P  NNAMEm4305 P5E_PEX2_STN6_TX_C_DN<111>                                        
P  NNAMEm4306 P5E_PEX3_STN5_RX_DP<88>                                           
P  NNAMEm4307 P5E_PEX0_STN1_RX_DN<21>                                           
P  NNAMEm4308 P5E_PEX0_STN6_RX_DP<103>                                          
P  NNAMEm4309 P5E_PEX2_STN2_TX_C_DN<39>                                         
P  NNAMEm4310 P5E_PEX2_STN6_TX_C_DP<102>                                        
P  NNAMEm4311 P5E_PEX3_STN5_RX_DN<82>                                           
P  NNAMEm4312 NIC6_AUX_PWR_EN_R                                                 
P  NNAMEm4313 P5E_PEX0_STN1_TX_C_DP<22>                                         
P  NNAMEm4314 P5E_PEX0_STN6_RX_DN<98>                                           
P  NNAMEm4315 P5E_PEX2_STN2_TX_C_DN<35>                                         
P  NNAMEm4316 P5E_PEX2_STN6_RX_DN<97>                                           
P  NNAMEm4317 P5E_PEX3_STN5_TX_C_DP<87>                                         
P  NNAMEm4318 P5E_PEX0_STN1_RX_DN<27>                                           
P  NNAMEm4319 P5E_PEX0_STN6_TX_C_DP<100>                                        
P  NNAMEm4320 P5E_PEX2_STN2_TX_C_DN<46>                                         
P  NNAMEm4321 P5E_PEX2_STN6_RX_DN<103>                                          
P  NNAMEm4322 P5E_PEX3_STN5_TX_C_DN<89>                                         
P  NNAMEm4323 P5E_PEX0_STN1_TX_C_DN<21>                                         
P  NNAMEm4324 P5E_PEX0_STN6_RX_DN<100>                                          
P  NNAMEm4325 P5E_PEX2_STN2_RX_DN<40>                                           
P  NNAMEm4326 P5E_PEX2_STN6_RX_DP<100>                                          
P  NNAMEm4327 P5E_PEX0_STN1_RX_DP<31>                                           
P  NNAMEm4328 P5E_PEX0_STN6_RX_DN<101>                                          
P  NNAMEm4329 P5E_PEX2_STN2_TX_C_DP<34>                                         
P  NNAMEm4330 P5E_PEX2_STN6_RX_DP<96>                                           
P  NNAMEm4331 RST_NIC6_PERST0_R_N                                               
P  NNAMEm4332 P5E_PEX0_STN1_TX_C_DN<28>                                         
P  NNAMEm4333 P5E_PEX0_STN6_TX_C_DP<110>                                        
P  NNAMEm4334 P5E_PEX2_STN2_RX_DN<37>                                           
P  NNAMEm4335 P5E_PEX2_STN6_TX_C_DN<109>                                        
P  NNAMEm4336 P5E_PEX0_STN1_TX_C_DP<20>                                         
P  NNAMEm4337 P5E_PEX0_STN6_TX_C_DP<103>                                        
P  NNAMEm4338 P5E_PEX2_STN2_TX_C_DN<43>                                         
P  NNAMEm4339 P5E_PEX2_STN6_RX_DN<105>                                          
P  NNAMEm4340 P5E_PEX0_STN1_TX_C_DN<29>                                         
P  NNAMEm4341 P5E_PEX0_STN6_TX_C_DN<98>                                         
P  NNAMEm4342 P5E_PEX2_STN2_TX_C_DN<34>                                         
P  NNAMEm4343 P5E_PEX2_STN6_RX_DP<107>                                          
P  NNAMEm4344 NIC6_RBT_ARB_OUT                                                  
P  NNAMEm4345 P5E_PEX0_STN1_RX_DP<23>                                           
P  NNAMEm4346 P5E_PEX2_STN2_RX_DN<43>                                           
P  NNAMEm4347 P5E_PEX2_STN6_TX_C_DN<105>                                        
P  NNAMEm4348 P5E_PEX3_STN1_TX_C_DN<23>                                         
P  NNAMEm4349 P5E_PEX0_STN1_TX_C_DP<21>                                         
P  NNAMEm4350 P5E_PEX0_STN6_TX_C_DN<101>                                        
P  NNAMEm4351 P5E_PEX2_STN2_RX_DP<39>                                           
P  NNAMEm4352 P5E_PEX2_STN6_TX_C_DP<97>                                         
P  NNAMEm4353 P5E_PEX3_STN1_TX_C_DN<30>                                         
P  NNAMEm4354 RST_NIC6_PERST1_R_N                                               
P  NNAMEm4355 P5E_PEX0_STN1_RX_DP<18>                                           
P  NNAMEm4356 P5E_PEX0_STN6_TX_C_DN<102>                                        
P  NNAMEm4357 P5E_PEX2_STN2_TX_C_DP<45>                                         
P  NNAMEm4358 P5E_PEX2_STN6_TX_C_DN<102>                                        
P  NNAMEm4359 P5E_PEX3_STN1_TX_C_DN<27>                                         
P  NNAMEm4360 PWRGD_NIC6_PWR_GOOD                                               
P  NNAMEm4361 P5E_PEX0_STN1_RX_DP<20>                                           
P  NNAMEm4362 P5E_PEX2_STN2_RX_DP<42>                                           
P  NNAMEm4363 P5E_PEX2_STN6_TX_C_DP<99>                                         
P  NNAMEm4364 P5E_PEX3_STN1_TX_C_DP<16>                                         
P  NNAMEm4365 P5E_PEX0_STN1_TX_C_DP<18>                                         
P  NNAMEm4366 P5E_PEX2_STN2_RX_DN<45>                                           
P  NNAMEm4367 P5E_PEX2_STN6_TX_C_DN<106>                                        
P  NNAMEm4368 P5E_PEX3_STN1_RX_DN<20>                                           
P  NNAMEm4369 P5E_PEX0_STN1_TX_C_DP<29>                                         
P  NNAMEm4370 P5E_PEX0_STN6_TX_C_DP<101>                                        
P  NNAMEm4371 P5E_PEX2_STN2_TX_C_DN<38>                                         
P  NNAMEm4372 P5E_PEX2_STN6_RX_DP<105>                                          
P  NNAMEm4373 P5E_PEX3_STN1_RX_DP<30>                                           
P  NNAMEm4374 P5E_PEX0_STN6_TX_C_DN<100>                                        
P  NNAMEm4375 P5E_PEX2_STN2_TX_C_DN<36>                                         
P  NNAMEm4376 P5E_PEX2_STN6_RX_DP<103>                                          
P  NNAMEm4377 P5E_PEX3_STN1_TX_C_DP<19>                                         
P  NNAMEm4378 NCSI_NIC6_CRS_DV                                                  
P  NNAMEm4379 P5E_PEX0_STN6_RX_DP<98>                                           
P  NNAMEm4380 P5E_PEX2_STN2_TX_C_DN<42>                                         
P  NNAMEm4381 P5E_PEX2_STN6_TX_C_DP<100>                                        
P  NNAMEm4382 P5E_PEX3_STN1_TX_C_DN<31>                                         
P  NNAMEm4383 P5E_PEX0_STN6_TX_C_DP<108>                                        
P  NNAMEm4384 P5E_PEX2_STN2_RX_DN<42>                                           
P  NNAMEm4385 P5E_PEX2_STN6_RX_DN<99>                                           
P  NNAMEm4386 P5E_PEX3_STN1_TX_C_DN<28>                                         
P  NNAMEm4387 P5E_PEX0_STN6_RX_DP<102>                                          
P  NNAMEm4388 P5E_PEX2_STN2_RX_DP<43>                                           
P  NNAMEm4389 P5E_PEX2_STN6_RX_DP<110>                                          
P  NNAMEm4390 P5E_PEX3_STN1_RX_DP<21>                                           
P  NNAMEm4391 HP_NIC3_PWRGD_R                                                   
P  NNAMEm4392 P5E_PEX0_STN6_RX_DP<99>                                           
P  NNAMEm4393 P5E_PEX2_STN2_TX_C_DP<43>                                         
P  NNAMEm4394 P5E_PEX2_STN6_RX_DP<109>                                          
P  NNAMEm4395 P5E_PEX3_STN1_TX_C_DP<31>                                         
P  NNAMEm4396 CLK_50M_NIC6_RBT_REF                                              
P  NNAMEm4397 P5E_PEX0_STN6_RX_DN<111>                                          
P  NNAMEm4398 P5E_PEX2_STN2_RX_DP<38>                                           
P  NNAMEm4399 P5E_PEX2_STN6_TX_C_DN<110>                                        
P  NNAMEm4400 P5E_PEX3_STN1_RX_DN<25>                                           
P  NNAMEm4401 P5E_PEX0_STN6_TX_C_DN<109>                                        
P  NNAMEm4402 P5E_PEX2_STN2_TX_C_DN<33>                                         
P  NNAMEm4403 P5E_PEX2_STN6_TX_C_DP<104>                                        
P  NNAMEm4404 P5E_PEX3_STN1_RX_DP<19>                                           
P  NNAMEm4405 P5E_PEX0_STN6_RX_DP<101>                                          
P  NNAMEm4406 P5E_PEX2_STN2_TX_C_DP<47>                                         
P  NNAMEm4407 P5E_PEX2_STN6_RX_DN<110>                                          
P  NNAMEm4408 P5E_PEX3_STN1_TX_C_DP<24>                                         
P  NNAMEm4409 P5E_PEX2_STN2_TX_C_DP<38>                                         
P  NNAMEm4410 P5E_PEX2_STN6_TX_C_DN<96>                                         
P  NNAMEm4411 P5E_PEX3_STN1_TX_C_DN<18>                                         
P  NNAMEm4412 P5E_PEX0_STN6_RX_DN<97>                                           
P  NNAMEm4413 P5E_PEX2_STN2_RX_DP<32>                                           
P  NNAMEm4414 P5E_PEX2_STN6_TX_C_DP<106>                                        
P  NNAMEm4415 P5E_PEX3_STN1_TX_C_DP<17>                                         
P  NNAMEm4416 RST_SMB_NIC6_MUX_ISO_R_N                                          
P  NNAMEm4417 P5E_PEX0_STN6_RX_DP<108>                                          
P  NNAMEm4418 P5E_PEX2_STN2_RX_DN<41>                                           
P  NNAMEm4419 P5E_PEX2_STN6_TX_C_DP<103>                                        
P  NNAMEm4420 P5E_PEX3_STN1_RX_DN<31>                                           
P  NNAMEm4421 NCSI_NIC6_TX_EN                                                   
P  NNAMEm4422 P5E_PEX0_STN6_TX_C_DN<111>                                        
P  NNAMEm4423 P5E_PEX2_STN2_TX_C_DP<42>                                         
P  NNAMEm4424 P5E_PEX2_STN6_TX_C_DN<101>                                        
P  NNAMEm4425 P5E_PEX3_STN1_TX_C_DN<16>                                         
P  NNAMEm4426 NIC6_MAIN_PWR_EN_R                                                
P  NNAMEm4427 P5E_PEX0_STN6_RX_DN<99>                                           
P  NNAMEm4428 P5E_PEX2_STN2_TX_C_DP<32>                                         
P  NNAMEm4429 P5E_PEX2_STN6_RX_DP<97>                                           
P  NNAMEm4430 P5E_PEX3_STN1_RX_DP<20>                                           
P  NNAMEm4431 RST_NIC6_PERST3_R_N                                               
P  NNAMEm4432 P5E_PEX0_STN6_TX_C_DP<97>                                         
P  NNAMEm4433 P5E_PEX1_STN2_RX_DN<37>                                           
P  NNAMEm4434 P5E_PEX2_STN2_RX_DN<44>                                           
P  NNAMEm4435 P5E_PEX2_STN6_TX_C_DP<109>                                        
P  NNAMEm4436 P5E_PEX3_STN1_RX_DP<27>                                           
P  NNAMEm4437 P5E_PEX0_STN6_TX_C_DP<109>                                        
P  NNAMEm4438 P5E_PEX1_STN2_RX_DP<37>                                           
P  NNAMEm4439 P5E_PEX2_STN6_TX_C_DN<108>                                        
P  NNAMEm4440 P5E_PEX3_STN1_TX_C_DP<27>                                         
P  NNAMEm4441 P5E_PEX0_STN6_RX_DP<97>                                           
P  NNAMEm4442 P5E_PEX1_STN2_TX_C_DP<36>                                         
P  NNAMEm4443 P5E_PEX2_STN6_TX_C_DP<105>                                        
P  NNAMEm4444 P5E_PEX3_STN1_RX_DN<27>                                           
P  NNAMEm4445 P5E_PEX0_STN6_RX_DN<108>                                          
P  NNAMEm4446 P5E_PEX1_STN2_TX_C_DP<46>                                         
P  NNAMEm4447 P5E_PEX2_STN6_RX_DN<101>                                          
P  NNAMEm4448 P5E_PEX3_STN1_RX_DN<19>                                           
P  NNAMEm4449 P5E_PEX3_STN6_TX_C_DN<98>                                         
P  NNAMEm4450 DUALPORT_N_SSD9                                                   
P  NNAMEm4451 P5E_PEX1_STN2_TX_C_DP<47>                                         
P  NNAMEm4452 P5E_PEX2_STN6_RX_DP<108>                                          
P  NNAMEm4453 P5E_PEX3_STN1_TX_C_DP<25>                                         
P  NNAMEm4454 P5E_PEX3_STN6_RX_DN<111>                                          
P  NNAMEm4455 NIC3_AUX_PWR_EN_R                                                 
P  NNAMEm4456 RST_NIC6_PERST2_R_N                                               
P  NNAMEm4457 P5E_PEX0_STN6_TX_C_DN<108>                                        
P  NNAMEm4458 P5E_PEX1_STN2_TX_C_DP<33>                                         
P  NNAMEm4459 P5E_PEX2_STN6_RX_DN<102>                                          
P  NNAMEm4460 P5E_PEX3_STN1_TX_C_DN<22>                                         
P  NNAMEm4461 P5E_PEX3_STN6_RX_DN<108>                                          
P  NNAMEm4462 DUALPORT_N_SSD8                                                   
P  NNAMEm4463 P5E_PEX0_STN6_TX_C_DN<99>                                         
P  NNAMEm4464 P5E_PEX1_STN2_RX_DN<34>                                           
P  NNAMEm4465 P5E_PEX2_STN0_RX_DN<12>                                           
P  NNAMEm4466 P5E_PEX2_STN6_TX_C_DP<101>                                        
P  NNAMEm4467 P5E_PEX3_STN1_TX_C_DP<22>                                         
P  NNAMEm4468 P5E_PEX3_STN6_TX_C_DN<110>                                        
P  NNAMEm4469 NIC3_RBT_ARB_OUT                                                  
P  NNAMEm4470 P5E_PEX0_STN6_TX_C_DN<97>                                         
P  NNAMEm4471 P5E_PEX1_STN2_TX_C_DN<46>                                         
P  NNAMEm4472 P5E_PEX2_STN0_TX_C_DN<8>                                          
P  NNAMEm4473 P5E_PEX2_STN6_RX_DN<109>                                          
P  NNAMEm4474 P5E_PEX3_STN1_TX_C_DP<30>                                         
P  NNAMEm4475 P5E_PEX3_STN6_RX_DP<98>                                           
P  NNAMEm4476 NIC6_RBT_ARB_IN                                                   
P  NNAMEm4477 P5E_PEX0_STN6_RX_DN<109>                                          
P  NNAMEm4478 P5E_PEX1_STN2_TX_C_DP<32>                                         
P  NNAMEm4479 P5E_PEX2_STN0_TX_C_DN<11>                                         
P  NNAMEm4480 P5E_PEX2_STN6_TX_C_DP<96>                                         
P  NNAMEm4481 P5E_PEX3_STN1_RX_DN<16>                                           
P  NNAMEm4482 P5E_PEX3_STN6_TX_C_DN<102>                                        
P  NNAMEm4483 P5E_PEX1_STN2_RX_DP<40>                                           
P  NNAMEm4484 P5E_PEX2_STN0_RX_DN<3>                                            
P  NNAMEm4485 P5E_PEX2_STN6_RX_DP<111>                                          
P  NNAMEm4486 P5E_PEX3_STN1_TX_C_DP<20>                                         
P  NNAMEm4487 P5E_PEX3_STN6_TX_C_DP<111>                                        
P  NNAMEm4488 P5E_PEX1_STN2_RX_DN<36>                                           
P  NNAMEm4489 P5E_PEX2_STN0_TX_C_DP<3>                                          
P  NNAMEm4490 P5E_PEX2_STN6_RX_DN<96>                                           
P  NNAMEm4491 P5E_PEX3_STN1_TX_C_DN<29>                                         
P  NNAMEm4492 P5E_PEX3_STN6_RX_DP<104>                                          
P  NNAMEm4493 P5E_PEX1_STN2_TX_C_DP<35>                                         
P  NNAMEm4494 P5E_PEX2_STN0_TX_C_DN<0>                                          
P  NNAMEm4495 P5E_PEX2_STN6_TX_C_DP<111>                                        
P  NNAMEm4496 P5E_PEX3_STN1_TX_C_DN<20>                                         
P  NNAMEm4497 P5E_PEX3_STN6_RX_DP<100>                                          
P  NNAMEm4498 RST_NIC3_PERST2_R_N                                               
P  NNAMEm4499 P5E_PEX1_STN2_TX_C_DN<36>                                         
P  NNAMEm4500 P5E_PEX2_STN0_RX_DN<10>                                           
P  NNAMEm4501 P5E_PEX2_STN6_RX_DN<104>                                          
P  NNAMEm4502 P5E_PEX3_STN1_TX_C_DP<29>                                         
P  NNAMEm4503 P5E_PEX3_STN6_RX_DN<110>                                          
P  NNAMEm4504 RST_SMB_NIC3_MUX_ISO_R_N                                          
P  NNAMEm4505 P5E_PEX1_STN2_TX_C_DP<38>                                         
P  NNAMEm4506 P5E_PEX2_STN0_TX_C_DP<10>                                         
P  NNAMEm4507 P5E_PEX2_STN6_RX_DN<106>                                          
P  NNAMEm4508 P5E_PEX3_STN1_RX_DN<22>                                           
P  NNAMEm4509 P5E_PEX3_STN6_RX_DN<97>                                           
P  NNAMEm4510 P5E_PEX0_STN2_RX_DP<40>                                           
P  NNAMEm4511 P5E_PEX1_STN2_TX_C_DN<42>                                         
P  NNAMEm4512 P5E_PEX2_STN0_RX_DP<0>                                            
P  NNAMEm4513 P5E_PEX2_STN6_RX_DP<102>                                          
P  NNAMEm4514 P5E_PEX3_STN1_TX_C_DP<18>                                         
P  NNAMEm4515 P5E_PEX3_STN6_RX_DP<101>                                          
P  NNAMEm4516 P5E_PEX1_STN2_RX_DN<46>                                           
P  NNAMEm4517 P5E_PEX2_STN0_RX_DN<2>                                            
P  NNAMEm4518 P5E_PEX2_STN6_TX_C_DN<107>                                        
P  NNAMEm4519 P5E_PEX3_STN1_RX_DP<28>                                           
P  NNAMEm4520 P5E_PEX3_STN6_TX_C_DN<100>                                        
P  NNAMEm4521 P5E_PEX0_STN2_RX_DP<46>                                           
P  NNAMEm4522 P5E_PEX1_STN2_TX_C_DN<45>                                         
P  NNAMEm4523 P5E_PEX2_STN0_TX_C_DP<13>                                         
P  NNAMEm4524 P5E_PEX2_STN6_TX_C_DN<97>                                         
P  NNAMEm4525 P5E_PEX3_STN1_RX_DN<17>                                           
P  NNAMEm4526 P5E_PEX3_STN6_RX_DP<103>                                          
P  NNAMEm4527 CLK_50M_NIC3_RBT_REF                                              
P  NNAMEm4528 P5E_PEX1_STN2_TX_C_DN<33>                                         
P  NNAMEm4529 P5E_PEX2_STN0_RX_DN<15>                                           
P  NNAMEm4530 P5E_PEX2_STN6_TX_C_DN<103>                                        
P  NNAMEm4531 P5E_PEX3_STN1_TX_C_DP<28>                                         
P  NNAMEm4532 P5E_PEX3_STN6_RX_DP<102>                                          
P  NNAMEm4533 P5E_PEX1_STN2_RX_DP<36>                                           
P  NNAMEm4534 P5E_PEX2_STN0_TX_C_DP<4>                                          
P  NNAMEm4535 P5E_PEX2_STN6_TX_C_DN<99>                                         
P  NNAMEm4536 P5E_PEX3_STN1_TX_C_DN<17>                                         
P  NNAMEm4537 P5E_PEX3_STN6_TX_C_DP<104>                                        
P  NNAMEm4538 NIC3_RBT_ARB_IN                                                   
P  NNAMEm4539 P5E_PEX0_STN2_RX_DN<41>                                           
P  NNAMEm4540 P5E_PEX1_STN2_RX_DP<38>                                           
P  NNAMEm4541 P5E_PEX2_STN0_RX_DP<13>                                           
P  NNAMEm4542 P5E_PEX2_STN6_RX_DP<101>                                          
P  NNAMEm4543 P5E_PEX3_STN1_TX_C_DN<24>                                         
P  NNAMEm4544 P5E_PEX3_STN6_RX_DP<96>                                           
P  NNAMEm4545 P5E_PEX0_STN2_RX_DN<36>                                           
P  NNAMEm4546 P5E_PEX1_STN2_RX_DP<42>                                           
P  NNAMEm4547 P5E_PEX2_STN0_RX_DP<15>                                           
P  NNAMEm4548 P5E_PEX2_STN6_RX_DN<108>                                          
P  NNAMEm4549 P5E_PEX3_STN1_RX_DP<24>                                           
P  NNAMEm4550 P5E_PEX3_STN6_RX_DP<97>                                           
P  NNAMEm4551 NCSI_NIC3_CRS_DV                                                  
P  NNAMEm4552 P5E_PEX0_STN2_RX_DP<41>                                           
P  NNAMEm4553 P5E_PEX1_STN2_RX_DN<43>                                           
P  NNAMEm4554 P5E_PEX2_STN0_TX_C_DP<6>                                          
P  NNAMEm4555 P5E_PEX2_STN6_TX_C_DP<110>                                        
P  NNAMEm4556 P5E_PEX3_STN1_RX_DN<30>                                           
P  NNAMEm4557 P5E_PEX3_STN6_RX_DP<111>                                          
P  NNAMEm4558 NCSI_NIC3_TX_EN                                                   
P  NNAMEm4559 P5E_PEX0_STN2_RX_DP<33>                                           
P  NNAMEm4560 P5E_PEX1_STN2_RX_DP<41>                                           
P  NNAMEm4561 P5E_PEX2_STN0_TX_C_DN<7>                                          
P  NNAMEm4562 P5E_PEX2_STN6_RX_DN<100>                                          
P  NNAMEm4563 P5E_PEX3_STN1_RX_DN<29>                                           
P  NNAMEm4564 P5E_PEX3_STN6_RX_DP<108>                                          
P  NNAMEm4565 RST_NIC3_PERST1_R_N                                               
P  NNAMEm4566 P5E_PEX1_STN2_RX_DP<33>                                           
P  NNAMEm4567 P5E_PEX2_STN0_RX_DN<11>                                           
P  NNAMEm4568 P5E_PEX3_STN1_RX_DN<26>                                           
P  NNAMEm4569 P5E_PEX3_STN6_RX_DP<107>                                          
P  NNAMEm4570 P5E_PEX0_STN2_RX_DN<37>                                           
P  NNAMEm4571 P5E_PEX1_STN2_TX_C_DP<40>                                         
P  NNAMEm4572 P5E_PEX2_STN0_TX_C_DP<5>                                          
P  NNAMEm4573 P5E_PEX3_STN1_RX_DN<21>                                           
P  NNAMEm4574 P5E_PEX3_STN6_TX_C_DP<103>                                        
P  NNAMEm4575 HP_NIC0_PWRGD_R                                                   
P  NNAMEm4576 P5E_PEX0_STN2_RX_DN<40>                                           
P  NNAMEm4577 P5E_PEX1_STN2_RX_DP<34>                                           
P  NNAMEm4578 P5E_PEX2_STN0_TX_C_DN<12>                                         
P  NNAMEm4579 P5E_PEX3_STN1_RX_DN<28>                                           
P  NNAMEm4580 P5E_PEX3_STN6_TX_C_DN<105>                                        
P  NNAMEm4581 P5E_PEX0_STN2_RX_DN<34>                                           
P  NNAMEm4582 P5E_PEX1_STN2_TX_C_DN<37>                                         
P  NNAMEm4583 P5E_PEX2_STN0_RX_DP<4>                                            
P  NNAMEm4584 P5E_PEX3_STN1_TX_C_DP<23>                                         
P  NNAMEm4585 P5E_PEX3_STN6_RX_DN<96>                                           
P  NNAMEm4586 P5E_PEX0_STN2_RX_DP<32>                                           
P  NNAMEm4587 P5E_PEX1_STN2_RX_DP<46>                                           
P  NNAMEm4588 P5E_PEX2_STN0_RX_DN<9>                                            
P  NNAMEm4589 P5E_PEX3_STN1_RX_DN<24>                                           
P  NNAMEm4590 P5E_PEX3_STN6_TX_C_DN<101>                                        
P  NNAMEm4591 P5E_PEX1_STN2_RX_DN<40>                                           
P  NNAMEm4592 P5E_PEX2_STN0_RX_DP<1>                                            
P  NNAMEm4593 P5E_PEX3_STN1_RX_DP<23>                                           
P  NNAMEm4594 P5E_PEX3_STN6_RX_DP<99>                                           
P  NNAMEm4595 RST_NIC3_PERST3_R_N                                               
P  NNAMEm4596 P5E_PEX0_STN2_RX_DN<32>                                           
P  NNAMEm4597 P5E_PEX1_STN2_TX_C_DP<44>                                         
P  NNAMEm4598 P5E_PEX2_STN0_TX_C_DN<3>                                          
P  NNAMEm4599 P5E_PEX3_STN1_RX_DP<25>                                           
P  NNAMEm4600 P5E_PEX3_STN6_TX_C_DN<109>                                        
P  NNAMEm4601 P5E_PEX1_STN2_RX_DN<47>                                           
P  NNAMEm4602 P5E_PEX2_STN0_RX_DN<8>                                            
P  NNAMEm4603 P5E_PEX3_STN1_TX_C_DP<21>                                         
P  NNAMEm4604 P5E_PEX3_STN6_RX_DN<99>                                           
P  NNAMEm4605 PWRGD_NIC3_PWR_GOOD                                               
P  NNAMEm4606 P5E_PEX1_STN2_RX_DN<41>                                           
P  NNAMEm4607 P5E_PEX2_STN0_RX_DP<5>                                            
P  NNAMEm4608 P5E_PEX3_STN1_TX_C_DN<19>                                         
P  NNAMEm4609 P5E_PEX3_STN6_RX_DN<109>                                          
P  NNAMEm4610 P5E_PEX1_STN2_TX_C_DP<43>                                         
P  NNAMEm4611 P5E_PEX2_STN0_TX_C_DN<13>                                         
P  NNAMEm4612 P5E_PEX3_STN1_TX_C_DN<21>                                         
P  NNAMEm4613 P5E_PEX3_STN6_RX_DN<107>                                          
P  NNAMEm4614 NIC3_MAIN_PWR_EN_R                                                
P  NNAMEm4615 P5E_PEX1_STN2_RX_DN<42>                                           
P  NNAMEm4616 P5E_PEX2_STN0_TX_C_DP<2>                                          
P  NNAMEm4617 P5E_PEX3_STN1_RX_DP<22>                                           
P  NNAMEm4618 P5E_PEX3_STN6_RX_DN<105>                                          
P  NNAMEm4619 RST_NIC3_PERST0_R_N                                               
P  NNAMEm4620 P5E_PEX1_STN2_RX_DP<45>                                           
P  NNAMEm4621 P5E_PEX2_STN0_RX_DP<11>                                           
P  NNAMEm4622 P5E_PEX3_STN1_TX_C_DN<25>                                         
P  NNAMEm4623 P5E_PEX3_STN6_TX_C_DP<105>                                        
P  NNAMEm4624 P5E_PEX0_STN2_RX_DP<36>                                           
P  NNAMEm4625 P5E_PEX1_STN2_RX_DP<43>                                           
P  NNAMEm4626 P5E_PEX2_STN0_RX_DP<7>                                            
P  NNAMEm4627 P5E_PEX3_STN1_RX_DP<29>                                           
P  NNAMEm4628 P5E_PEX3_STN6_TX_C_DP<97>                                         
P  NNAMEm4629 P5E_PEX1_STN2_TX_C_DP<39>                                         
P  NNAMEm4630 P5E_PEX2_STN0_RX_DN<6>                                            
P  NNAMEm4631 P5E_PEX3_STN1_RX_DP<16>                                           
P  NNAMEm4632 P5E_PEX3_STN6_RX_DP<105>                                          
P  NNAMEm4633 P5E_PEX0_STN2_RX_DN<45>                                           
P  NNAMEm4634 P5E_PEX1_STN2_TX_C_DP<34>                                         
P  NNAMEm4635 P5E_PEX2_STN0_RX_DN<1>                                            
P  NNAMEm4636 P5E_PEX3_STN1_RX_DP<26>                                           
P  NNAMEm4637 P5E_PEX3_STN6_TX_C_DN<97>                                         
P  NNAMEm4638 RST_NIC0_PERST1_R_N                                               
P  NNAMEm4639 P5E_PEX1_STN2_RX_DN<33>                                           
P  NNAMEm4640 P5E_PEX2_STN0_TX_C_DN<6>                                          
P  NNAMEm4641 P5E_PEX3_STN1_RX_DP<18>                                           
P  NNAMEm4642 P5E_PEX3_STN6_TX_C_DP<109>                                        
P  NNAMEm4643 P5E_PEX1_STN2_TX_C_DP<45>                                         
P  NNAMEm4644 P5E_PEX2_STN0_TX_C_DP<1>                                          
P  NNAMEm4645 P5E_PEX3_STN1_RX_DP<17>                                           
P  NNAMEm4646 P5E_PEX3_STN6_TX_C_DP<99>                                         
P  NNAMEm4647 NIC0_AUX_PWR_EN_R                                                 
P  NNAMEm4648 P5E_PEX0_STN2_RX_DN<42>                                           
P  NNAMEm4649 P5E_PEX1_STN2_TX_C_DN<39>                                         
P  NNAMEm4650 P5E_PEX2_STN0_TX_C_DN<15>                                         
P  NNAMEm4651 P5E_PEX3_STN1_TX_C_DN<26>                                         
P  NNAMEm4652 P5E_PEX3_STN6_RX_DP<110>                                          
P  NNAMEm4653 P5E_PEX0_STN2_RX_DN<47>                                           
P  NNAMEm4654 P5E_PEX1_STN2_RX_DN<32>                                           
P  NNAMEm4655 P5E_PEX2_STN0_TX_C_DN<14>                                         
P  NNAMEm4656 P5E_PEX3_STN1_TX_C_DP<26>                                         
P  NNAMEm4657 P5E_PEX3_STN6_RX_DN<98>                                           
P  NNAMEm4658 P5E_PEX0_STN2_RX_DN<46>                                           
P  NNAMEm4659 P5E_PEX1_STN2_TX_C_DN<35>                                         
P  NNAMEm4660 P5E_PEX2_STN0_TX_C_DP<9>                                          
P  NNAMEm4661 P5E_PEX3_STN1_RX_DN<18>                                           
P  NNAMEm4662 P5E_PEX3_STN6_RX_DN<102>                                          
P  NNAMEm4663 NCSI_NIC0_CRS_DV                                                  
P  NNAMEm4664 P5E_PEX1_STN2_TX_C_DP<42>                                         
P  NNAMEm4665 P5E_PEX2_STN0_TX_C_DP<7>                                          
P  NNAMEm4666 P5E_PEX3_STN1_RX_DN<23>                                           
P  NNAMEm4667 P5E_PEX3_STN6_TX_C_DP<108>                                        
P  NNAMEm4668 NIC0_RBT_ARB_OUT                                                  
P  NNAMEm4669 P5E_PEX0_STN2_RX_DP<42>                                           
P  NNAMEm4670 P5E_PEX1_STN2_RX_DP<32>                                           
P  NNAMEm4671 P5E_PEX2_STN0_TX_C_DP<11>                                         
P  NNAMEm4672 P5E_PEX3_STN1_RX_DP<31>                                           
P  NNAMEm4673 P5E_PEX3_STN6_TX_C_DP<107>                                        
P  NNAMEm4674 RST_NIC0_PERST0_R_N                                               
P  NNAMEm4675 P5E_PEX0_STN2_RX_DN<38>                                           
P  NNAMEm4676 P5E_PEX1_STN2_TX_C_DN<44>                                         
P  NNAMEm4677 P5E_PEX2_STN0_RX_DP<10>                                           
P  NNAMEm4678 P5E_PEX3_STN6_TX_C_DN<106>                                        
P  NNAMEm4679 NCSI_NIC0_TX_EN                                                   
P  NNAMEm4680 P5E_PEX0_STN2_RX_DP<43>                                           
P  NNAMEm4681 P5E_PEX1_STN2_RX_DN<38>                                           
P  NNAMEm4682 P5E_PEX2_STN0_RX_DP<8>                                            
P  NNAMEm4683 P5E_PEX3_STN6_TX_C_DN<99>                                         
P  NNAMEm4684 P5E_PEX1_STN2_TX_C_DN<34>                                         
P  NNAMEm4685 P5E_PEX2_STN0_TX_C_DN<5>                                          
P  NNAMEm4686 P5E_PEX3_STN6_RX_DP<109>                                          
P  NNAMEm4687 RST_NIC0_PERST2_R_N                                               
P  NNAMEm4688 P5E_PEX1_STN2_RX_DN<44>                                           
P  NNAMEm4689 P5E_PEX2_STN0_RX_DN<4>                                            
P  NNAMEm4690 P5E_PEX3_STN6_TX_C_DN<108>                                        
P  NNAMEm4691 P5E_PEX0_STN2_RX_DP<45>                                           
P  NNAMEm4692 P5E_PEX1_STN2_RX_DN<35>                                           
P  NNAMEm4693 P5E_PEX2_STN0_RX_DN<5>                                            
P  NNAMEm4694 P5E_PEX3_STN6_TX_C_DP<101>                                        
P  NNAMEm4695 NIC0_MAIN_PWR_EN_R                                                
P  NNAMEm4696 P5E_PEX1_STN2_TX_C_DN<40>                                         
P  NNAMEm4697 P5E_PEX2_STN0_TX_C_DN<1>                                          
P  NNAMEm4698 P5E_PEX3_STN6_TX_C_DN<107>                                        
P  NNAMEm4699 P5E_PEX0_STN2_RX_DP<37>                                           
P  NNAMEm4700 P5E_PEX1_STN2_TX_C_DN<47>                                         
P  NNAMEm4701 P5E_PEX2_STN0_RX_DP<2>                                            
P  NNAMEm4702 P5E_PEX3_STN6_TX_C_DN<103>                                        
P  NNAMEm4703 P5E_PEX1_STN2_RX_DP<44>                                           
P  NNAMEm4704 P5E_PEX2_STN0_RX_DN<13>                                           
P  NNAMEm4705 P5E_PEX3_STN6_TX_C_DP<110>                                        
P  NNAMEm4706 PWRGD_NIC0_PWR_GOOD                                               
P  NNAMEm4707 P5E_PEX0_STN2_RX_DN<35>                                           
P  NNAMEm4708 P5E_PEX1_STN2_TX_C_DN<41>                                         
P  NNAMEm4709 P5E_PEX2_STN0_RX_DP<3>                                            
P  NNAMEm4710 P5E_PEX2_STN7_TX_C_DN<119>                                        
P  NNAMEm4711 P5E_PEX3_STN6_RX_DN<106>                                          
P  NNAMEm4712 P5E_PEX0_STN2_RX_DP<47>                                           
P  NNAMEm4713 P5E_PEX1_STN2_RX_DP<47>                                           
P  NNAMEm4714 P5E_PEX2_STN0_TX_C_DP<0>                                          
P  NNAMEm4715 P5E_PEX2_STN7_RX_DP<113>                                          
P  NNAMEm4716 P5E_PEX3_STN6_RX_DP<106>                                          
P  NNAMEm4717 HP_NIC5_PWRGD_R                                                   
P  NNAMEm4718 P5E_PEX1_STN2_RX_DN<45>                                           
P  NNAMEm4719 P5E_PEX2_STN0_TX_C_DP<15>                                         
P  NNAMEm4720 P5E_PEX2_STN7_TX_C_DN<115>                                        
P  NNAMEm4721 P5E_PEX3_STN6_TX_C_DP<100>                                        
P  NNAMEm4722 P5E_PEX1_STN2_RX_DP<39>                                           
P  NNAMEm4723 P5E_PEX2_STN0_RX_DP<9>                                            
P  NNAMEm4724 P5E_PEX3_STN6_TX_C_DP<102>                                        
P  NNAMEm4725 P5E_PEX0_STN2_RX_DN<39>                                           
P  NNAMEm4726 P5E_PEX1_STN2_RX_DP<35>                                           
P  NNAMEm4727 P5E_PEX2_STN0_TX_C_DN<10>                                         
P  NNAMEm4728 P5E_PEX2_STN7_RX_DN<114>                                          
P  NNAMEm4729 P5E_PEX3_STN6_RX_DN<101>                                          
P  NNAMEm4730 P5E_PEX1_STN2_TX_C_DN<32>                                         
P  NNAMEm4731 P5E_PEX2_STN0_RX_DP<12>                                           
P  NNAMEm4732 P5E_PEX3_STN6_TX_C_DP<98>                                         
P  NNAMEm4733 RST_NIC0_PERST3_R_N                                               
P  NNAMEm4734 P5E_PEX1_STN2_TX_C_DN<38>                                         
P  NNAMEm4735 P5E_PEX2_STN0_TX_C_DN<4>                                          
P  NNAMEm4736 P5E_PEX2_STN7_TX_C_DP<119>                                        
P  NNAMEm4737 P5E_PEX3_STN6_TX_C_DP<106>                                        
P  NNAMEm4738 P5E_PEX1_STN2_TX_C_DP<37>                                         
P  NNAMEm4739 P5E_PEX2_STN0_RX_DP<14>                                           
P  NNAMEm4740 P5E_PEX3_STN6_RX_DN<100>                                          
P  NNAMEm4741 CLK_50M_NIC0_RBT_REF                                              
P  NNAMEm4742 P5E_PEX1_STN2_TX_C_DP<41>                                         
P  NNAMEm4743 P5E_PEX2_STN0_RX_DN<7>                                            
P  NNAMEm4744 P5E_PEX2_STN7_RX_DN<115>                                          
P  NNAMEm4745 P5E_PEX3_STN6_RX_DN<103>                                          
P  NNAMEm4746 P5E_PEX1_STN2_TX_C_DN<43>                                         
P  NNAMEm4747 P5E_PEX2_STN0_TX_C_DN<2>                                          
P  NNAMEm4748 P5E_PEX2_STN7_TX_C_DP<116>                                        
P  NNAMEm4749 P5E_PEX3_STN6_TX_C_DN<111>                                        
P  NNAMEm4750 P5E_PEX0_STN2_RX_DN<33>                                           
P  NNAMEm4751 P5E_PEX1_STN2_RX_DN<39>                                           
P  NNAMEm4752 P5E_PEX2_STN0_RX_DP<6>                                            
P  NNAMEm4753 P5E_PEX2_STN7_RX_DP<115>                                          
P  NNAMEm4754 P5E_PEX3_STN6_TX_C_DN<104>                                        
P  NNAMEm4755 P5E_PEX2_STN0_TX_C_DP<12>                                         
P  NNAMEm4756 P5E_PEX3_STN6_TX_C_DN<96>                                         
P  NNAMEm4757 P5E_PEX0_STN2_RX_DP<35>                                           
P  NNAMEm4758 P5E_PEX2_STN0_RX_DN<0>                                            
P  NNAMEm4759 P5E_PEX3_STN6_TX_C_DP<96>                                         
P  NNAMEm4760 P5E_PEX0_STN2_RX_DP<44>                                           
P  NNAMEm4761 P5E_PEX2_STN0_TX_C_DP<14>                                         
P  NNAMEm4762 P5E_PEX2_STN7_TX_C_DP<113>                                        
P  NNAMEm4763 P5E_PEX3_STN6_RX_DN<104>                                          
P  NNAMEm4764 P5E_PEX2_STN0_TX_C_DN<9>                                          
P  NNAMEm4765 P5E_PEX2_STN7_TX_C_DN<118>                                        
P  NNAMEm4766 NIC0_RBT_ARB_IN                                                   
P  NNAMEm4767 P5E_PEX2_STN0_TX_C_DP<8>                                          
P  NNAMEm4768 P5E_PEX0_STN2_RX_DN<44>                                           
P  NNAMEm4769 P5E_PEX2_STN0_RX_DN<14>                                           
P  NNAMEm4770 P5E_PEX0_STN2_RX_DN<43>                                           
P  NNAMEm4771 P5E_PEX2_STN7_RX_DP<112>                                          
P  NNAMEm4772 P5E_PEX0_STN2_TX_DP<40>                                           
P  NNAMEm4773 P5E_PEX1_STN5_TX_DP<91>                                           
P  NNAMEm4774 P5E_PEX2_STN2_TX_DN<42>                                           
P  NNAMEm4775 P5E_PEX2_STN6_TX_DP<99>                                           
P  NNAMEm4776 P5E_PEX3_STN0_TX_DN<5>                                            
P  NNAMEm4777 P5E_PEX3_STN6_TX_DP<104>                                          
P  NNAMEm4778 P5E_PEX0_STN2_TX_DN<43>                                           
P  NNAMEm4779 P5E_PEX1_STN5_TX_DP<85>                                           
P  NNAMEm4780 P5E_PEX2_STN5_TX_DN<86>                                           
P  NNAMEm4781 P5E_PEX2_STN6_TX_DN<111>                                          
P  NNAMEm4782 P5E_PEX3_STN0_TX_DP<0>                                            
P  NNAMEm4783 P5E_PEX3_STN7_TX_DP<124>                                          
P  NNAMEm4784 P5E_PEX0_STN2_TX_DP<32>                                           
P  NNAMEm4785 P5E_PEX1_STN5_TX_DN<91>                                           
P  NNAMEm4786 P5E_PEX2_STN2_TX_DP<40>                                           
P  NNAMEm4787 P5E_PEX2_STN6_TX_DP<96>                                           
P  NNAMEm4788 P5E_PEX3_STN0_TX_DN<7>                                            
P  NNAMEm4789 P5E_PEX3_STN6_TX_DN<98>                                           
P  NNAMEm4790 P5E_PEX0_STN5_TX_DN<89>                                           
P  NNAMEm4791 P5E_PEX1_STN2_TX_DN<42>                                           
P  NNAMEm4792 P5E_PEX2_STN5_TX_DP<82>                                           
P  NNAMEm4793 P5E_PEX2_STN7_TX_DP<121>                                          
P  NNAMEm4794 P5E_PEX3_STN1_TX_DP<20>                                           
P  NNAMEm4795 P5E_PEX3_STN6_TX_DP<102>                                          
P  NNAMEm4796 P5E_PEX0_STN2_TX_DP<46>                                           
P  NNAMEm4797 P5E_PEX1_STN2_TX_DN<44>                                           
P  NNAMEm4798 P5E_PEX2_STN5_TX_DN<87>                                           
P  NNAMEm4799 P5E_PEX2_STN6_TX_DP<111>                                          
P  NNAMEm4800 P5E_PEX3_STN0_TX_DN<9>                                            
P  NNAMEm4801 P5E_PEX3_STN7_TX_DP<114>                                          
P  NNAMEm4802 P5E_PEX0_STN2_TX_DN<39>                                           
P  NNAMEm4803 P5E_PEX1_STN2_TX_DN<46>                                           
P  NNAMEm4804 P5E_PEX2_STN5_TX_DP<95>                                           
P  NNAMEm4805 P5E_PEX2_STN7_TX_DN<119>                                          
P  NNAMEm4806 P5E_PEX3_STN1_TX_DP<16>                                           
P  NNAMEm4807 P5E_PEX3_STN7_TX_DP<127>                                          
P  NNAMEm4808 P5E_PEX0_STN2_TX_DN<40>                                           
P  NNAMEm4809 P5E_PEX1_STN2_TX_DN<34>                                           
P  NNAMEm4810 P5E_PEX2_STN2_TX_DN<38>                                           
P  NNAMEm4811 P5E_PEX2_STN7_TX_DN<113>                                          
P  NNAMEm4812 P5E_PEX3_STN1_TX_DP<22>                                           
P  NNAMEm4813 P5E_PEX3_STN7_TX_DN<116>                                          
P  NNAMEm4814 P5E_PEX0_STN2_TX_DN<44>                                           
P  NNAMEm4815 P5E_PEX1_STN5_TX_DP<86>                                           
P  NNAMEm4816 P5E_PEX2_STN5_TX_DN<80>                                           
P  NNAMEm4817 P5E_PEX2_STN7_TX_DN<117>                                          
P  NNAMEm4818 P5E_PEX3_STN0_TX_DP<5>                                            
P  NNAMEm4819 P5E_PEX3_STN7_TX_DN<123>                                          
P  NNAMEm4820 P5E_PEX0_STN5_TX_DN<81>                                           
P  NNAMEm4821 P5E_PEX1_STN2_TX_DN<36>                                           
P  NNAMEm4822 P5E_PEX2_STN7_TX_DP<112>                                          
P  NNAMEm4823 P5E_PEX3_STN1_TX_DP<28>                                           
P  NNAMEm4824 P5E_PEX3_STN6_TX_DP<99>                                           
P  NNAMEm4825 P5E_PEX0_STN5_TX_DN<85>                                           
P  NNAMEm4826 P5E_PEX1_STN2_TX_DN<40>                                           
P  NNAMEm4827 P5E_PEX2_STN6_TX_DN<101>                                          
P  NNAMEm4828 P5E_PEX3_STN1_TX_DP<29>                                           
P  NNAMEm4829 P5E_PEX3_STN7_TX_DP<120>                                          
P  NNAMEm4830 P5E_PEX0_STN5_TX_DN<95>                                           
P  NNAMEm4831 P5E_PEX1_STN2_TX_DN<45>                                           
P  NNAMEm4832 P5E_PEX2_STN6_TX_DN<104>                                          
P  NNAMEm4833 P5E_PEX3_STN1_TX_DN<21>                                           
P  NNAMEm4834 P5E_PEX3_STN7_TX_DP<118>                                          
P  NNAMEm4835 P5E_PEX0_STN5_TX_DN<94>                                           
P  NNAMEm4836 P5E_PEX1_STN2_TX_DP<34>                                           
P  NNAMEm4837 P5E_PEX2_STN7_TX_DP<124>                                          
P  NNAMEm4838 P5E_PEX3_STN0_TX_DN<11>                                           
P  NNAMEm4839 P5E_PEX3_STN7_TX_DP<112>                                          
P  NNAMEm4840 P5E_PEX0_STN5_TX_DP<86>                                           
P  NNAMEm4841 P5E_PEX1_STN5_TX_DP<88>                                           
P  NNAMEm4842 P5E_PEX2_STN7_TX_DN<120>                                          
P  NNAMEm4843 P5E_PEX3_STN1_TX_DP<31>                                           
P  NNAMEm4844 P5E_PEX3_STN7_TX_DP<122>                                          
P  NNAMEm4845 P5E_PEX0_STN2_TX_DN<46>                                           
P  NNAMEm4846 P5E_PEX1_STN2_TX_DP<35>                                           
P  NNAMEm4847 P5E_PEX2_STN0_TX_DP<9>                                            
P  NNAMEm4848 P5E_PEX2_STN6_TX_DN<109>                                          
P  NNAMEm4849 P5E_PEX3_STN0_TX_DN<2>                                            
P  NNAMEm4850 P5E_PEX3_STN7_TX_DN<125>                                          
P  NNAMEm4851 P5E_PEX0_STN2_TX_DP<47>                                           
P  NNAMEm4852 P5E_PEX1_STN2_TX_DP<33>                                           
P  NNAMEm4853 P5E_PEX2_STN1_TX_DP<21>                                           
P  NNAMEm4854 P5E_PEX2_STN6_TX_DN<99>                                           
P  NNAMEm4855 P5E_PEX3_STN1_TX_DN<26>                                           
P  NNAMEm4856 P5E_PEX3_STN7_TX_DP<121>                                          
P  NNAMEm4857 P5E_PEX0_STN2_TX_DP<33>                                           
P  NNAMEm4858 P5E_PEX1_STN2_TX_DP<40>                                           
P  NNAMEm4859 P5E_PEX2_STN0_TX_DN<4>                                            
P  NNAMEm4860 P5E_PEX2_STN7_TX_DP<119>                                          
P  NNAMEm4861 P5E_PEX3_STN1_TX_DN<17>                                           
P  NNAMEm4862 P5E_PEX3_STN6_TX_DN<99>                                           
P  NNAMEm4863 P5E_PEX0_STN2_TX_DN<35>                                           
P  NNAMEm4864 P5E_PEX1_STN5_TX_DN<94>                                           
P  NNAMEm4865 P5E_PEX2_STN0_TX_DP<11>                                           
P  NNAMEm4866 P5E_PEX2_STN7_TX_DN<126>                                          
P  NNAMEm4867 P5E_PEX3_STN1_TX_DP<26>                                           
P  NNAMEm4868 P5E_PEX3_STN6_TX_DN<105>                                          
P  NNAMEm4869 P5E_PEX0_STN2_TX_DN<42>                                           
P  NNAMEm4870 P5E_PEX1_STN5_TX_DP<94>                                           
P  NNAMEm4871 P5E_PEX2_STN0_TX_DN<2>                                            
P  NNAMEm4872 P5E_PEX2_STN7_TX_DP<120>                                          
P  NNAMEm4873 P5E_PEX3_STN0_TX_DP<10>                                           
P  NNAMEm4874 P5E_PEX3_STN6_TX_DP<96>                                           
P  NNAMEm4875 P5E_PEX0_STN7_RX_DN<120>                                          
P  NNAMEm4876 P5E_PEX1_STN5_TX_C_DP<91>                                         
P  NNAMEm4877 P5E_PEX0_STN2_TX_DP<45>                                           
P  NNAMEm4878 P5E_PEX1_STN2_TX_DP<43>                                           
P  NNAMEm4879 P5E_PEX2_STN1_TX_DP<26>                                           
P  NNAMEm4880 P5E_PEX2_STN7_TX_DP<114>                                          
P  NNAMEm4881 P5E_PEX3_STN1_TX_DP<21>                                           
P  NNAMEm4882 P5E_PEX3_STN7_TX_DP<123>                                          
P  NNAMEm4883 P5E_PEX0_STN5_TX_DN<90>                                           
P  NNAMEm4884 P5E_PEX1_STN5_TX_DN<93>                                           
P  NNAMEm4885 P5E_PEX2_STN0_TX_DN<6>                                            
P  NNAMEm4886 P5E_PEX2_STN6_TX_DP<108>                                          
P  NNAMEm4887 P5E_PEX3_STN1_TX_DP<18>                                           
P  NNAMEm4888 P5E_PEX3_STN6_TX_DP<101>                                          
P  NNAMEm4889 P5E_PEX1_STN7_TX_C_DN<121>                                        
P  NNAMEm4890 P5E_PEX0_STN5_TX_DN<88>                                           
P  NNAMEm4891 P5E_PEX1_STN5_TX_DP<82>                                           
P  NNAMEm4892 P5E_PEX2_STN1_TX_DN<27>                                           
P  NNAMEm4893 P5E_PEX2_STN6_TX_DP<97>                                           
P  NNAMEm4894 P5E_PEX3_STN1_TX_DN<27>                                           
P  NNAMEm4895 P5E_PEX3_STN6_TX_DP<107>                                          
P  NNAMEm4896 P5E_PEX0_STN2_TX_DP<36>                                           
P  NNAMEm4897 P5E_PEX1_STN5_TX_DP<95>                                           
P  NNAMEm4898 P5E_PEX2_STN1_TX_DP<20>                                           
P  NNAMEm4899 P5E_PEX2_STN7_TX_DP<125>                                          
P  NNAMEm4900 P5E_PEX3_STN1_TX_DN<28>                                           
P  NNAMEm4901 P5E_PEX3_STN6_TX_DP<111>                                          
P  NNAMEm4902 P5E_PEX1_STN5_TX_C_DP<90>                                         
P  NNAMEm4903 P5E_PEX0_STN2_TX_DN<37>                                           
P  NNAMEm4904 P5E_PEX1_STN2_TX_DN<38>                                           
P  NNAMEm4905 P5E_PEX2_STN0_TX_DN<0>                                            
P  NNAMEm4906 P5E_PEX2_STN6_TX_DN<105>                                          
P  NNAMEm4907 P5E_PEX3_STN0_TX_DN<3>                                            
P  NNAMEm4908 P5E_PEX3_STN7_TX_DP<117>                                          
P  NNAMEm4909 P5E_PEX1_STN5_TX_C_DP<89>                                         
P  NNAMEm4910 P5E_PEX0_STN2_TX_DP<38>                                           
P  NNAMEm4911 P5E_PEX1_STN2_TX_DP<44>                                           
P  NNAMEm4912 P5E_PEX2_STN0_TX_DP<15>                                           
P  NNAMEm4913 P5E_PEX2_STN6_TX_DN<100>                                          
P  NNAMEm4914 P5E_PEX3_STN0_TX_DP<2>                                            
P  NNAMEm4915 P5E_PEX3_STN7_TX_DN<120>                                          
P  NNAMEm4916 P5E_PEX1_STN7_TX_C_DP<120>                                        
P  NNAMEm4917 P5E_PEX1_STN2_TX_DP<37>                                           
P  NNAMEm4918 P5E_PEX2_STN0_TX_DN<8>                                            
P  NNAMEm4919 P5E_PEX2_STN7_TX_DP<126>                                          
P  NNAMEm4920 P5E_PEX3_STN0_TX_DP<8>                                            
P  NNAMEm4921 P5E_PEX3_STN7_TX_DP<113>                                          
P  NNAMEm4922 P5E_PEX1_STN5_TX_DP<90>                                           
P  NNAMEm4923 P5E_PEX2_STN1_TX_DP<30>                                           
P  NNAMEm4924 P5E_PEX2_STN7_TX_DN<115>                                          
P  NNAMEm4925 P5E_PEX3_STN1_TX_DP<24>                                           
P  NNAMEm4926 P5E_PEX3_STN7_TX_DP<115>                                          
P  NNAMEm4927 P5E_PEX1_STN7_TX_C_DP<125>                                        
P  NNAMEm4928 P5E_PEX1_STN2_TX_DN<39>                                           
P  NNAMEm4929 P5E_PEX2_STN0_TX_DN<11>                                           
P  NNAMEm4930 P5E_PEX2_STN7_TX_DN<125>                                          
P  NNAMEm4931 P5E_PEX3_STN1_TX_DN<18>                                           
P  NNAMEm4932 P5E_PEX3_STN6_TX_DP<106>                                          
P  NNAMEm4933 P5E_PEX0_STN7_TX_C_DN<119>                                        
P  NNAMEm4934 P5E_PEX1_STN7_TX_C_DN<122>                                        
P  NNAMEm4935 P5E_PEX1_STN2_TX_DN<32>                                           
P  NNAMEm4936 P5E_PEX2_STN1_TX_DP<23>                                           
P  NNAMEm4937 P5E_PEX2_STN6_TX_DP<103>                                          
P  NNAMEm4938 P5E_PEX3_STN0_TX_DP<4>                                            
P  NNAMEm4939 P5E_PEX3_STN6_TX_DP<103>                                          
P  NNAMEm4940 P5E_PEX1_STN5_TX_DP<84>                                           
P  NNAMEm4941 P5E_PEX2_STN1_TX_DN<28>                                           
P  NNAMEm4942 P5E_PEX2_STN7_TX_DP<118>                                          
P  NNAMEm4943 P5E_PEX3_STN0_TX_DP<15>                                           
P  NNAMEm4944 P5E_PEX2_STN7_RX_DN<127>                                          
P  NNAMEm4945 P5E_PEX1_STN5_TX_C_DN<89>                                         
P  NNAMEm4946 P5E_PEX1_STN5_TX_DP<87>                                           
P  NNAMEm4947 P5E_PEX2_STN1_TX_DN<17>                                           
P  NNAMEm4948 P5E_PEX2_STN6_TX_DN<102>                                          
P  NNAMEm4949 P5E_PEX3_STN0_TX_DP<9>                                            
P  NNAMEm4950 P5E_PEX2_STN7_RX_DP<123>                                          
P  NNAMEm4951 P5E_PEX0_STN7_TX_C_DP<119>                                        
P  NNAMEm4952 P5E_PEX1_STN5_TX_C_DP<92>                                         
P  NNAMEm4953 P5E_PEX1_STN5_TX_DP<89>                                           
P  NNAMEm4954 P5E_PEX2_STN0_TX_DP<12>                                           
P  NNAMEm4955 P5E_PEX2_STN7_TX_DP<116>                                          
P  NNAMEm4956 P5E_PEX3_STN0_TX_DN<1>                                            
P  NNAMEm4957 P5E_PEX1_STN5_TX_DN<82>                                           
P  NNAMEm4958 P5E_PEX2_STN1_TX_DP<27>                                           
P  NNAMEm4959 P5E_PEX2_STN7_TX_DN<112>                                          
P  NNAMEm4960 P5E_PEX3_STN1_TX_DN<29>                                           
P  NNAMEm4961 P5E_PEX2_STN5_RX_DN<88>                                           
P  NNAMEm4962 P5E_PEX1_STN7_TX_C_DN<120>                                        
P  NNAMEm4963 P5E_PEX1_STN5_TX_DP<81>                                           
P  NNAMEm4964 P5E_PEX2_STN1_TX_DN<20>                                           
P  NNAMEm4965 P5E_PEX2_STN6_TX_DP<104>                                          
P  NNAMEm4966 P5E_PEX3_STN0_TX_DP<12>                                           
P  NNAMEm4967 P5E_PEX1_STN5_TX_C_DN<92>                                         
P  NNAMEm4968 P5E_PEX1_STN2_TX_DN<47>                                           
P  NNAMEm4969 P5E_PEX2_STN0_TX_DP<1>                                            
P  NNAMEm4970 P5E_PEX2_STN7_TX_DN<118>                                          
P  NNAMEm4971 P5E_PEX3_STN0_TX_DN<0>                                            
P  NNAMEm4972 P5E_PEX2_STN7_RX_DN<126>                                          
P  NNAMEm4973 P5E_PEX1_STN2_TX_DP<46>                                           
P  NNAMEm4974 P5E_PEX1_STN6_TX_DP<104>                                          
P  NNAMEm4975 P5E_PEX2_STN0_TX_DN<1>                                            
P  NNAMEm4976 P5E_PEX2_STN6_TX_DP<107>                                          
P  NNAMEm4977 P5E_PEX3_STN1_TX_DP<17>                                           
P  NNAMEm4978 P5E_PEX2_STN7_RX_DP<121>                                          
P  NNAMEm4979 P5E_PEX1_STN5_TX_DN<83>                                           
P  NNAMEm4980 P5E_PEX1_STN7_TX_DP<124>                                          
P  NNAMEm4981 P5E_PEX2_STN0_TX_DP<3>                                            
P  NNAMEm4982 P5E_PEX2_STN7_TX_DP<115>                                          
P  NNAMEm4983 P5E_PEX3_STN1_TX_DP<23>                                           
P  NNAMEm4984 P5E_PEX1_STN5_TX_DP<92>                                           
P  NNAMEm4985 P5E_PEX1_STN7_TX_DN<123>                                          
P  NNAMEm4986 P5E_PEX2_STN0_TX_DP<0>                                            
P  NNAMEm4987 P5E_PEX2_STN7_TX_DP<113>                                          
P  NNAMEm4988 P5E_PEX3_STN1_TX_DN<30>                                           
P  NNAMEm4989 P5E_PEX1_STN7_TX_C_DN<124>                                        
P  NNAMEm4990 P5E_PEX1_STN2_TX_DP<45>                                           
P  NNAMEm4991 P5E_PEX1_STN7_TX_DP<115>                                          
P  NNAMEm4992 P5E_PEX2_STN0_TX_DP<13>                                           
P  NNAMEm4993 P5E_PEX2_STN6_TX_DN<103>                                          
P  NNAMEm4994 P5E_PEX3_STN1_TX_DP<19>                                           
P  NNAMEm4995 P5E_PEX2_STN7_RX_DP<127>                                          
P  NNAMEm4996 P5E_PEX1_STN7_TX_C_DN<126>                                        
P  NNAMEm4997 P5E_PEX1_STN5_TX_DN<89>                                           
P  NNAMEm4998 P5E_PEX1_STN6_TX_DN<97>                                           
P  NNAMEm4999 P5E_PEX2_STN0_TX_DP<6>                                            
P  NNAMEm5000 P5E_PEX2_STN6_TX_DN<108>                                          
P  NNAMEm5001 P5E_PEX3_STN1_TX_DN<23>                                           
P  NNAMEm5002 P5E_PEX1_STN2_TX_DP<41>                                           
P  NNAMEm5003 P5E_PEX1_STN6_TX_DN<100>                                          
P  NNAMEm5004 P5E_PEX2_STN1_TX_DN<16>                                           
P  NNAMEm5005 P5E_PEX2_STN6_TX_DN<110>                                          
P  NNAMEm5006 P5E_PEX3_STN1_TX_DN<25>                                           
P  NNAMEm5007 P5E_PEX1_STN5_TX_C_DN<91>                                         
P  NNAMEm5008 P5E_PEX1_STN2_TX_DN<43>                                           
P  NNAMEm5009 P5E_PEX1_STN7_TX_DP<116>                                          
P  NNAMEm5010 P5E_PEX2_STN1_TX_DP<31>                                           
P  NNAMEm5011 P5E_PEX2_STN6_TX_DP<105>                                          
P  NNAMEm5012 P5E_PEX3_STN0_TX_DP<11>                                           
P  NNAMEm5013 P5E_PEX1_STN2_TX_DP<38>                                           
P  NNAMEm5014 P5E_PEX1_STN6_TX_DP<109>                                          
P  NNAMEm5015 P5E_PEX2_STN0_TX_DP<4>                                            
P  NNAMEm5016 P5E_PEX2_STN7_TX_DP<122>                                          
P  NNAMEm5017 P5E_PEX3_STN0_TX_DN<13>                                           
P  NNAMEm5018 P5E_PEX1_STN5_TX_C_DP<94>                                         
P  NNAMEm5019 P5E_PEX1_STN5_TX_DP<80>                                           
P  NNAMEm5020 P5E_PEX1_STN7_TX_DN<127>                                          
P  NNAMEm5021 P5E_PEX2_STN1_TX_DP<18>                                           
P  NNAMEm5022 P5E_PEX2_STN7_TX_DP<123>                                          
P  NNAMEm5023 RST_HP_NIC7_BUF_N                                                 
P  NNAMEm5024 P5E_PEX1_STN7_TX_C_DN<123>                                        
P  NNAMEm5025 P5E_PEX1_STN7_TX_DP<118>                                          
P  NNAMEm5026 P5E_PEX2_STN0_TX_DN<7>                                            
P  NNAMEm5027 P5E_PEX2_STN7_TX_DN<122>                                          
P  NNAMEm5028 P5E_PEX1_STN5_TX_C_DN<94>                                         
P  NNAMEm5029 P5E_PEX1_STN7_TX_DP<127>                                          
P  NNAMEm5030 P5E_PEX2_STN1_TX_DP<25>                                           
P  NNAMEm5031 P5E_PEX2_STN6_TX_DP<100>                                          
P  NNAMEm5032 P5E_PEX2_STN7_RX_DP<124>                                          
P  NNAMEm5033 P5E_PEX0_STN7_TX_C_DN<115>                                        
P  NNAMEm5034 P5E_PEX1_STN6_TX_DP<99>                                           
P  NNAMEm5035 P5E_PEX2_STN1_TX_DN<24>                                           
P  NNAMEm5036 P5E_PEX2_STN6_TX_DP<106>                                          
P  NNAMEm5037 P5E_PEX2_STN7_RX_DP<122>                                          
P  NNAMEm5038 P5E_PEX1_STN5_TX_C_DN<88>                                         
P  NNAMEm5039 P5E_PEX1_STN7_TX_DN<114>                                          
P  NNAMEm5040 P5E_PEX2_STN0_TX_DN<5>                                            
P  NNAMEm5041 P5E_PEX2_STN6_TX_DN<96>                                           
P  NNAMEm5042 HP_NIC7_HSC_PWRGD_N                                               
P  NNAMEm5043 P5E_PEX0_STN7_TX_C_DP<114>                                        
P  NNAMEm5044 P5E_PEX1_STN7_TX_DN<115>                                          
P  NNAMEm5045 P5E_PEX2_STN1_TX_DN<23>                                           
P  NNAMEm5046 P5E_PEX2_STN6_TX_DP<109>                                          
P  NNAMEm5047 P5E_PEX1_STN0_TX_DN<15>                                           
P  NNAMEm5048 P5E_PEX1_STN7_TX_DP<119>                                          
P  NNAMEm5049 P5E_PEX2_STN1_TX_DP<29>                                           
P  NNAMEm5050 P5E_PEX2_STN7_TX_DP<117>                                          
P  NNAMEm5051 P5E_PEX2_STN5_RX_DN<91>                                           
P  NNAMEm5052 P5E_PEX0_STN7_TX_C_DN<114>                                        
P  NNAMEm5053 P5E_PEX1_STN5_TX_C_DN<90>                                         
P  NNAMEm5054 P5E_PEX1_STN1_TX_DP<21>                                           
P  NNAMEm5055 P5E_PEX1_STN6_TX_DP<105>                                          
P  NNAMEm5056 P5E_PEX2_STN0_TX_DP<5>                                            
P  NNAMEm5057 P5E_PEX2_STN7_TX_DN<116>                                          
P  NNAMEm5058 RST_SMB_NIC3_MUX_N                                                
P  NNAMEm5059 P5E_PEX1_STN1_TX_DN<18>                                           
P  NNAMEm5060 P5E_PEX1_STN7_TX_DN<122>                                          
P  NNAMEm5061 P5E_PEX2_STN1_TX_DP<17>                                           
P  NNAMEm5062 P5E_PEX2_STN6_TX_DN<106>                                          
P  NNAMEm5063 P5E_PEX2_STN5_RX_DN<92>                                           
P  NNAMEm5064 RST_SMB_NIC3_MUX_ISO_N                                            
P  NNAMEm5065 P5E_PEX0_STN7_TX_C_DP<113>                                        
P  NNAMEm5066 P5E_PEX1_STN5_TX_C_DP<95>                                         
P  NNAMEm5067 P5E_PEX1_STN0_TX_DP<8>                                            
P  NNAMEm5068 P5E_PEX1_STN6_TX_DN<110>                                          
P  NNAMEm5069 P5E_PEX2_STN1_TX_DP<22>                                           
P  NNAMEm5070 P5E_PEX2_STN7_TX_DN<123>                                          
P  NNAMEm5071 P5E_PEX2_STN5_RX_DN<93>                                           
P  NNAMEm5072 RST_SMB_NIC0_MUX_N                                                
P  NNAMEm5073 P5E_PEX1_STN1_TX_DP<31>                                           
P  NNAMEm5074 P5E_PEX1_STN6_TX_DP<110>                                          
P  NNAMEm5075 P5E_PEX2_STN1_TX_DN<21>                                           
P  NNAMEm5076 P5E_PEX2_STN7_TX_DN<127>                                          
P  NNAMEm5077 P5E_PEX2_STN5_RX_DP<94>                                           
P  NNAMEm5078 RST_SMB_NIC0_MUX_ISO_N                                            
P  NNAMEm5079 P5E_PEX0_STN7_TX_C_DN<113>                                        
P  NNAMEm5080 P5E_PEX1_STN7_TX_C_DP<121>                                        
P  NNAMEm5081 P5E_PEX1_STN0_TX_DN<11>                                           
P  NNAMEm5082 P5E_PEX1_STN7_TX_DN<119>                                          
P  NNAMEm5083 P5E_PEX2_STN1_TX_DN<25>                                           
P  NNAMEm5084 P5E_PEX2_STN7_TX_DP<127>                                          
P  NNAMEm5085 RST_SMB_NIC6_MUX_N                                                
P  NNAMEm5086 P5E_PEX1_STN0_TX_DN<8>                                            
P  NNAMEm5087 P5E_PEX1_STN6_TX_DN<103>                                          
P  NNAMEm5088 P5E_PEX2_STN0_TX_DN<3>                                            
P  NNAMEm5089 P5E_PEX2_STN6_TX_DP<98>                                           
P  NNAMEm5090 RST_SMB_NIC6_MUX_ISO_N                                            
P  NNAMEm5091 HP_NIC1_HSC_PWRGD_N                                               
P  NNAMEm5092 P5E_PEX1_STN0_TX_DP<14>                                           
P  NNAMEm5093 P5E_PEX1_STN7_TX_DP<113>                                          
P  NNAMEm5094 P5E_PEX2_STN0_TX_DN<15>                                           
P  NNAMEm5095 P5E_PEX2_STN7_TX_DN<114>                                          
P  NNAMEm5096 HP_NIC4_HSC_PWRGD_N                                               
P  NNAMEm5097 RST_HP_NIC1_BUF_N                                                 
P  NNAMEm5098 P5E_PEX1_STN7_TX_C_DP<127>                                        
P  NNAMEm5099 P5E_PEX1_STN1_TX_DP<19>                                           
P  NNAMEm5100 P5E_PEX1_STN7_TX_DP<120>                                          
P  NNAMEm5101 P5E_PEX2_STN1_TX_DN<26>                                           
P  NNAMEm5102 P5E_PEX2_STN6_TX_DN<97>                                           
P  NNAMEm5103 P5E_PEX2_STN5_RX_DN<95>                                           
P  NNAMEm5104 RST_HP_NIC4_BUF_N                                                 
P  NNAMEm5105 P5E_PEX1_STN0_TX_DP<11>                                           
P  NNAMEm5106 P5E_PEX1_STN6_TX_DP<98>                                           
P  NNAMEm5107 P5E_PEX2_STN1_TX_DN<18>                                           
P  NNAMEm5108 P5E_PEX2_STN6_TX_DN<98>                                           
P  NNAMEm5109 P5E_PEX1_STN7_TX_C_DN<127>                                        
P  NNAMEm5110 P5E_PEX1_STN1_TX_DP<29>                                           
P  NNAMEm5111 P5E_PEX1_STN6_TX_DN<109>                                          
P  NNAMEm5112 P5E_PEX2_STN0_TX_DP<10>                                           
P  NNAMEm5113 P5E_PEX2_STN6_TX_DP<110>                                          
P  NNAMEm5114 P5E_PEX2_STN5_RX_DP<93>                                           
P  NNAMEm5115 P5E_PEX1_STN0_TX_DN<9>                                            
P  NNAMEm5116 P5E_PEX1_STN7_TX_DN<116>                                          
P  NNAMEm5117 P5E_PEX2_STN1_TX_DN<22>                                           
P  NNAMEm5118 P5E_PEX2_STN6_TX_DN<107>                                          
P  NNAMEm5119 P5E_PEX2_STN7_RX_DP<126>                                          
P  NNAMEm5120 P5E_PEX1_STN1_TX_DN<28>                                           
P  NNAMEm5121 P5E_PEX1_STN6_TX_DN<96>                                           
P  NNAMEm5122 P5E_PEX2_STN0_TX_DN<14>                                           
P  NNAMEm5123 P5E_PEX2_STN7_TX_DN<121>                                          
P  NNAMEm5124 P5E_PEX2_STN5_RX_DP<90>                                           
P  NNAMEm5125 P5E_PEX1_STN0_TX_DP<2>                                            
P  NNAMEm5126 P5E_PEX1_STN6_TX_DN<101>                                          
P  NNAMEm5127 P5E_PEX2_STN0_TX_DP<7>                                            
P  NNAMEm5128 P5E_PEX2_STN6_TX_DP<102>                                          
P  NNAMEm5129 P5E_PEX2_STN5_RX_DP<91>                                           
P  NNAMEm5130 P5E_PEX1_STN5_TX_C_DP<93>                                         
P  NNAMEm5131 P5E_PEX1_STN0_TX_DP<10>                                           
P  NNAMEm5132 P5E_PEX1_STN6_TX_DN<105>                                          
P  NNAMEm5133 P5E_PEX2_STN0_TX_DP<14>                                           
P  NNAMEm5134 P5E_PEX2_STN7_TX_DN<124>                                          
P  NNAMEm5135 P5E_PEX2_STN5_RX_DP<89>                                           
P  NNAMEm5136 P5E_PEX1_STN0_TX_DP<0>                                            
P  NNAMEm5137 P5E_PEX1_STN6_TX_DP<97>                                           
P  NNAMEm5138 P5E_PEX2_STN1_TX_DN<31>                                           
P  NNAMEm5139 P5E_PEX1_STN1_TX_DN<26>                                           
P  NNAMEm5140 P5E_PEX1_STN7_TX_DP<122>                                          
P  NNAMEm5141 P5E_PEX2_STN0_TX_DN<9>                                            
P  NNAMEm5142 P5E_PEX1_STN7_TX_C_DN<125>                                        
P  NNAMEm5143 P5E_PEX1_STN0_TX_DN<4>                                            
P  NNAMEm5144 P5E_PEX1_STN6_TX_DN<107>                                          
P  NNAMEm5145 P5E_PEX2_STN0_TX_DP<2>                                            
P  NNAMEm5146 P5E_PEX1_STN7_TX_C_DP<122>                                        
P  NNAMEm5147 P5E_PEX1_STN1_TX_DP<27>                                           
P  NNAMEm5148 P5E_PEX1_STN6_TX_DN<99>                                           
P  NNAMEm5149 P5E_PEX2_STN0_TX_DN<13>                                           
P  NNAMEm5150 P5E_PEX2_STN5_RX_DN<94>                                           
P  NNAMEm5151 P5E_PEX1_STN5_TX_C_DN<93>                                         
P  NNAMEm5152 P5E_PEX1_STN0_TX_DP<4>                                            
P  NNAMEm5153 P5E_PEX1_STN7_TX_DP<112>                                          
P  NNAMEm5154 P5E_PEX2_STN1_TX_DP<24>                                           
P  NNAMEm5155 P5E_PEX2_STN7_RX_DN<125>                                          
P  NNAMEm5156 P5E_PEX1_STN7_TX_C_DP<123>                                        
P  NNAMEm5157 P5E_PEX1_STN1_TX_DP<30>                                           
P  NNAMEm5158 P5E_PEX1_STN7_TX_DP<114>                                          
P  NNAMEm5159 P5E_PEX2_STN0_TX_DN<12>                                           
P  NNAMEm5160 P5E_PEX2_STN7_RX_DN<124>                                          
P  NNAMEm5161 P5E_PEX1_STN1_TX_DP<26>                                           
P  NNAMEm5162 P5E_PEX1_STN6_TX_DP<106>                                          
P  NNAMEm5163 P5E_PEX2_STN1_TX_DN<29>                                           
P  NNAMEm5164 P5E_PEX1_STN5_TX_C_DP<88>                                         
P  NNAMEm5165 P5E_PEX1_STN1_TX_DN<24>                                           
P  NNAMEm5166 P5E_PEX1_STN7_TX_DP<117>                                          
P  NNAMEm5167 P5E_PEX2_STN0_TX_DP<8>                                            
P  NNAMEm5168 P5E_PEX2_STN7_RX_DN<122>                                          
P  NNAMEm5169 P5E_PEX1_STN0_TX_DP<5>                                            
P  NNAMEm5170 P5E_PEX1_STN6_TX_DP<103>                                          
P  NNAMEm5171 P5E_PEX2_STN1_TX_DP<28>                                           
P  NNAMEm5172 P5E_PEX1_STN5_RX_DP<82>                                           
P  NNAMEm5173 P5E_PEX1_STN0_TX_DN<5>                                            
P  NNAMEm5174 P5E_PEX1_STN6_TX_DP<107>                                          
P  NNAMEm5175 P5E_PEX2_STN1_TX_DP<16>                                           
P  NNAMEm5176 P5E_PEX1_STN7_RX_DN<119>                                          
P  NNAMEm5177 P5E_PEX2_STN7_RX_DN<123>                                          
P  NNAMEm5178 P5E_PEX1_STN1_TX_DP<16>                                           
P  NNAMEm5179 P5E_PEX1_STN7_TX_DN<120>                                          
P  NNAMEm5180 P5E_PEX2_STN1_TX_DP<19>                                           
P  NNAMEm5181 P5E_PEX1_STN7_RX_DN<117>                                          
P  NNAMEm5182 P5E_PEX0_STN7_TX_C_DN<112>                                        
P  NNAMEm5183 P5E_PEX1_STN7_TX_C_DP<124>                                        
P  NNAMEm5184 P5E_PEX1_STN1_TX_DP<24>                                           
P  NNAMEm5185 P5E_PEX1_STN7_TX_DP<125>                                          
P  NNAMEm5186 P5E_PEX2_STN1_TX_DN<30>                                           
P  NNAMEm5187 P5E_PEX1_STN5_RX_DP<83>                                           
P  NNAMEm5188 P5E_PEX2_STN5_RX_DN<90>                                           
P  NNAMEm5189 P5E_PEX0_STN7_TX_DP<123>                                          
P  NNAMEm5190 P5E_PEX1_STN0_TX_DN<2>                                            
P  NNAMEm5191 P5E_PEX1_STN7_TX_DN<112>                                          
P  NNAMEm5192 P5E_PEX2_STN1_TX_DN<19>                                           
P  NNAMEm5193 P5E_PEX1_STN5_RX_DN<82>                                           
P  NNAMEm5194 P5E_PEX2_STN5_RX_DP<88>                                           
P  NNAMEm5195 P5E_PEX0_STN7_TX_C_DP<112>                                        
P  NNAMEm5196 P5E_PEX1_STN0_TX_DN<6>                                            
P  NNAMEm5197 P5E_PEX1_STN7_TX_DN<124>                                          
P  NNAMEm5198 P5E_PEX2_STN0_TX_DN<10>                                           
P  NNAMEm5199 P5E_PEX1_STN7_RX_DP<118>                                          
P  NNAMEm5200 P5E_PEX1_STN7_TX_C_DP<126>                                        
P  NNAMEm5201 P5E_PEX1_STN1_TX_DP<20>                                           
P  NNAMEm5202 P5E_PEX1_STN6_TX_DN<111>                                          
P  NNAMEm5203 P5E_PEX1_STN7_RX_DP<116>                                          
P  NNAMEm5204 P5E_PEX2_STN5_RX_DP<95>                                           
P  NNAMEm5205 P5E_PEX1_STN5_TX_C_DN<95>                                         
P  NNAMEm5206 P5E_PEX0_STN7_TX_DN<123>                                          
P  NNAMEm5207 P5E_PEX1_STN1_TX_DN<29>                                           
P  NNAMEm5208 P5E_PEX1_STN7_TX_DN<118>                                          
P  NNAMEm5209 P5E_PEX1_STN7_RX_DN<116>                                          
P  NNAMEm5210 P5E_PEX2_STN7_RX_DN<120>                                          
P  NNAMEm5211 P5E_PEX0_STN7_TX_DN<122>                                          
P  NNAMEm5212 P5E_PEX1_STN0_TX_DN<13>                                           
P  NNAMEm5213 P5E_PEX1_STN6_TX_DP<111>                                          
P  NNAMEm5214 P5E_PEX1_STN7_RX_DN<115>                                          
P  NNAMEm5215 P5E_PEX2_STN5_RX_DN<89>                                           
P  NNAMEm5216 P5E_PEX1_STN0_TX_DN<1>                                            
P  NNAMEm5217 P5E_PEX1_STN7_TX_DN<125>                                          
P  NNAMEm5218 P5E_PEX1_STN5_RX_DN<84>                                           
P  NNAMEm5219 P5E_PEX2_STN7_RX_DP<125>                                          
P  NNAMEm5220 P5E_PEX1_STN1_TX_DN<16>                                           
P  NNAMEm5221 P5E_PEX1_STN6_TX_DN<102>                                          
P  NNAMEm5222 P5E_PEX1_STN5_RX_DP<86>                                           
P  NNAMEm5223 P5E_PEX2_STN7_RX_DN<121>                                          
P  NNAMEm5224 P5E_PEX0_STN7_TX_DP<116>                                          
P  NNAMEm5225 P5E_PEX1_STN1_TX_DN<25>                                           
P  NNAMEm5226 P5E_PEX1_STN6_TX_DP<96>                                           
P  NNAMEm5227 P5E_PEX1_STN5_RX_DN<85>                                           
P  NNAMEm5228 P5E_PEX0_STN7_TX_DP<125>                                          
P  NNAMEm5229 P5E_PEX1_STN1_TX_DN<22>                                           
P  NNAMEm5230 P5E_PEX1_STN6_TX_DP<108>                                          
P  NNAMEm5231 P5E_PEX1_STN5_RX_DN<81>                                           
P  NNAMEm5232 P5E_PEX1_STN0_TX_DP<13>                                           
P  NNAMEm5233 P5E_PEX1_STN7_TX_DN<121>                                          
P  NNAMEm5234 P5E_PEX1_STN5_RX_DN<86>                                           
P  NNAMEm5235 P5E_PEX1_STN0_TX_DN<14>                                           
P  NNAMEm5236 P5E_PEX1_STN7_TX_DP<123>                                          
P  NNAMEm5237 P5E_PEX1_STN7_RX_DP<119>                                          
P  NNAMEm5238 P5E_PEX2_STN5_RX_DP<92>                                           
P  NNAMEm5239 P5E_PEX1_STN1_TX_DN<17>                                           
P  NNAMEm5240 P5E_PEX1_STN7_TX_DP<126>                                          
P  NNAMEm5241 P5E_PEX1_STN5_RX_DP<87>                                           
P  NNAMEm5242 P5E_PEX1_STN0_TX_DP<9>                                            
P  NNAMEm5243 P5E_PEX1_STN7_TX_DN<117>                                          
P  NNAMEm5244 P5E_PEX1_STN7_RX_DN<114>                                          
P  NNAMEm5245 P5E_PEX0_STN7_TX_DP<122>                                          
P  NNAMEm5246 P5E_PEX1_STN0_TX_DN<12>                                           
P  NNAMEm5247 P5E_PEX1_STN7_TX_DN<126>                                          
P  NNAMEm5248 P5E_PEX1_STN7_RX_DN<113>                                          
P  NNAMEm5249 P5E_PEX2_STN7_RX_DP<120>                                          
P  NNAMEm5250 P5E_PEX0_STN7_TX_DN<127>                                          
P  NNAMEm5251 P5E_PEX1_STN0_TX_DP<12>                                           
P  NNAMEm5252 P5E_PEX1_STN6_TX_DP<101>                                          
P  NNAMEm5253 P5E_PEX1_STN5_RX_DN<87>                                           
P  NNAMEm5254 P5E_PEX1_STN1_TX_DN<30>                                           
P  NNAMEm5255 P5E_PEX1_STN6_TX_DP<102>                                          
P  NNAMEm5256 P5E_PEX1_STN7_RX_DN<112>                                          
P  NNAMEm5257 P5E_PEX1_STN1_TX_DN<31>                                           
P  NNAMEm5258 P5E_PEX1_STN6_TX_DN<98>                                           
P  NNAMEm5259 P5E_PEX1_STN5_RX_DP<84>                                           
P  NNAMEm5260 P5E_PEX1_STN1_TX_DN<21>                                           
P  NNAMEm5261 P5E_PEX1_STN7_TX_DN<113>                                          
P  NNAMEm5262 P5E_PEX1_STN5_RX_DP<80>                                           
P  NNAMEm5263 P5E_PEX1_STN7_TX_C_DP<116>                                        
P  NNAMEm5264 P5E_PEX0_STN7_TX_DP<119>                                          
P  NNAMEm5265 P5E_PEX1_STN0_TX_DP<3>                                            
P  NNAMEm5266 P5E_PEX1_STN6_TX_DN<104>                                          
P  NNAMEm5267 P5E_PEX1_STN5_RX_DN<80>                                           
P  NNAMEm5268 P5E_PEX0_STN7_TX_DN<126>                                          
P  NNAMEm5269 P5E_PEX1_STN0_TX_DP<15>                                           
P  NNAMEm5270 P5E_PEX1_STN7_TX_DP<121>                                          
P  NNAMEm5271 P5E_PEX1_STN5_RX_DP<81>                                           
P  NNAMEm5272 P5E_PEX0_STN5_TX_C_DN<80>                                         
P  NNAMEm5273 P5E_PEX1_STN5_TX_C_DP<85>                                         
P  NNAMEm5274 P5E_PEX0_STN7_TX_DP<120>                                          
P  NNAMEm5275 P5E_PEX1_STN0_TX_DP<6>                                            
P  NNAMEm5276 P5E_PEX1_STN6_TX_DN<106>                                          
P  NNAMEm5277 P5E_PEX1_STN7_RX_DP<115>                                          
P  NNAMEm5278 P5E_PEX1_STN5_TX_C_DP<86>                                         
P  NNAMEm5279 P5E_PEX0_STN1_TX_DN<24>                                           
P  NNAMEm5280 P5E_PEX0_STN7_TX_DN<120>                                          
P  NNAMEm5281 P5E_PEX1_STN0_TX_DN<3>                                            
P  NNAMEm5282 P5E_PEX1_STN6_TX_DP<100>                                          
P  NNAMEm5283 P5E_PEX1_STN5_RX_DP<85>                                           
P  NNAMEm5284 P5E_PEX0_STN5_TX_C_DP<93>                                         
P  NNAMEm5285 P5E_PEX1_STN5_TX_C_DP<87>                                         
P  NNAMEm5286 P5E_PEX0_STN0_TX_DN<1>                                            
P  NNAMEm5287 P5E_PEX0_STN7_TX_DP<121>                                          
P  NNAMEm5288 P5E_PEX1_STN0_TX_DP<7>                                            
P  NNAMEm5289 P5E_PEX1_STN6_TX_DN<108>                                          
P  NNAMEm5290 P5E_PEX1_STN7_RX_DP<114>                                          
P  NNAMEm5291 P5E_PEX1_STN5_TX_C_DN<85>                                         
P  NNAMEm5292 P5E_PEX0_STN1_TX_DP<27>                                           
P  NNAMEm5293 P5E_PEX1_STN1_TX_DP<23>                                           
P  NNAMEm5294 P5E_PEX1_STN7_RX_DP<113>                                          
P  NNAMEm5295 P5E_PEX1_STN7_TX_C_DN<118>                                        
P  NNAMEm5296 P5E_PEX0_STN0_TX_DP<9>                                            
P  NNAMEm5297 P5E_PEX1_STN0_TX_DN<7>                                            
P  NNAMEm5298 P5E_PEX1_STN7_RX_DP<117>                                          
P  NNAMEm5299 P5E_PEX0_STN1_TX_DP<30>                                           
P  NNAMEm5300 P5E_PEX0_STN7_TX_DN<124>                                          
P  NNAMEm5301 P5E_PEX1_STN0_TX_DN<0>                                            
P  NNAMEm5302 P5E_PEX1_STN7_RX_DN<118>                                          
P  NNAMEm5303 P5E_PEX0_STN5_TX_C_DP<92>                                         
P  NNAMEm5304 P5E_PEX1_STN7_TX_C_DN<119>                                        
P  NNAMEm5305 P5E_PEX0_STN1_TX_DP<25>                                           
P  NNAMEm5306 P5E_PEX0_STN7_TX_DP<127>                                          
P  NNAMEm5307 P5E_PEX1_STN1_TX_DP<18>                                           
P  NNAMEm5308 P5E_PEX1_STN7_RX_DP<112>                                          
P  NNAMEm5309 P5E_PEX0_STN1_TX_DN<31>                                           
P  NNAMEm5310 P5E_PEX1_STN1_TX_DN<23>                                           
P  NNAMEm5311 P5E_PEX1_STN5_RX_DN<83>                                           
P  NNAMEm5312 P5E_PEX0_STN5_TX_C_DP<80>                                         
P  NNAMEm5313 P5E_PEX0_STN0_TX_DN<13>                                           
P  NNAMEm5314 P5E_PEX1_STN1_TX_DP<28>                                           
P  NNAMEm5315 P5E_PEX1_STN5_RX_DP<93>                                           
P  NNAMEm5316 P5E_PEX0_STN1_TX_DP<28>                                           
P  NNAMEm5317 P5E_PEX0_STN7_TX_DP<117>                                          
P  NNAMEm5318 P5E_PEX1_STN0_TX_DN<10>                                           
P  NNAMEm5319 P5E_PEX1_STN5_RX_DN<93>                                           
P  NNAMEm5320 P5E_PEX0_STN1_TX_DP<23>                                           
P  NNAMEm5321 P5E_PEX1_STN1_TX_DP<17>                                           
P  NNAMEm5322 P5E_PEX1_STN7_RX_DN<122>                                          
P  NNAMEm5323 P5E_PEX0_STN5_TX_C_DN<81>                                         
P  NNAMEm5324 P5E_PEX0_STN0_TX_DP<1>                                            
P  NNAMEm5325 P5E_PEX0_STN7_TX_DN<113>                                          
P  NNAMEm5326 P5E_PEX1_STN1_TX_DN<27>                                           
P  NNAMEm5327 P5E_PEX1_STN7_RX_DP<123>                                          
P  NNAMEm5328 P5E_PEX0_STN5_TX_C_DN<92>                                         
P  NNAMEm5329 P5E_PEX1_STN7_TX_C_DN<117>                                        
P  NNAMEm5330 P5E_PEX0_STN0_TX_DN<7>                                            
P  NNAMEm5331 P5E_PEX0_STN7_TX_DN<115>                                          
P  NNAMEm5332 P5E_PEX1_STN1_TX_DN<19>                                           
P  NNAMEm5333 P5E_PEX1_STN7_RX_DN<120>                                          
P  NNAMEm5334 P5E_PEX1_STN5_TX_C_DN<84>                                         
P  NNAMEm5335 P5E_PEX0_STN1_TX_DN<26>                                           
P  NNAMEm5336 P5E_PEX1_STN0_TX_DP<1>                                            
P  NNAMEm5337 P5E_PEX1_STN5_RX_DP<95>                                           
P  NNAMEm5338 P5E_PEX0_STN5_TX_C_DN<94>                                         
P  NNAMEm5339 P5E_PEX0_STN1_TX_DN<28>                                           
P  NNAMEm5340 P5E_PEX0_STN7_TX_DP<114>                                          
P  NNAMEm5341 P5E_PEX1_STN1_TX_DP<25>                                           
P  NNAMEm5342 P5E_PEX1_STN7_RX_DP<124>                                          
P  NNAMEm5343 P5E_PEX0_STN5_TX_C_DP<95>                                         
P  NNAMEm5344 P5E_PEX0_STN0_TX_DP<12>                                           
P  NNAMEm5345 P5E_PEX0_STN7_TX_DP<124>                                          
P  NNAMEm5346 P5E_PEX1_STN1_TX_DN<20>                                           
P  NNAMEm5347 P5E_PEX1_STN5_RX_DN<90>                                           
P  NNAMEm5348 P5E_PEX1_STN7_TX_C_DP<119>                                        
P  NNAMEm5349 P5E_PEX0_STN0_TX_DN<11>                                           
P  NNAMEm5350 P5E_PEX0_STN7_TX_DP<113>                                          
P  NNAMEm5351 P5E_PEX1_STN1_TX_DP<22>                                           
P  NNAMEm5352 P5E_PEX1_STN5_RX_DP<92>                                           
P  NNAMEm5353 P5E_PEX1_STN7_TX_C_DP<118>                                        
P  NNAMEm5354 P5E_PEX0_STN0_TX_DN<3>                                            
P  NNAMEm5355 P5E_PEX1_STN7_RX_DN<125>                                          
P  NNAMEm5356 P5E_PEX0_STN5_TX_C_DP<94>                                         
P  NNAMEm5357 P5E_PEX1_STN5_TX_C_DN<86>                                         
P  NNAMEm5358 P5E_PEX0_STN1_TX_DN<23>                                           
P  NNAMEm5359 P5E_PEX1_STN5_RX_DN<91>                                           
P  NNAMEm5360 P5E_PEX0_STN1_TX_DP<31>                                           
P  NNAMEm5361 P5E_PEX1_STN7_RX_DN<124>                                          
P  NNAMEm5362 P5E_PEX0_STN5_TX_C_DN<95>                                         
P  NNAMEm5363 P5E_PEX0_STN1_TX_DN<29>                                           
P  NNAMEm5364 P5E_PEX1_STN7_RX_DN<123>                                          
P  NNAMEm5365 P5E_PEX0_STN1_TX_DN<22>                                           
P  NNAMEm5366 P5E_PEX1_STN5_RX_DP<90>                                           
P  NNAMEm5367 P5E_PEX0_STN5_TX_C_DN<93>                                         
P  NNAMEm5368 P5E_PEX1_STN7_TX_C_DN<116>                                        
P  NNAMEm5369 P5E_PEX0_STN0_TX_DP<10>                                           
P  NNAMEm5370 P5E_PEX0_STN7_TX_DN<117>                                          
P  NNAMEm5371 P5E_PEX1_STN5_RX_DN<94>                                           
P  NNAMEm5372 P5E_PEX0_STN5_TX_C_DP<87>                                         
P  NNAMEm5373 P5E_PEX0_STN1_TX_DN<27>                                           
P  NNAMEm5374 P5E_PEX0_STN7_TX_DN<116>                                          
P  NNAMEm5375 P5E_PEX1_STN5_RX_DP<94>                                           
P  NNAMEm5376 P5E_PEX0_STN5_TX_C_DP<81>                                         
P  NNAMEm5377 P5E_PEX0_STN0_TX_DP<6>                                            
P  NNAMEm5378 P5E_PEX0_STN7_TX_DP<126>                                          
P  NNAMEm5379 P5E_PEX1_STN7_RX_DP<127>                                          
P  NNAMEm5380 P5E_PEX0_STN5_TX_C_DN<87>                                         
P  NNAMEm5381 P5E_PEX1_STN5_TX_C_DN<87>                                         
P  NNAMEm5382 P5E_PEX0_STN1_TX_DN<18>                                           
P  NNAMEm5383 P5E_PEX1_STN7_RX_DN<126>                                          
P  NNAMEm5384 P5E_PEX1_STN7_TX_C_DP<117>                                        
P  NNAMEm5385 P5E_PEX0_STN0_TX_DP<15>                                           
P  NNAMEm5386 P5E_PEX1_STN5_RX_DN<89>                                           
P  NNAMEm5387 P5E_PEX1_STN5_TX_C_DP<84>                                         
P  NNAMEm5388 P5E_PEX0_STN1_TX_DP<26>                                           
P  NNAMEm5389 P5E_PEX0_STN7_TX_DP<112>                                          
P  NNAMEm5390 P5E_PEX1_STN5_RX_DN<88>                                           
P  NNAMEm5391 P5E_PEX0_STN0_TX_DN<4>                                            
P  NNAMEm5392 P5E_PEX1_STN7_RX_DP<126>                                          
P  NNAMEm5393 P5E_PEX0_STN0_TX_DN<8>                                            
P  NNAMEm5394 P5E_PEX1_STN5_RX_DP<89>                                           
P  NNAMEm5395 P5E_PEX0_STN1_TX_DN<30>                                           
P  NNAMEm5396 P5E_PEX1_STN7_RX_DP<125>                                          
P  NNAMEm5397 P5E_PEX0_STN1_TX_DN<17>                                           
P  NNAMEm5398 P5E_PEX0_STN7_TX_DN<118>                                          
P  NNAMEm5399 P5E_PEX1_STN5_RX_DP<88>                                           
P  NNAMEm5400 P5E_PEX0_STN0_TX_DN<12>                                           
P  NNAMEm5401 P5E_PEX0_STN7_TX_DN<119>                                          
P  NNAMEm5402 P5E_PEX1_STN7_RX_DP<122>                                          
P  NNAMEm5403 RST_SMB_NIC7_MUX_ISO_N                                            
P  NNAMEm5404 P5E_PEX0_STN1_TX_DP<21>                                           
P  NNAMEm5405 P5E_PEX0_STN7_TX_DN<121>                                          
P  NNAMEm5406 P5E_PEX1_STN7_RX_DP<121>                                          
P  NNAMEm5407 RST_SMB_NIC7_MUX_N                                                
P  NNAMEm5408 P5E_PEX0_STN0_TX_DP<13>                                           
P  NNAMEm5409 P5E_PEX0_STN7_TX_DP<115>                                          
P  NNAMEm5410 P5E_PEX1_STN5_RX_DN<95>                                           
P  NNAMEm5411 P5E_PEX0_STN1_TX_DN<21>                                           
P  NNAMEm5412 P5E_PEX1_STN7_RX_DN<121>                                          
P  NNAMEm5413 P5E_PEX0_STN0_TX_DP<5>                                            
P  NNAMEm5414 P5E_PEX1_STN5_RX_DN<92>                                           
P  NNAMEm5415 P5E_PEX0_STN0_TX_DP<2>                                            
P  NNAMEm5416 P5E_PEX0_STN7_TX_DN<114>                                          
P  NNAMEm5417 P5E_PEX1_STN7_RX_DN<127>                                          
P  NNAMEm5418 P5E_PEX0_STN0_TX_DN<5>                                            
P  NNAMEm5419 P5E_PEX1_STN7_RX_DP<120>                                          
P  NNAMEm5420 P5E_PEX0_STN1_TX_DP<19>                                           
P  NNAMEm5421 P5E_PEX1_STN5_RX_DP<91>                                           
P  NNAMEm5422 RST_SMB_NIC1_MUX_ISO_N                                            
P  NNAMEm5423 P5E_PEX0_STN0_TX_DP<7>                                            
P  NNAMEm5424 P5E_PEX0_STN7_RX_DN<112>                                          
P  NNAMEm5425 RST_SMB_NIC1_MUX_N                                                
P  NNAMEm5426 P5E_PEX0_STN1_TX_DN<20>                                           
P  NNAMEm5427 P5E_PEX0_STN7_TX_DP<118>                                          
P  NNAMEm5428 P5E_PEX0_STN7_RX_DN<118>                                          
P  NNAMEm5429 RST_SMB_NIC4_MUX_ISO_N                                            
P  NNAMEm5430 P5E_PEX0_STN0_TX_DP<11>                                           
P  NNAMEm5431 P5E_PEX0_STN7_TX_DN<112>                                          
P  NNAMEm5432 P5E_PEX0_STN7_RX_DP<117>                                          
P  NNAMEm5433 RST_SMB_NIC4_MUX_N                                                
P  NNAMEm5434 P5E_PEX0_STN0_TX_DN<6>                                            
P  NNAMEm5435 P5E_PEX0_STN7_TX_DN<125>                                          
P  NNAMEm5436 P5E_PEX0_STN7_RX_DP<118>                                          
P  NNAMEm5437 HP_NIC2_HSC_PWRGD_N                                               
P  NNAMEm5438 P5E_PEX0_STN0_TX_DP<14>                                           
P  NNAMEm5439 P5E_PEX0_STN5_RX_DP<86>                                           
P  NNAMEm5440 RST_HP_NIC2_BUF_N                                                 
P  NNAMEm5441 P5E_PEX0_STN1_TX_DP<22>                                           
P  NNAMEm5442 P5E_PEX0_STN5_RX_DN<83>                                           
P  NNAMEm5443 RST_HP_NIC5_BUF_N                                                 
P  NNAMEm5444 P5E_PEX0_STN0_TX_DN<9>                                            
P  NNAMEm5445 P5E_PEX0_STN5_RX_DN<80>                                           
P  NNAMEm5446 HP_NIC5_HSC_PWRGD_N                                               
P  NNAMEm5447 P5E_PEX0_STN0_TX_DN<15>                                           
P  NNAMEm5448 P5E_PEX0_STN7_RX_DN<114>                                          
P  NNAMEm5449 P5E_PEX0_STN1_TX_DP<20>                                           
P  NNAMEm5450 P5E_PEX0_STN5_RX_DP<82>                                           
P  NNAMEm5451 P5E_PEX0_STN1_TX_DP<17>                                           
P  NNAMEm5452 P5E_PEX0_STN5_RX_DN<81>                                           
P  NNAMEm5453 P5E_PEX0_STN1_TX_DP<29>                                           
P  NNAMEm5454 P5E_PEX0_STN7_RX_DN<117>                                          
P  NNAMEm5455 P5E_PEX0_STN0_TX_DP<0>                                            
P  NNAMEm5456 P5E_PEX0_STN7_RX_DP<115>                                          
P  NNAMEm5457 P5E_PEX0_STN0_TX_DP<3>                                            
P  NNAMEm5458 P5E_PEX0_STN5_RX_DN<85>                                           
P  NNAMEm5459 P5E_PEX0_STN7_TX_C_DN<116>                                        
P  NNAMEm5460 P5E_PEX0_STN1_TX_DP<16>                                           
P  NNAMEm5461 P5E_PEX0_STN7_RX_DP<113>                                          
P  NNAMEm5462 P5E_PEX0_STN7_TX_C_DN<117>                                        
P  NNAMEm5463 P5E_PEX0_STN1_TX_DP<18>                                           
P  NNAMEm5464 P5E_PEX0_STN7_RX_DN<116>                                          
P  NNAMEm5465 P5E_PEX0_STN0_TX_DN<14>                                           
P  NNAMEm5466 P5E_PEX0_STN7_RX_DN<113>                                          
P  NNAMEm5467 P5E_PEX0_STN7_TX_C_DP<117>                                        
P  NNAMEm5468 P5E_PEX0_STN0_TX_DN<0>                                            
P  NNAMEm5469 P5E_PEX0_STN7_RX_DP<112>                                          
P  NNAMEm5470 P5E_PEX0_STN1_TX_DN<19>                                           
P  NNAMEm5471 P5E_PEX0_STN5_RX_DN<87>                                           
P  NNAMEm5472 P5E_PEX0_STN7_TX_C_DN<118>                                        
P  NNAMEm5473 P5E_PEX1_STN5_TX_C_DP<83>                                         
P  NNAMEm5474 P5E_PEX0_STN1_TX_DN<16>                                           
P  NNAMEm5475 P5E_PEX0_STN5_RX_DN<86>                                           
P  NNAMEm5476 P5E_PEX1_STN5_TX_C_DP<80>                                         
P  NNAMEm5477 P5E_PEX0_STN1_TX_DN<25>                                           
P  NNAMEm5478 P5E_PEX0_STN5_RX_DP<87>                                           
P  NNAMEm5479 P5E_PEX0_STN0_TX_DP<8>                                            
P  NNAMEm5480 P5E_PEX0_STN5_RX_DN<84>                                           
P  NNAMEm5481 P5E_PEX0_STN7_TX_C_DP<118>                                        
P  NNAMEm5482 P5E_PEX0_STN5_TX_C_DP<85>                                         
P  NNAMEm5483 P5E_PEX0_STN0_TX_DN<10>                                           
P  NNAMEm5484 P5E_PEX0_STN7_RX_DN<115>                                          
P  NNAMEm5485 P5E_PEX0_STN0_TX_DN<2>                                            
P  NNAMEm5486 P5E_PEX0_STN5_RX_DP<81>                                           
P  NNAMEm5487 P5E_PEX0_STN6_TX_DP<106>                                          
P  NNAMEm5488 P5E_PEX0_STN7_TX_C_DP<116>                                        
P  NNAMEm5489 P5E_PEX1_STN7_TX_C_DP<114>                                        
P  NNAMEm5490 P5E_PEX0_STN0_TX_DP<4>                                            
P  NNAMEm5491 P5E_PEX0_STN5_RX_DP<83>                                           
P  NNAMEm5492 P5E_PEX0_STN6_TX_DN<96>                                           
P  NNAMEm5493 P5E_PEX1_STN7_TX_C_DP<115>                                        
P  NNAMEm5494 P5E_PEX0_STN5_TX_C_DN<86>                                         
P  NNAMEm5495 P5E_PEX0_STN1_TX_DP<24>                                           
P  NNAMEm5496 P5E_PEX0_STN5_RX_DP<80>                                           
P  NNAMEm5497 P5E_PEX0_STN5_TX_C_DN<85>                                         
P  NNAMEm5498 P5E_PEX3_STN2_TX_DN<47>                                           
P  NNAMEm5499 P5E_PEX0_STN7_RX_DP<114>                                          
P  NNAMEm5500 P5E_PEX0_STN6_TX_DP<105>                                          
P  NNAMEm5501 P5E_PEX0_STN5_RX_DN<88>                                           
P  NNAMEm5502 P5E_PEX0_STN5_TX_C_DP<84>                                         
P  NNAMEm5503 P5E_PEX3_STN2_TX_DP<47>                                           
P  NNAMEm5504 P5E_PEX0_STN5_RX_DP<85>                                           
P  NNAMEm5505 P5E_PEX2_STN5_TX_C_DP<92>                                         
P  NNAMEm5506 P5E_PEX0_STN6_TX_DN<102>                                          
P  NNAMEm5507 P5E_PEX3_STN2_TX_DN<42>                                           
P  NNAMEm5508 P5E_PEX0_STN5_RX_DP<84>                                           
P  NNAMEm5509 P5E_PEX0_STN5_RX_DP<88>                                           
P  NNAMEm5510 P5E_PEX3_STN2_TX_DP<38>                                           
P  NNAMEm5511 P5E_PEX0_STN5_RX_DN<82>                                           
P  NNAMEm5512 P5E_PEX0_STN6_TX_DN<99>                                           
P  NNAMEm5513 P5E_PEX0_STN7_RX_DP<120>                                          
P  NNAMEm5514 P5E_PEX0_STN5_TX_C_DP<86>                                         
P  NNAMEm5515 P5E_PEX3_STN5_TX_DN<80>                                           
P  NNAMEm5516 P5E_PEX0_STN7_RX_DN<119>                                          
P  NNAMEm5517 P5E_PEX2_STN5_TX_C_DN<89>                                         
P  NNAMEm5518 P5E_PEX3_STN5_TX_DP<83>                                           
P  NNAMEm5519 P5E_PEX0_STN7_RX_DP<119>                                          
P  NNAMEm5520 P5E_PEX2_STN7_TX_C_DN<120>                                        
P  NNAMEm5521 P5E_PEX0_STN5_TX_C_DN<84>                                         
P  NNAMEm5522 P5E_PEX3_STN2_TX_DP<40>                                           
P  NNAMEm5523 P5E_PEX0_STN7_RX_DP<116>                                          
P  NNAMEm5524 P5E_PEX1_STN7_TX_C_DN<112>                                        
P  NNAMEm5525 P5E_PEX3_STN2_TX_DP<45>                                           
P  NNAMEm5526 P5E_PEX2_STN5_TX_C_DN<95>                                         
P  NNAMEm5527 P5E_PEX0_STN6_TX_DN<103>                                          
P  NNAMEm5528 P5E_PEX3_STN2_TX_DN<40>                                           
P  NNAMEm5529 P5E_PEX1_STN5_TX_C_DN<83>                                         
P  NNAMEm5530 P5E_PEX3_STN5_TX_DN<90>                                           
P  NNAMEm5531 P5E_PEX2_STN5_TX_C_DN<91>                                         
P  NNAMEm5532 P5E_PEX0_STN6_TX_DN<97>                                           
P  NNAMEm5533 P5E_PEX1_STN7_TX_C_DN<113>                                        
P  NNAMEm5534 P5E_PEX3_STN5_TX_DP<93>                                           
P  NNAMEm5535 P5E_PEX3_STN5_TX_DP<92>                                           
P  NNAMEm5536 P5E_PEX2_STN5_TX_C_DP<91>                                         
P  NNAMEm5537 P5E_PEX1_STN7_TX_C_DN<115>                                        
P  NNAMEm5538 P5E_PEX3_STN5_TX_DN<93>                                           
P  NNAMEm5539 P5E_PEX2_STN7_TX_C_DP<123>                                        
P  NNAMEm5540 P5E_PEX3_STN5_TX_DP<89>                                           
P  NNAMEm5541 P5E_PEX3_STN5_TX_DN<86>                                           
P  NNAMEm5542 P5E_PEX2_STN5_TX_C_DN<88>                                         
P  NNAMEm5543 P5E_PEX0_STN6_TX_DP<101>                                          
P  NNAMEm5544 P5E_PEX3_STN5_TX_DN<91>                                           
P  NNAMEm5545 P5E_PEX0_STN6_TX_DP<96>                                           
P  NNAMEm5546 P5E_PEX3_STN2_TX_DN<41>                                           
P  NNAMEm5547 P5E_PEX3_STN2_TX_DP<32>                                           
P  NNAMEm5548 P5E_PEX2_STN7_TX_C_DN<127>                                        
P  NNAMEm5549 P5E_PEX3_STN2_TX_DN<36>                                           
P  NNAMEm5550 P5E_PEX0_STN6_TX_DN<110>                                          
P  NNAMEm5551 P5E_PEX3_STN5_TX_DP<88>                                           
P  NNAMEm5552 P5E_PEX2_STN5_TX_C_DP<94>                                         
P  NNAMEm5553 P5E_PEX3_STN2_TX_DN<45>                                           
P  NNAMEm5554 P5E_PEX2_STN5_TX_C_DP<90>                                         
P  NNAMEm5555 P5E_PEX0_STN6_TX_DN<107>                                          
P  NNAMEm5556 P5E_PEX3_STN2_TX_DN<35>                                           
P  NNAMEm5557 P5E_PEX2_STN7_TX_C_DN<125>                                        
P  NNAMEm5558 P5E_PEX0_STN5_TX_C_DN<83>                                         
P  NNAMEm5559 P5E_PEX3_STN2_TX_DP<46>                                           
P  NNAMEm5560 P5E_PEX0_STN7_TX_C_DP<115>                                        
P  NNAMEm5561 P5E_PEX1_STN7_TX_C_DN<114>                                        
P  NNAMEm5562 P5E_PEX3_STN2_TX_DN<46>                                           
P  NNAMEm5563 P5E_PEX0_STN5_RX_DN<93>                                           
P  NNAMEm5564 P5E_PEX2_STN5_TX_C_DP<88>                                         
P  NNAMEm5565 P5E_PEX3_STN2_TX_DN<33>                                           
P  NNAMEm5566 P5E_PEX0_STN7_RX_DP<127>                                          
P  NNAMEm5567 P5E_PEX2_STN5_TX_C_DP<93>                                         
P  NNAMEm5568 P5E_PEX3_STN2_TX_DN<38>                                           
P  NNAMEm5569 P5E_PEX0_STN7_RX_DN<126>                                          
P  NNAMEm5570 P5E_PEX0_STN6_TX_DP<97>                                           
P  NNAMEm5571 P5E_PEX3_STN5_TX_DN<95>                                           
P  NNAMEm5572 P5E_PEX0_STN7_RX_DP<125>                                          
P  NNAMEm5573 P5E_PEX0_STN6_TX_DP<99>                                           
P  NNAMEm5574 P5E_PEX0_STN5_TX_C_DP<83>                                         
P  NNAMEm5575 P5E_PEX1_STN5_TX_C_DN<80>                                         
P  NNAMEm5576 P5E_PEX3_STN2_TX_DP<36>                                           
P  NNAMEm5577 P5E_PEX0_STN5_RX_DP<95>                                           
P  NNAMEm5578 P5E_PEX0_STN6_TX_DN<100>                                          
P  NNAMEm5579 P5E_PEX3_STN2_TX_DN<39>                                           
P  NNAMEm5580 P5E_PEX0_STN7_RX_DP<126>                                          
P  NNAMEm5581 P5E_PEX0_STN6_TX_DN<106>                                          
P  NNAMEm5582 P5E_PEX3_STN5_TX_DP<94>                                           
P  NNAMEm5583 P5E_PEX0_STN7_RX_DN<124>                                          
P  NNAMEm5584 P5E_PEX2_STN5_TX_C_DN<94>                                         
P  NNAMEm5585 P5E_PEX3_STN5_TX_DP<91>                                           
P  NNAMEm5586 P5E_PEX0_STN5_RX_DN<94>                                           
P  NNAMEm5587 P5E_PEX2_STN7_TX_C_DP<126>                                        
P  NNAMEm5588 P5E_PEX3_STN5_TX_DN<89>                                           
P  NNAMEm5589 P5E_PEX0_STN7_RX_DP<124>                                          
P  NNAMEm5590 P5E_PEX0_STN6_TX_DP<109>                                          
P  NNAMEm5591 P5E_PEX3_STN5_TX_DP<82>                                           
P  NNAMEm5592 P5E_PEX0_STN7_RX_DN<125>                                          
P  NNAMEm5593 P5E_PEX0_STN6_TX_DP<104>                                          
P  NNAMEm5594 P5E_PEX3_STN2_TX_DP<33>                                           
P  NNAMEm5595 P5E_PEX0_STN7_RX_DN<127>                                          
P  NNAMEm5596 P5E_PEX0_STN6_TX_DN<111>                                          
P  NNAMEm5597 P5E_PEX3_STN5_TX_DP<85>                                           
P  NNAMEm5598 P5E_PEX0_STN5_RX_DP<93>                                           
P  NNAMEm5599 P5E_PEX2_STN2_TX_DN<34>                                           
P  NNAMEm5600 P5E_PEX3_STN5_TX_DP<95>                                           
P  NNAMEm5601 P5E_PEX0_STN5_RX_DP<94>                                           
P  NNAMEm5602 P5E_PEX2_STN7_TX_C_DP<124>                                        
P  NNAMEm5603 P5E_PEX2_STN5_TX_DN<94>                                           
P  NNAMEm5604 P5E_PEX3_STN2_TX_DP<37>                                           
P  NNAMEm5605 P5E_PEX0_STN5_RX_DN<92>                                           
P  NNAMEm5606 P5E_PEX2_STN7_TX_C_DN<126>                                        
P  NNAMEm5607 P5E_PEX0_STN6_TX_DN<98>                                           
P  NNAMEm5608 P5E_PEX1_STN7_TX_C_DP<113>                                        
P  NNAMEm5609 P5E_PEX2_STN5_TX_DN<83>                                           
P  NNAMEm5610 P5E_PEX3_STN2_TX_DN<34>                                           
P  NNAMEm5611 P5E_PEX0_STN5_RX_DN<95>                                           
P  NNAMEm5612 P5E_PEX2_STN7_TX_C_DP<122>                                        
P  NNAMEm5613 P5E_PEX0_STN6_TX_DN<105>                                          
P  NNAMEm5614 P5E_PEX2_STN5_TX_DP<93>                                           
P  NNAMEm5615 P5E_PEX3_STN5_TX_DP<90>                                           
P  NNAMEm5616 P5E_PEX0_STN5_RX_DP<92>                                           
P  NNAMEm5617 P5E_PEX0_STN6_TX_DN<101>                                          
P  NNAMEm5618 P5E_PEX2_STN2_TX_DN<39>                                           
P  NNAMEm5619 P5E_PEX3_STN2_TX_DP<43>                                           
P  NNAMEm5620 P5E_PEX0_STN7_TX_C_DN<121>                                        
P  NNAMEm5621 P5E_PEX2_STN5_TX_DP<92>                                           
P  NNAMEm5622 P5E_PEX3_STN2_TX_DP<41>                                           
P  NNAMEm5623 P5E_PEX0_STN7_TX_C_DP<120>                                        
P  NNAMEm5624 P5E_PEX2_STN2_TX_DP<38>                                           
P  NNAMEm5625 P5E_PEX3_STN2_TX_DN<37>                                           
P  NNAMEm5626 P5E_PEX0_STN5_TX_C_DP<90>                                         
P  NNAMEm5627 P5E_PEX2_STN7_TX_C_DP<127>                                        
P  NNAMEm5628 P5E_PEX1_STN7_TX_C_DP<112>                                        
P  NNAMEm5629 P5E_PEX2_STN2_TX_DP<37>                                           
P  NNAMEm5630 P5E_PEX3_STN5_TX_DN<92>                                           
P  NNAMEm5631 P5E_PEX0_STN5_TX_C_DP<91>                                         
P  NNAMEm5632 P5E_PEX0_STN6_TX_DP<110>                                          
P  NNAMEm5633 P5E_PEX2_STN5_TX_DN<95>                                           
P  NNAMEm5634 P5E_PEX3_STN5_TX_DN<94>                                           
P  NNAMEm5635 P5E_PEX0_STN5_TX_C_DN<91>                                         
P  NNAMEm5636 P5E_PEX0_STN6_TX_DP<100>                                          
P  NNAMEm5637 P5E_PEX2_STN5_TX_DN<85>                                           
P  NNAMEm5638 P5E_PEX3_STN5_TX_DP<80>                                           
P  NNAMEm5639 P5E_PEX0_STN5_TX_C_DN<88>                                         
P  NNAMEm5640 P5E_PEX0_STN6_TX_DP<108>                                          
P  NNAMEm5641 P5E_PEX2_STN5_TX_DP<83>                                           
P  NNAMEm5642 P5E_PEX3_STN5_TX_DP<81>                                           
P  NNAMEm5643 P5E_PEX0_STN7_TX_C_DP<123>                                        
P  NNAMEm5644 P5E_PEX2_STN7_TX_C_DP<121>                                        
P  NNAMEm5645 P5E_PEX0_STN6_TX_DP<103>                                          
P  NNAMEm5646 P5E_PEX2_STN2_TX_DP<33>                                           
P  NNAMEm5647 P5E_PEX3_STN2_TX_DP<39>                                           
P  NNAMEm5648 P5E_PEX0_STN5_TX_C_DP<89>                                         
P  NNAMEm5649 P5E_PEX2_STN7_TX_C_DP<120>                                        
P  NNAMEm5650 P5E_PEX0_STN6_TX_DP<98>                                           
P  NNAMEm5651 P5E_PEX2_STN2_TX_DP<42>                                           
P  NNAMEm5652 P5E_PEX3_STN5_TX_DN<82>                                           
P  NNAMEm5653 P5E_PEX0_STN5_TX_C_DP<88>                                         
P  NNAMEm5654 P5E_PEX0_STN6_TX_DP<107>                                          
P  NNAMEm5655 P5E_PEX2_STN2_TX_DN<47>                                           
P  NNAMEm5656 P5E_PEX3_STN2_TX_DP<44>                                           
P  NNAMEm5657 P5E_PEX0_STN7_TX_C_DN<122>                                        
P  NNAMEm5658 P5E_PEX0_STN6_TX_DP<102>                                          
P  NNAMEm5659 P5E_PEX2_STN5_TX_DP<88>                                           
P  NNAMEm5660 P5E_PEX3_STN5_TX_DN<83>                                           
P  NNAMEm5661 P5E_PEX0_STN7_TX_C_DN<123>                                        
P  NNAMEm5662 P5E_PEX2_STN5_TX_DN<92>                                           
P  NNAMEm5663 P5E_PEX3_STN5_TX_DN<85>                                           
P  NNAMEm5664 P5E_PEX0_STN7_TX_C_DN<120>                                        
P  NNAMEm5665 P5E_PEX2_STN7_TX_C_DP<125>                                        
P  NNAMEm5666 P5E_PEX0_STN5_TX_DP<91>                                           
P  NNAMEm5667 P5E_PEX2_STN2_TX_DN<32>                                           
P  NNAMEm5668 P5E_PEX3_STN2_TX_DP<35>                                           
P  NNAMEm5669 P5E_PEX0_STN5_TX_C_DN<89>                                         
P  NNAMEm5670 P5E_PEX0_STN6_TX_DN<104>                                          
P  NNAMEm5671 P5E_PEX0_STN5_TX_DN<92>                                           
P  NNAMEm5672 P5E_PEX2_STN5_TX_DP<80>                                           
P  NNAMEm5673 P5E_PEX3_STN2_TX_DN<43>                                           
P  NNAMEm5674 P5E_PEX0_STN7_TX_C_DP<122>                                        
P  NNAMEm5675 P5E_PEX2_STN5_TX_C_DN<90>                                         
P  NNAMEm5676 P5E_PEX0_STN2_TX_DN<45>                                           
P  NNAMEm5677 P5E_PEX2_STN5_TX_DN<93>                                           
P  NNAMEm5678 P5E_PEX3_STN2_TX_DP<42>                                           
P  NNAMEm5679 P5E_PEX0_STN5_TX_C_DN<90>                                         
P  NNAMEm5680 P5E_PEX2_STN5_TX_C_DN<93>                                         
P  NNAMEm5681 P5E_PEX0_STN6_TX_DN<108>                                          
P  NNAMEm5682 P5E_PEX0_STN5_TX_DP<84>                                           
P  NNAMEm5683 P5E_PEX2_STN2_TX_DN<46>                                           
P  NNAMEm5684 P5E_PEX3_STN2_TX_DP<34>                                           
P  NNAMEm5685 P5E_PEX0_STN7_TX_C_DP<121>                                        
P  NNAMEm5686 P5E_PEX0_STN2_TX_DP<41>                                           
P  NNAMEm5687 P5E_PEX2_STN2_TX_DN<45>                                           
P  NNAMEm5688 P5E_PEX3_STN5_TX_DN<81>                                           
P  NNAMEm5689 P5E_PEX3_STN7_TX_DN<112>                                          
P  NNAMEm5690 P5E_PEX2_STN5_TX_C_DP<89>                                         
P  NNAMEm5691 P5E_PEX0_STN2_TX_DP<44>                                           
P  NNAMEm5692 P5E_PEX2_STN5_TX_DN<82>                                           
P  NNAMEm5693 P5E_PEX3_STN5_TX_DP<87>                                           
P  NNAMEm5694 P5E_PEX3_STN6_TX_DN<106>                                          
P  NNAMEm5695 P5E_PEX2_STN7_TX_C_DN<122>                                        
P  NNAMEm5696 P5E_PEX0_STN5_TX_DP<94>                                           
P  NNAMEm5697 P5E_PEX2_STN2_TX_DN<44>                                           
P  NNAMEm5698 P5E_PEX3_STN5_TX_DP<84>                                           
P  NNAMEm5699 P5E_PEX3_STN7_TX_DN<118>                                          
P  NNAMEm5700 P5E_PEX0_STN6_TX_DP<111>                                          
P  NNAMEm5701 RST_SMB_NIC2_MUX_ISO_N                                            
P  NNAMEm5702 P5E_PEX0_STN5_TX_DP<81>                                           
P  NNAMEm5703 P5E_PEX2_STN2_TX_DP<34>                                           
P  NNAMEm5704 P5E_PEX3_STN2_TX_DN<32>                                           
P  NNAMEm5705 P5E_PEX3_STN6_TX_DN<107>                                          
P  NNAMEm5706 P5E_PEX2_STN5_TX_C_DP<95>                                         
P  NNAMEm5707 RST_SMB_NIC2_MUX_N                                                
P  NNAMEm5708 P5E_PEX0_STN2_TX_DP<34>                                           
P  NNAMEm5709 P5E_PEX2_STN2_TX_DP<35>                                           
P  NNAMEm5710 P5E_PEX3_STN5_TX_DN<87>                                           
P  NNAMEm5711 P5E_PEX3_STN7_TX_DP<119>                                          
P  NNAMEm5712 P5E_PEX0_STN5_RX_DP<91>                                           
P  NNAMEm5713 P5E_PEX2_STN7_TX_C_DN<124>                                        
P  NNAMEm5714 P5E_PEX0_STN6_TX_DN<109>                                          
P  NNAMEm5715 RST_SMB_NIC5_MUX_ISO_N                                            
P  NNAMEm5716 P5E_PEX0_STN2_TX_DP<43>                                           
P  NNAMEm5717 P5E_PEX2_STN2_TX_DN<36>                                           
P  NNAMEm5718 P5E_PEX3_STN5_TX_DP<86>                                           
P  NNAMEm5719 P5E_PEX3_STN7_TX_DN<115>                                          
P  NNAMEm5720 P5E_PEX0_STN7_RX_DN<123>                                          
P  NNAMEm5721 P5E_PEX0_STN5_TX_C_DP<82>                                         
P  NNAMEm5722 RST_SMB_NIC5_MUX_N                                                
P  NNAMEm5723 HP_NIC3_HSC_PWRGD_N                                               
P  NNAMEm5724 P5E_PEX0_STN5_TX_DN<87>                                           
P  NNAMEm5725 P5E_PEX2_STN5_TX_DP<87>                                           
P  NNAMEm5726 P5E_PEX3_STN5_TX_DN<84>                                           
P  NNAMEm5727 P5E_PEX3_STN6_TX_DN<110>                                          
P  NNAMEm5728 P5E_PEX0_STN5_RX_DN<91>                                           
P  NNAMEm5729 P5E_PEX2_STN5_TX_C_DN<92>                                         
P  NNAMEm5730 P5E_PEX0_STN5_TX_C_DN<82>                                         
P  NNAMEm5731 P5E_PEX0_STN5_TX_DP<95>                                           
P  NNAMEm5732 P5E_PEX2_STN2_TX_DP<41>                                           
P  NNAMEm5733 P5E_PEX3_STN5_TX_DN<88>                                           
P  NNAMEm5734 P5E_PEX3_STN6_TX_DP<109>                                          
P  NNAMEm5735 P5E_PEX0_STN7_RX_DP<123>                                          
P  NNAMEm5736 HP_NIC0_HSC_PWRGD_N                                               
P  NNAMEm5737 RST_HP_NIC3_BUF_N                                                 
P  NNAMEm5738 P5E_PEX0_STN5_TX_DN<93>                                           
P  NNAMEm5739 P5E_PEX2_STN5_TX_DP<81>                                           
P  NNAMEm5740 P5E_PEX3_STN2_TX_DN<44>                                           
P  NNAMEm5741 P5E_PEX3_STN7_TX_DN<121>                                          
P  NNAMEm5742 P5E_PEX2_STN7_TX_C_DN<121>                                        
P  NNAMEm5743 RST_HP_NIC0_BUF_N                                                 
P  NNAMEm5744 P5E_PEX0_STN5_TX_DP<87>                                           
P  NNAMEm5745 P5E_PEX2_STN2_TX_DN<43>                                           
P  NNAMEm5746 P5E_PEX3_STN7_TX_DN<126>                                          
P  NNAMEm5747 P5E_PEX2_STN7_TX_C_DN<123>                                        
P  NNAMEm5748 P5E_PEX0_STN5_TX_DN<84>                                           
P  NNAMEm5749 P5E_PEX2_STN5_TX_DN<81>                                           
P  NNAMEm5750 P5E_PEX3_STN6_TX_DN<111>                                          
P  NNAMEm5751 HP_NIC6_HSC_PWRGD_N                                               
P  NNAMEm5752 P5E_PEX0_STN5_TX_DP<93>                                           
P  NNAMEm5753 P5E_PEX2_STN2_TX_DP<44>                                           
P  NNAMEm5754 P5E_PEX3_STN6_TX_DN<102>                                          
P  NNAMEm5755 RST_HP_NIC6_BUF_N                                                 
P  NNAMEm5756 P5E_PEX0_STN2_TX_DP<37>                                           
P  NNAMEm5757 P5E_PEX2_STN2_TX_DP<45>                                           
P  NNAMEm5758 P5E_PEX3_STN7_TX_DN<122>                                          
P  NNAMEm5759 P5E_PEX0_STN7_RX_DN<122>                                          
P  NNAMEm5760 P5E_PEX0_STN5_TX_DP<85>                                           
P  NNAMEm5761 P5E_PEX2_STN5_TX_DP<90>                                           
P  NNAMEm5762 P5E_PEX3_STN7_TX_DN<117>                                          
P  NNAMEm5763 P5E_PEX0_STN5_RX_DN<90>                                           
P  NNAMEm5764 P5E_PEX0_STN5_TX_DN<91>                                           
P  NNAMEm5765 P5E_PEX2_STN5_TX_DN<84>                                           
P  NNAMEm5766 P5E_PEX3_STN0_TX_DP<14>                                           
P  NNAMEm5767 P5E_PEX3_STN7_TX_DP<125>                                          
P  NNAMEm5768 P5E_PEX0_STN5_RX_DP<90>                                           
P  NNAMEm5769 P5E_PEX0_STN7_TX_C_DP<124>                                        
P  NNAMEm5770 P5E_PEX0_STN5_TX_DP<83>                                           
P  NNAMEm5771 P5E_PEX1_STN5_TX_DP<93>                                           
P  NNAMEm5772 P5E_PEX2_STN2_TX_DN<35>                                           
P  NNAMEm5773 P5E_PEX3_STN0_TX_DP<13>                                           
P  NNAMEm5774 P5E_PEX3_STN6_TX_DN<97>                                           
P  NNAMEm5775 P5E_PEX0_STN7_RX_DP<122>                                          
P  NNAMEm5776 P5E_PEX0_STN7_TX_C_DP<126>                                        
P  NNAMEm5777 P5E_PEX0_STN5_TX_DP<92>                                           
P  NNAMEm5778 P5E_PEX1_STN5_TX_DN<92>                                           
P  NNAMEm5779 P5E_PEX2_STN2_TX_DP<36>                                           
P  NNAMEm5780 P5E_PEX3_STN0_TX_DN<12>                                           
P  NNAMEm5781 P5E_PEX3_STN7_TX_DN<114>                                          
P  NNAMEm5782 P5E_PEX0_STN7_TX_C_DN<127>                                        
P  NNAMEm5783 P5E_PEX0_STN5_TX_DP<80>                                           
P  NNAMEm5784 P5E_PEX1_STN2_TX_DN<35>                                           
P  NNAMEm5785 P5E_PEX2_STN2_TX_DN<41>                                           
P  NNAMEm5786 P5E_PEX3_STN0_TX_DP<1>                                            
P  NNAMEm5787 P5E_PEX3_STN6_TX_DN<108>                                          
P  NNAMEm5788 P5E_PEX0_STN7_TX_C_DN<126>                                        
P  NNAMEm5789 P5E_PEX0_STN2_TX_DN<47>                                           
P  NNAMEm5790 P5E_PEX1_STN2_TX_DN<37>                                           
P  NNAMEm5791 P5E_PEX2_STN5_TX_DP<94>                                           
P  NNAMEm5792 P5E_PEX3_STN0_TX_DN<10>                                           
P  NNAMEm5793 P5E_PEX3_STN7_TX_DP<116>                                          
P  NNAMEm5794 P5E_PEX0_STN7_TX_C_DP<125>                                        
P  NNAMEm5795 P5E_PEX0_STN2_TX_DN<34>                                           
P  NNAMEm5796 P5E_PEX1_STN2_TX_DN<33>                                           
P  NNAMEm5797 P5E_PEX2_STN2_TX_DP<43>                                           
P  NNAMEm5798 P5E_PEX3_STN1_TX_DN<24>                                           
P  NNAMEm5799 P5E_PEX3_STN6_TX_DN<109>                                          
P  NNAMEm5800 P5E_PEX0_STN7_TX_C_DP<127>                                        
P  NNAMEm5801 P5E_PEX0_STN2_TX_DP<35>                                           
P  NNAMEm5802 P5E_PEX1_STN2_TX_DN<41>                                           
P  NNAMEm5803 P5E_PEX2_STN2_TX_DN<33>                                           
P  NNAMEm5804 P5E_PEX3_STN0_TX_DN<14>                                           
P  NNAMEm5805 P5E_PEX3_STN6_TX_DP<105>                                          
P  NNAMEm5806 P5E_PEX0_STN5_RX_DP<89>                                           
P  NNAMEm5807 P5E_PEX0_STN7_TX_C_DN<124>                                        
P  NNAMEm5808 P5E_PEX0_STN2_TX_DN<33>                                           
P  NNAMEm5809 P5E_PEX1_STN5_TX_DN<84>                                           
P  NNAMEm5810 P5E_PEX2_STN2_TX_DN<40>                                           
P  NNAMEm5811 P5E_PEX3_STN0_TX_DN<8>                                            
P  NNAMEm5812 P5E_PEX3_STN7_TX_DN<124>                                          
P  NNAMEm5813 P5E_PEX0_STN7_RX_DP<121>                                          
P  NNAMEm5814 P5E_PEX0_STN7_TX_C_DN<125>                                        
P  NNAMEm5815 P5E_PEX0_STN5_TX_DN<83>                                           
P  NNAMEm5816 P5E_PEX1_STN5_TX_DN<95>                                           
P  NNAMEm5817 P5E_PEX2_STN5_TX_DP<89>                                           
P  NNAMEm5818 P5E_PEX3_STN1_TX_DP<27>                                           
P  NNAMEm5819 P5E_PEX3_STN6_TX_DP<100>                                          
P  NNAMEm5820 P5E_PEX0_STN5_RX_DN<89>                                           
P  NNAMEm5821 P5E_PEX0_STN5_TX_DN<86>                                           
P  NNAMEm5822 P5E_PEX1_STN2_TX_DP<32>                                           
P  NNAMEm5823 P5E_PEX2_STN5_TX_DN<88>                                           
P  NNAMEm5824 P5E_PEX3_STN1_TX_DN<31>                                           
P  NNAMEm5825 P5E_PEX3_STN6_TX_DP<108>                                          
P  NNAMEm5826 P5E_PEX0_STN7_RX_DN<121>                                          
P  NNAMEm5827 P5E_PEX0_STN5_TX_DP<88>                                           
P  NNAMEm5828 P5E_PEX1_STN5_TX_DP<83>                                           
P  NNAMEm5829 P5E_PEX2_STN5_TX_DP<91>                                           
P  NNAMEm5830 P5E_PEX3_STN0_TX_DN<6>                                            
P  NNAMEm5831 P5E_PEX3_STN7_TX_DN<127>                                          
P  NNAMEm5832 P5E_PEX0_STN5_TX_DN<80>                                           
P  NNAMEm5833 P5E_PEX1_STN5_TX_DN<86>                                           
P  NNAMEm5834 P5E_PEX2_STN5_TX_DP<86>                                           
P  NNAMEm5835 P5E_PEX3_STN1_TX_DN<22>                                           
P  NNAMEm5836 P5E_PEX3_STN7_TX_DP<126>                                          
P  NNAMEm5837 P5E_PEX0_STN2_TX_DN<32>                                           
P  NNAMEm5838 P5E_PEX1_STN2_TX_DP<42>                                           
P  NNAMEm5839 P5E_PEX2_STN2_TX_DP<39>                                           
P  NNAMEm5840 P5E_PEX3_STN0_TX_DN<4>                                            
P  NNAMEm5841 P5E_PEX3_STN6_TX_DN<104>                                          
P  NNAMEm5842 P5E_PEX0_STN2_TX_DN<41>                                           
P  NNAMEm5843 P5E_PEX1_STN2_TX_DP<47>                                           
P  NNAMEm5844 P5E_PEX2_STN2_TX_DP<47>                                           
P  NNAMEm5845 P5E_PEX3_STN1_TX_DN<19>                                           
P  NNAMEm5846 P5E_PEX3_STN7_TX_DN<113>                                          
P  NNAMEm5847 P5E_PEX0_STN2_TX_DN<38>                                           
P  NNAMEm5848 P5E_PEX1_STN5_TX_DN<81>                                           
P  NNAMEm5849 P5E_PEX2_STN5_TX_DP<85>                                           
P  NNAMEm5850 P5E_PEX3_STN1_TX_DP<30>                                           
P  NNAMEm5851 P5E_PEX3_STN6_TX_DN<101>                                          
P  NNAMEm5852 P5E_PEX0_STN2_TX_DP<42>                                           
P  NNAMEm5853 P5E_PEX1_STN5_TX_DN<87>                                           
P  NNAMEm5854 P5E_PEX2_STN2_TX_DN<37>                                           
P  NNAMEm5855 P5E_PEX3_STN0_TX_DN<15>                                           
P  NNAMEm5856 P5E_PEX3_STN6_TX_DN<100>                                          
P  NNAMEm5857 P5E_PEX0_STN2_TX_DN<36>                                           
P  NNAMEm5858 P5E_PEX1_STN5_TX_DN<90>                                           
P  NNAMEm5859 P5E_PEX2_STN5_TX_DP<84>                                           
P  NNAMEm5860 P5E_PEX3_STN1_TX_DN<16>                                           
P  NNAMEm5861 P5E_PEX3_STN7_TX_DN<119>                                          
P  NNAMEm5862 P5E_PEX0_STN5_TX_DP<90>                                           
P  NNAMEm5863 P5E_PEX1_STN2_TX_DP<39>                                           
P  NNAMEm5864 P5E_PEX2_STN5_TX_DN<89>                                           
P  NNAMEm5865 P5E_PEX3_STN0_TX_DP<3>                                            
P  NNAMEm5866 P5E_PEX3_STN6_TX_DP<110>                                          
P  NNAMEm5867 P5E_PEX0_STN5_TX_DN<82>                                           
P  NNAMEm5868 P5E_PEX1_STN2_TX_DP<36>                                           
P  NNAMEm5869 P5E_PEX2_STN5_TX_DN<91>                                           
P  NNAMEm5870 P5E_PEX3_STN0_TX_DP<6>                                            
P  NNAMEm5871 P5E_PEX3_STN6_TX_DP<98>                                           
P  NNAMEm5872 P5E_PEX0_STN5_TX_DP<82>                                           
P  NNAMEm5873 P5E_PEX1_STN5_TX_DN<88>                                           
P  NNAMEm5874 P5E_PEX2_STN2_TX_DP<46>                                           
P  NNAMEm5875 P5E_PEX3_STN1_TX_DN<20>                                           
P  NNAMEm5876 P5E_PEX3_STN6_TX_DN<96>                                           
P  NNAMEm5877 P5E_PEX0_STN5_TX_DP<89>                                           
P  NNAMEm5878 P5E_PEX1_STN5_TX_DN<80>                                           
P  NNAMEm5879 P5E_PEX2_STN5_TX_DN<90>                                           
P  NNAMEm5880 P5E_PEX3_STN0_TX_DP<7>                                            
P  NNAMEm5881 P5E_PEX3_STN6_TX_DN<103>                                          
P  NNAMEm5882 P5E_PEX0_STN2_TX_DP<39>                                           
P  NNAMEm5883 P5E_PEX1_STN5_TX_DN<85>                                           
P  NNAMEm5884 P5E_PEX2_STN2_TX_DP<32>                                           
P  NNAMEm5885 P5E_PEX2_STN6_TX_DP<101>                                          
P  NNAMEm5886 P5E_PEX3_STN1_TX_DP<25>                                           
P  NNAMEm5887 P5E_PEX3_STN6_TX_DP<97>                                           
C                                                                               
C  ****************************************                                     
C      SIGNAL PINS & VIAS ON THE BOARD                                          
C  ****************************************                                     
C                                                                               
327m0000            Y8    -3          A01X+042738Y+155550X0360Y0400R090 S1      
327m0000            R6844 -2          A01X+042780Y+154637X0198Y0197     S1      
327m0000            C3636 -1   M      A01X+042771Y+155021X0198Y0197R180 S1      
327m0001            Y5    -3          A01X+095514Y+036572X0360Y0400R270 S1      
327m0001            R6843 -2          A01X+093866Y+036779X0198Y0197R090 S1      
327m0001            C2623 -1   M      A01X+094244Y+036778X0198Y0197R270 S1      
327m0002            VIA   -    M      A01X+075486Y+159230X0300Y         S1      
327m0002            U338  -5          A01X+074596Y+160473X0250Y0480R180 S1      
327m0002            R6825 -2   M      A01X+075519Y+158690X0198Y0197R090 S1      
327m0002            C2844 -1          A01X+076314Y+158686X0198Y0197R270 S1      
327m0002            C4493 -1   M      A01X+075917Y+158691X0198Y0197R270 S1      
327m0003            VIA   -    M      A01X+101911Y+135313X0300Y         S1      
327m0003            U436  -5          A01X+102757Y+134820X0250Y0480R270 S1      
327m0003            C4447 -1   M      A01X+101967Y+134807X0198Y0197R270 S1      
327m0003            R6824 -2          A01X+101408Y+135794X0198Y0197     S1      
327m0003            C4492 -1   M      A01X+101408Y+135371X0198Y0197R180 S1      
317m0004            VIA   -    MD0100PA00X+095954Y+091831X0200Y         S2      
317m0004            VIA   -    MD0100PA00X+092546Y+086734X0180Y         S0      
327m0004            U5    -K2         A01X+092389Y+086576X0160Y    R180 S1      
327m0004            R6815 -1   M      A18X+096051Y+092312X0198Y0197     S2      
327m0004            R6816 -2          A18X+094906Y+091989X0198Y0197R090 S2      
327m0004            C4489 -1   M      A18X+095296Y+091991X0198Y0197R270 S2      
317m0005            VIA   -    MD0100PA00X+081408Y+086446X0200Y         S2      
327m0005            R6819 -2   M      A18X+081382Y+086908X0198Y0197     S2      
317m0005            VIA   -    MD0100PA00X+091916Y+086734X0180Y         S0      
327m0005            U5    -K4         A01X+091759Y+086576X0160Y    R180 S1      
327m0005            R6814 -1          A18X+081382Y+087660X0198Y0197R180 S2      
327m0005            C4488 -1   M      A18X+081382Y+087281X0198Y0197R180 S2      
327m0006            VIA   -    M      A18X+090382Y+087977X0200Y         S2      
317m0006            VIA   -    MD0100PA00X+092231Y+086734X0180Y         S0      
327m0006            U5    -K3         A01X+092074Y+086576X0160Y    R180 S1      
327m0006            R6813 -1   M      A18X+090373Y+088452X0198Y0197     S2      
327m0006            C4487 -1          A18X+090374Y+089246X0198Y0197     S2      
327m0006            R6820 -2   M      A18X+090372Y+088848X0198Y0197R180 S2      
327VR_TYPE_ADC_R    VIA   -    M      A18X+092956Y+088926X0200Y         S2      
327VR_TYPE_ADC_R    R6821 -1   M      A18X+093126Y+088370X0198Y0197R090 S2      
327VR_TYPE_ADC_R    R6818 -2          A18X+093875Y+088199X0198Y0197R090 S2      
327VR_TYPE_ADC_R    C4490 -1   M      A18X+093494Y+088199X0198Y0197R270 S2      
317VR_TYPE_ADC_R    VIA   -    MD0100PA00X+092546Y+086419X0180Y         S0      
327VR_TYPE_ADC_R    U5    -J2         A01X+092389Y+086262X0160Y    R180 S1      
317ADC_TYPE_ADC_R   VIA   -    MD0100PA00X+083446Y+088454X0200Y         S2      
327ADC_TYPE_ADC_R   C4491 -1   M      A18X+082985Y+088693X0198Y0197R270 S2      
327ADC_TYPE_ADC_R   R6817 -2   M      A18X+082549Y+088690X0198Y0197R090 S2      
327ADC_TYPE_ADC_R   R6822 -1          A18X+082157Y+089388X0198Y0197     S2      
317ADC_TYPE_ADC_R   VIA   -    MD0100PA00X+091916Y+086419X0180Y         S0      
327ADC_TYPE_ADC_R   U5    -J4         A01X+091759Y+086262X0160Y    R180 S1      
327SMB_PEX1_R_SCL   VIA   -    M      A01X+079541Y+121240X0300Y         S1      
327SMB_PEX1_R_SCL   R6808 -1   M      A01X+079832Y+119818X0198Y0197R270 S1      
327SMB_PEX1_R_SCL   R6718 -2          A01X+079516Y+119177X0198Y0197R090 S1      
327SMB_PEX1_R_SCL   R3930 -2          A01X+079542Y+120649X0198Y0197R090 S1      
327SMB_PEX1_R_SDA   R6717 -2          A01X+080233Y+119809X0198Y0197R090 S1      
327SMB_PEX1_R_SDA   VIA   -    M      A01X+080229Y+121146X0300Y         S1      
327SMB_PEX1_R_SDA   R3929 -2          A01X+080360Y+120655X0198Y0197R090 S1      
327SMB_PEX1_R_SDA   R6807 -1   M      A01X+079923Y+120661X0198Y0197R270 S1      
327SMB_PEX0_R_SCL   R6660 -2          A01X+033832Y+119404X0198Y0197R090 S1      
327SMB_PEX0_R_SCL   VIA   -    M      A01X+034240Y+119878X0300Y         S1      
327SMB_PEX0_R_SCL   R6806 -1   M      A01X+034230Y+119399X0198Y0197R270 S1      
327SMB_PEX0_R_SCL   R3894 -2          A01X+034215Y+120659X0198Y0197R090 S1      
327SMB_PEX0_R_SDA   R6659 -2          A01X+035119Y+119160X0198Y0197R180 S1      
327SMB_PEX0_R_SDA   R6805 -1   M      A01X+034614Y+119413X0198Y0197R270 S1      
327SMB_PEX0_R_SDA   VIA   -    M      A01X+034444Y+121131X0300Y         S1      
327SMB_PEX0_R_SDA   R3893 -2          A01X+034639Y+120656X0198Y0197R090 S1      
327SMB_PEX3_R_SDA   R3993 -2          A01X+171757Y+120639X0198Y0197R090 S1      
327SMB_PEX3_R_SDA   R6811 -1   M      A01X+171372Y+120646X0198Y0197R270 S1      
327SMB_PEX3_R_SDA   R6721 -2          A01X+171297Y+122412X0198Y0197R270 S1      
327SMB_PEX3_R_SCL   R3994 -2          A01X+170982Y+119966X0198Y0197R090 S1      
327SMB_PEX3_R_SCL   R6812 -1   M      A01X+170983Y+120642X0198Y0197R270 S1      
327SMB_PEX3_R_SCL   R6722 -2          A01X+170874Y+122412X0198Y0197R270 S1      
327SMB_PEX2_R_SCL   R6720 -2          A01X+125130Y+120200X0198Y0197R090 S1      
327SMB_PEX2_R_SCL   VIA   -    M      A01X+125238Y+120706X0300Y         S1      
327SMB_PEX2_R_SCL   R6810 -1   M      A01X+124923Y+119250X0198Y0197R270 S1      
327SMB_PEX2_R_SCL   R3975 -2          A01X+125286Y+119238X0198Y0197R180 S1      
327SMB_PEX2_R_SDA   R6719 -2          A01X+126077Y+119690X0198Y0197R090 S1      
327SMB_PEX2_R_SDA   VIA   -    M      A01X+125741Y+121128X0300Y         S1      
327SMB_PEX2_R_SDA   R3974 -2          A01X+126054Y+120660X0198Y0197R090 S1      
327SMB_PEX2_R_SDA   R6809 -1   M      A01X+125548Y+120200X0198Y0197R270 S1      
327m0007            R6803 -1          A18X+086582Y+087894X0198Y0197     S2      
327m0007            VIA   -    M      A18X+087343Y+087457X0260Y         S2      
317m0007            VIA   -    MD0100PA00X+088137Y+087049X0180Y    R270 S0      
327m0007            U5    -L15        A01X+088294Y+086891X0160Y    R180 S1      
327m0008            R6802 -1          A18X+086740Y+086914X0198Y0197     S2      
327m0008            VIA   -    M      A18X+087188Y+086908X0260Y         S2      
317m0008            VIA   -    MD0100PA00X+088452Y+087049X0180Y    R270 S0      
327m0008            U5    -L14        A01X+088609Y+086891X0160Y    R180 S1      
327OC_P2V5_COMP     VIA   -    M      A01X+102141Y+132353X0300Y         S1      
327OC_P2V5_COMP     U449  -1          A01X+103227Y+133780X0240Y0420R270 S1      
327OC_P2V5_COMP     U448  -1   M      A01X+103230Y+132309X0240Y0420R270 S1      
327OC_P2V5_COMP     R6790 -2   M      A01X+102005Y+133076X0198Y0197R270 S1      
327OC_P2V5_COMP     C4486 -1          A01X+102412Y+133081X0198Y0197R090 S1      
327UV_P2V5_COMP     VIA   -    M      A01X+078788Y+163136X0300Y         S1      
327UV_P2V5_COMP     C4477 -1   M      A01X+077382Y+163330X0198Y0197R270 S1      
327UV_P2V5_COMP     R6781 -2   M      A01X+077836Y+163328X0198Y0197R090 S1      
327UV_P2V5_COMP     U444  -1          A01X+078977Y+162388X0240Y0420R180 S1      
327UV_P2V5_COMP     U443  -1          A01X+076652Y+163309X0240Y0420R180 S1      
327HSC_OC_VOL       VIA   -    M      A01X+103420Y+130962X0300Y         S1      
327HSC_OC_VOL       R6795 -1          A01X+104009Y+130949X0198Y0197     S1      
327HSC_OC_VOL       U448  -3   M      A01X+103230Y+131561X0240Y0420R270 S1      
327HSC_OC_VOL       R6798 -1   M      A01X+102540Y+131343X0180Y0200R270 S1      
327HSC_OC_VOL       R6791 -2          A01X+101733Y+131344X0198Y0197R270 S1      
327HSC_OC_VOL       C4485 -1   M      A01X+102126Y+131345X0198Y0197R090 S1      
327HSC_D_OC_R2      VIA   -    M      A01X+104917Y+131561X0300Y         S1      
327HSC_D_OC_R2      U448  -4   M      A01X+104292Y+131561X0240Y0420R270 S1      
327HSC_D_OC_R2      R6797 -1          A01X+105446Y+131560X0198Y0197     S1      
327HSC_D_OC_R2      R6795 -2          A01X+104324Y+130949X0198Y0197     S1      
327HSC_UV_R2_N      VIA   -    M      A01X+074419Y+162470X0300Y         S1      
327HSC_UV_R2_N      R6776 -2   M      A01X+074900Y+162134X0198Y0197R270 S1      
327HSC_UV_R2_N      R6777 -1          A01X+073534Y+163003X0198Y0197R180 S1      
327HSC_UV_R2_N      U443  -4          A01X+075904Y+162246X0240Y0420R180 S1      
327m0009            R6780 -1   M      A01X+074759Y+163378X0198Y0197R270 S1      
327m0009            VIA   -    M      A01X+075398Y+162090X0300Y         S1      
327m0009            R6779 -2          A01X+074333Y+163379X0198Y0197R090 S1      
327m0009            C4478 -1   M      A01X+075215Y+163381X0198Y0197R270 S1      
327m0009            R6776 -1          A01X+074900Y+162448X0198Y0197R270 S1      
327m0009            U443  -3   M      A01X+075904Y+163309X0240Y0420R180 S1      
327m0010            VIA   -    M      A01X+128206Y+085732X0300Y         S1      
327m0010            U6    -M2         A01X+131848Y+086294X0160Y         S1      
317m0010            VIA   -    MD0100PA00X+100894Y+092401X0200Y         S0      
317m0010            VIA   -    MD0100PA00X+081258Y+088083X0200Y         S0      
317m0010            VIA   -    MD0100PA00X+103768Y+086279X0200Y         S0      
317m0010            VIA   -    MD0100PA00X+127089Y+085634X0200Y         S0      
327m0010            R6799 -2          A18X+085368Y+087547X0198Y0197     S2      
327m0011            VIA   -    M      A01X+130131Y+087348X0300Y         S1      
327m0011            U6    -K2         A01X+131848Y+086924X0160Y         S1      
317m0011            VIA   -    MD0100PA00X+131054Y+087078X0200Y         S0      
317m0011            VIA   -    MD0100PA00X+100495Y+092400X0200Y         S0      
317m0011            VIA   -    MD0100PA00X+081222Y+088359X0200Y         S0      
317m0011            VIA   -    MD0100PA00X+103518Y+086279X0200Y         S0      
317m0011            VIA   -    MD0100PA00X+128228Y+086560X0200Y         S0      
327m0011            R6800 -2          A18X+082700Y+088039X0198Y0197     S2      
317m0012            VIA   -    MD0100PA00X+159857Y+154337X0200Y         S2      
327m0012            R6775 -1          A01X+160352Y+154337X0198Y0197     S1      
317m0012            J14   -A7   D0122PA00X+153028Y+162240X0282Y    R180 S3      
317PRSNT_GPU_A1_N   J9    -A7   D0122PA00X+170350Y+162240X0282Y    R180 S3      
317PRSNT_GPU_A1_N   VIA   -    M      A01X+164058Y+155191X0200Y         S2      
017PRSNT_GPU_A1_N   VIA   -    M      A18X+164058Y+155191X0260Y         S2      
017PRSNT_GPU_A1_N         -    MD0100PA00X+164058Y+155191                       
327PRSNT_GPU_A1_N   R6775 -2          A01X+160667Y+154337X0198Y0197     S1      
327m0013            R6774 -1          A01X+126024Y+153538X0198Y0197R180 S1      
317m0013            J13   -A3   D0122PA00X+132240Y+162240X0282Y    R180 S3      
317m0013            VIA   -    M      A01X+126289Y+153533X0200Y         S2      
017m0013            VIA   -    M      A18X+126289Y+153533X0260Y         S2      
017m0013                  -    MD0100PA00X+126289Y+153533                       
327PRSNT_GPU_A2_N   R6774 -2          A01X+125710Y+153538X0198Y0197R180 S1      
317PRSNT_GPU_A2_N   J7    -A3   D0122PA00X+114917Y+162240X0282Y    R180 S3      
317PRSNT_GPU_A2_N   VIA   -    M      A01X+125043Y+153533X0200Y         S2      
017PRSNT_GPU_A2_N   VIA   -    M      A18X+125043Y+153533X0260Y         S2      
017PRSNT_GPU_A2_N         -    MD0100PA00X+125043Y+153533                       
317m0014            J13   -Z10  D0122PA00X+138303Y+145272X0282Y    R180 S3      
327m0014            VIA   -    M      A18X+137986Y+142070X0200Y         S2      
317m0014            VIA   -    MD0100PA00X+059187Y+151807X0200Y         S0      
317m0014            VIA   -    MD0100PA00X+078016Y+141285X0200Y         S0      
327m0014            R6773 -1          A01X+059426Y+150579X0198Y0197R180 S1      
327PRSNT_GPU_A3_N   R6773 -2          A01X+059111Y+150579X0198Y0197R180 S1      
317PRSNT_GPU_A3_N   J5    -Z8   D0122PA00X+069020Y+145272X0282Y    R180 S3      
317PRSNT_GPU_A3_N   VIA   -    M      A01X+059148Y+150931X0200Y    R270 S2      
017PRSNT_GPU_A3_N   VIA   -    M      A18X+059148Y+150931X0260Y    R270 S2      
017PRSNT_GPU_A3_N         -    MD0100PA00X+059148Y+150931                       
317PRSNT_SWB_B1_N   J14   -A1   D0122PA00X+147831Y+162240X0282Y0282R180 S3      
317PRSNT_SWB_B1_N   VIA   -    MD0100PA00X+144377Y+156217X0200Y         S2      
327PRSNT_SWB_B1_N   R6772 -1          A01X+143679Y+155852X0198Y0197R270 S1      
317PRSNT_SWB_B2_N   J13   -Z2   D0122PA00X+131374Y+145272X0282Y    R180 S3      
317PRSNT_SWB_B2_N   VIA   -    MD0100PA00X+125390Y+151964X0200Y         S2      
327PRSNT_SWB_B2_N   R6771 -1          A01X+125706Y+151946X0198Y0197     S1      
327PRSNT_SWB_B3_N   R6770 -1          A01X+058139Y+150572X0198Y0197     S1      
317PRSNT_SWB_B3_N   J12   -Z8   D0122PA00X+051697Y+145272X0282Y    R180 S3      
317PRSNT_SWB_B3_N   VIA   -    M      A01X+057793Y+150569X0200Y    R090 S2      
017PRSNT_SWB_B3_N   VIA   -    M      A18X+057793Y+150569X0260Y    R090 S2      
017PRSNT_SWB_B3_N         -    MD0100PA00X+057793Y+150569                       
327P0V8_PEX3_PVCC   PR156 -1          A18X+140855Y+111897X0198Y0197R090 S2      
327P0V8_PEX3_PVCC   PU14  -4          A01X+140642Y+111801X0090Y0240R270 S1      
327P0V8_PEX3_PVCC   PC170 -1   M      A01X+141105Y+112082X0198Y0197R090 S1      
317P0V8_PEX3_PVCC   VIA   -    MD0100PA00X+141124Y+111840X0200Y         S0      
327P0V8_PEX3_PVCC   PR7181-1          A18X+140795Y+112289X0198Y0197R270 S2      
327P0V8_PEX3_PVCC   PR7182-1   M      A18X+141183Y+112286X0198Y0197R270 S2      
327P0V8_PEX3_PVCC   PR160 -1          A18X+144067Y+111897X0198Y0197R090 S2      
327P0V8_PEX3_PVCC   PU15  -4          A01X+143855Y+111801X0090Y0240R270 S1      
327P0V8_PEX3_PVCC   PC187 -1   M      A01X+144317Y+112082X0198Y0197R090 S1      
317P0V8_PEX3_PVCC   VIA   -    MD0100PA00X+144336Y+111840X0200Y         S0      
327P0V8_PEX2_PVCC   PR148 -1          A18X+134296Y+111897X0198Y0197R090 S2      
317P0V8_PEX2_PVCC   VIA   -    MD0100PA00X+134565Y+111840X0200Y         S0      
327P0V8_PEX2_PVCC   PU12  -4          A01X+134083Y+111801X0090Y0240R270 S1      
327P0V8_PEX2_PVCC   PC137 -1   M      A01X+134546Y+112082X0198Y0197R090 S1      
327P0V8_PEX2_PVCC   PR7180-1          A18X+134222Y+112271X0198Y0197R270 S2      
327P0V8_PEX2_PVCC   PR7179-1   M      A18X+134608Y+112268X0198Y0197R270 S2      
327P0V8_PEX2_PVCC   PR152 -1          A18X+137509Y+111897X0198Y0197R090 S2      
327P0V8_PEX2_PVCC   PU13  -4          A01X+137296Y+111801X0090Y0240R270 S1      
327P0V8_PEX2_PVCC   PC154 -1   M      A01X+137759Y+112082X0198Y0197R090 S1      
317P0V8_PEX2_PVCC   VIA   -    MD0100PA00X+137778Y+111840X0200Y         S0      
327P0V8_PEX1_PVCC   PR107 -1          A18X+049437Y+111897X0198Y0197R090 S2      
327P0V8_PEX1_PVCC   PC107 -1   M      A01X+049687Y+112082X0198Y0197R090 S1      
327P0V8_PEX1_PVCC   PU9   -4          A01X+049225Y+111801X0090Y0240R270 S1      
317P0V8_PEX1_PVCC   VIA   -    MD0100PA00X+049706Y+111840X0200Y         S0      
327P0V8_PEX1_PVCC   PR7178-1          A18X+049353Y+112284X0198Y0197R270 S2      
327P0V8_PEX1_PVCC   PR7177-1   M      A18X+049736Y+112286X0198Y0197R270 S2      
327P0V8_PEX1_PVCC   PR111 -1          A18X+052650Y+111897X0198Y0197R090 S2      
327P0V8_PEX1_PVCC   PU10  -4          A01X+052438Y+111801X0090Y0240R270 S1      
327P0V8_PEX1_PVCC   PC90  -1   M      A01X+052900Y+112082X0198Y0197R090 S1      
317P0V8_PEX1_PVCC   VIA   -    MD0100PA00X+052919Y+111840X0200Y         S0      
327P0V8_PEX0_PVCC   PR99  -1          A18X+042878Y+111897X0198Y0197R090 S2      
327P0V8_PEX0_PVCC   PU7   -4          A01X+042666Y+111801X0090Y0240R270 S1      
327P0V8_PEX0_PVCC   PC74  -1   M      A01X+043128Y+112082X0198Y0197R090 S1      
317P0V8_PEX0_PVCC   VIA   -    MD0100PA00X+043148Y+111840X0200Y         S0      
327P0V8_PEX0_PVCC   PR7176-1          A18X+042800Y+112274X0198Y0197R270 S2      
327P0V8_PEX0_PVCC   PR7175-1   M      A18X+043182Y+112276X0198Y0197R270 S2      
327P0V8_PEX0_PVCC   PR103 -1          A18X+046091Y+111897X0198Y0197R090 S2      
327P0V8_PEX0_PVCC   PU8   -4          A01X+045879Y+111801X0090Y0240R270 S1      
327P0V8_PEX0_PVCC   PC57  -1   M      A01X+046341Y+112082X0198Y0197R090 S1      
317P0V8_PEX0_PVCC   VIA   -    MD0100PA00X+046360Y+111840X0200Y         S0      
327P0V8_PEX0_EN3    PR7168-1          A18X+048398Y+111118X0198Y0197R180 S2      
317P0V8_PEX0_EN3    VIA   -    MD0100PA00X+048408Y+110687X0200Y         S2      
327P0V8_PEX0_EN3    PU9   -35         A01X+048355Y+111023X0090Y0240R180 S1      
327P0V8_PEX0_EN3    R6764 -2          A18X+049107Y+110933X0198Y0197R090 S2      
327P0V8_PEX0_EN2    PR7166-1          A18X+045053Y+111123X0198Y0197R180 S2      
317P0V8_PEX0_EN2    VIA   -    MD0100PA00X+045062Y+110687X0200Y         S2      
327P0V8_PEX0_EN2    PU8   -35         A01X+045009Y+111023X0090Y0240R180 S1      
327P0V8_PEX0_EN2    R6763 -2          A18X+045758Y+110932X0198Y0197R090 S2      
327P0V8_PEX0_EN1    PR7167-1          A18X+041850Y+111123X0198Y0197R180 S2      
317P0V8_PEX0_EN1    VIA   -    MD0100PA00X+041850Y+110687X0200Y         S2      
327P0V8_PEX0_EN1    PU7   -35         A01X+041796Y+111023X0090Y0240R180 S1      
327P0V8_PEX0_EN1    R6762 -2          A18X+042543Y+110932X0198Y0197R090 S2      
327P0V8_PEX2_EN3    PR7173-1          A18X+139811Y+111126X0198Y0197R180 S2      
317P0V8_PEX2_EN3    VIA   -    MD0100PA00X+139826Y+110687X0200Y         S2      
327P0V8_PEX2_EN3    PU14  -35         A01X+139772Y+111023X0090Y0240R180 S1      
327P0V8_PEX2_EN3    R6768 -2          A18X+140519Y+110932X0198Y0197R090 S2      
327P0V8_PEX2_EN4    PR7174-1          A18X+143036Y+111120X0198Y0197R180 S2      
317P0V8_PEX2_EN4    VIA   -    MD0100PA00X+143038Y+110687X0200Y         S2      
327P0V8_PEX2_EN4    PU15  -35         A01X+142985Y+111023X0090Y0240R180 S1      
327P0V8_PEX2_EN4    R6769 -2          A18X+143735Y+110934X0198Y0197R090 S2      
327P0V8_PEX2_EN2    PR7172-1          A18X+136467Y+111120X0198Y0197R180 S2      
317P0V8_PEX2_EN2    VIA   -    MD0100PA00X+136480Y+110687X0200Y         S2      
327P0V8_PEX2_EN2    PU13  -35         A01X+136426Y+111023X0090Y0240R180 S1      
327P0V8_PEX2_EN2    R6767 -2          A18X+137179Y+110932X0198Y0197R090 S2      
327P0V8_PEX2_EN1    PR7171-1          A18X+133246Y+111120X0198Y0197R180 S2      
317P0V8_PEX2_EN1    VIA   -    MD0100PA00X+133267Y+110687X0200Y         S2      
327P0V8_PEX2_EN1    PU12  -35         A01X+133213Y+111023X0090Y0240R180 S1      
327P0V8_PEX2_EN1    R6766 -2          A18X+133968Y+110932X0198Y0197R090 S2      
327P0V8_PEX0_EN4    PR7169-1          A18X+051624Y+111127X0198Y0197R180 S2      
317P0V8_PEX0_EN4    VIA   -    MD0100PA00X+051621Y+110687X0200Y         S2      
327P0V8_PEX0_EN4    PU10  -35         A01X+051567Y+111023X0090Y0240R180 S1      
327P0V8_PEX0_EN4    R6765 -2          A18X+052320Y+110934X0198Y0197R090 S2      
317PG12_USB_HUB_N   VIA   -           A01X+002988Y+144170X0200Y         S2      
017PG12_USB_HUB_N   VIA   -           A18X+002988Y+144170X0260Y         S2      
017PG12_USB_HUB_N         -     D0100PA00X+002988Y+144170                       
327PG12_USB_HUB_N   R6758 -2   M      A01X+002722Y+144170X0198Y0197R090 S1      
327PG12_USB_HUB_N   Q251  -G          A01X+001256Y+144974X0320Y0360     S1      
327PG12_USB_HUB_N   Q250  -D   M      A01X+001634Y+144170X0320Y0360     S1      
327m0015            VIA   -    M      A01X+003122Y+154463X0300Y         S1      
327m0015            R6739 -2          A01X+003585Y+155016X0198Y0197R270 S1      
327m0015            U442  -45         A01X+003122Y+153896X0094Y0236     S1      
327m0016            VIA   -    M      A01X+004152Y+154511X0300Y         S1      
327m0016            R6743 -2          A01X+004707Y+155015X0198Y0197R270 S1      
327m0016            U442  -43         A01X+003516Y+153896X0094Y0236     S1      
327m0017            VIA   -    M      A01X+003636Y+154438X0300Y         S1      
327m0017            R6742 -2          A01X+004095Y+155016X0198Y0197R270 S1      
327m0017            U442  -44         A01X+003319Y+153896X0094Y0236     S1      
327m0018            VIA   -    M      A01X+002602Y+154393X0300Y         S1      
327m0018            R6741 -2          A01X+002623Y+154858X0198Y0197R270 S1      
327m0018            U442  -47         A01X+002728Y+153896X0094Y0236     S1      
327m0019            VIA   -    M      A01X+003110Y+154976X0300Y         S1      
327m0019            R6740 -2          A01X+000646Y+155688X0198Y0197R180 S1      
327m0019            U442  -46         A01X+002925Y+153896X0094Y0236     S1      
327m0020            VIA   -    M      A01X+002108Y+154311X0300Y         S1      
327m0020            R6753 -2   M      A01X+002238Y+154860X0198Y0197R270 S1      
327m0020            R6754 -1          A01X+001843Y+154861X0198Y0197R090 S1      
327m0020            U442  -48         A01X+002532Y+153896X0094Y0236     S1      
317P1V2_USB_8042    VIA   -    M      A01X+001260Y+143814X0200Y         S2      
017P1V2_USB_8042    VIA   -    M      A18X+001260Y+143814X0260Y         S2      
017P1V2_USB_8042          -    MD0100PA00X+001260Y+143814                       
327P1V2_USB_8042    Q250  -G          A01X+001260Y+143383X0320Y0360     S1      
327P1V2_USB_8042    C4467 -1          A18X+002572Y+152277X0198Y0197R180 S2      
317P1V2_USB_8042    VIA   -    MD0100PA00X+001986Y+152066X0200Y         S2      
327P1V2_USB_8042    U442  -57         A01X+002276Y+152066X0094Y0236R090 S1      
317P1V2_USB_8042    VIA   -    MD0100PA00X+006030Y+153444X0200Y         S0      
327P1V2_USB_8042    U442  -31         A01X+005740Y+153444X0094Y0236R090 S1      
317P1V2_USB_8042    VIA   -    MD0100PA00X+006028Y+152840X0200Y         S0      
327P1V2_USB_8042    U442  -28         A01X+005740Y+152853X0094Y0236R090 S1      
327P1V2_USB_8042    C4473 -1          A18X+006043Y+151860X0198Y0197R180 S2      
327P1V2_USB_8042    C4468 -1          A18X+006040Y+152571X0198Y0197R180 S2      
327P1V2_USB_8042    C4470 -1          A18X+006038Y+153180X0198Y0197R180 S2      
327P1V2_USB_8042    C4469 -1          A18X+004387Y+150141X0198Y0197R090 S2      
317P1V2_USB_8042    VIA   -    MD0100PA00X+003319Y+150137X0200Y         S0      
327P1V2_USB_8042    U442  -5          A01X+003319Y+150432X0094Y0236     S1      
317P1V2_USB_8042    VIA   -    MD0100PA00X+003910Y+150136X0200Y         S0      
327P1V2_USB_8042    U442  -8          A01X+003910Y+150432X0094Y0236     S1      
327P1V2_USB_8042    C4471 -1          A18X+003574Y+150141X0198Y0197R090 S2      
327P1V2_USB_8042    C4472 -1          A18X+002345Y+153730X0198Y0197R090 S2      
327P1V2_USB_8042    C4476 -1          A18X+005892Y+151174X0198Y0197R180 S2      
317P1V2_USB_8042    VIA   -    MD0100PA00X+006023Y+151475X0200Y         S0      
327P1V2_USB_8042    U442  -21         A01X+005740Y+151475X0094Y0236R090 S1      
327P1V2_USB_8042    C4474 -1          A18X+004408Y+153638X0400Y0500R270 S2      
327P1V2_USB_8042    L151  -1          A18X+005104Y+153636X0440Y0540R090 S2      
327P1V2_USB_8042    U442  -51         A01X+002276Y+153247X0094Y0236R090 S1      
317P1V2_USB_8042    VIA   -    MD0100PA00X+001888Y+153433X0200Y    R180 S2      
317P1V2_USB_8042    VIA   -    MD0100PA00X+004809Y+150139X0200Y         S0      
327P1V2_USB_8042    U442  -13         A01X+004894Y+150432X0094Y0236     S1      
317P3V3_USB_8042    VIA   -    M      A01X+006475Y+155589X0200Y         S2      
017P3V3_USB_8042    VIA   -    M      A18X+006475Y+155589X0260Y         S2      
017P3V3_USB_8042          -    MD0100PA00X+006475Y+155589                       
327P3V3_USB_8042    R6755 -1          A01X+006475Y+155326X0198Y0197R270 S1      
327P3V3_USB_8042    R6742 -1          A01X+004095Y+155330X0198Y0197R270 S1      
317P3V3_USB_8042    VIA   -    MD0100PA00X+004095Y+155593X0200Y         S0      
317P3V3_USB_8042    VIA   -    MD0100PA00X+004707Y+155592X0200Y         S0      
327P3V3_USB_8042    R6743 -1          A01X+004707Y+155330X0198Y0197R270 S1      
327P3V3_USB_8042    R6741 -1          A01X+002623Y+155173X0198Y0197R270 S1      
317P3V3_USB_8042    VIA   -    MD0100PA00X+002623Y+155417X0200Y         S0      
327P3V3_USB_8042    R6744 -1          A01X+001037Y+155066X0198Y0197R270 S1      
317P3V3_USB_8042    VIA   -    MD0100PA00X+001037Y+155308X0200Y    R180 S0      
327P3V3_USB_8042    R6740 -1          A01X+000961Y+155688X0198Y0197R180 S1      
327P3V3_USB_8042    R6756 -1          A01X+006548Y+154457X0198Y0197R180 S1      
317P3V3_USB_8042    VIA   -    M      A01X+006548Y+154198X0200Y         S2      
017P3V3_USB_8042    VIA   -    M      A18X+006548Y+154198X0260Y         S2      
017P3V3_USB_8042          -    MD0100PA00X+006548Y+154198                       
327P3V3_USB_8042    U442  -34         A01X+005287Y+153896X0094Y0236     S1      
317P3V3_USB_8042    VIA   -    MD0100PA00X+005586Y+154179X0200Y         S0      
327P3V3_USB_8042    U442  -52         A01X+002276Y+153050X0094Y0236R090 S1      
317P3V3_USB_8042    VIA   -    MD0100PA00X+001974Y+153050X0200Y         S0      
327P3V3_USB_8042    C4463 -1          A18X+002572Y+152993X0198Y0197R180 S2      
327P3V3_USB_8042    U442  -16         A01X+005484Y+150432X0094Y0236     S1      
317P3V3_USB_8042    VIA   -    MD0100PA00X+005484Y+150162X0200Y         S0      
327P3V3_USB_8042    C4464 -1          A18X+005145Y+150167X0198Y0197R090 S2      
327P3V3_USB_8042    C4465 -1          A18X+001777Y+150357X0400Y0500     S2      
327P3V3_USB_8042    L150  -1          A18X+001118Y+151075X0440Y0540R270 S2      
327P3V3_USB_8042    C4461 -1          A18X+001804Y+151242X0198Y0197R270 S2      
327P3V3_USB_8042    C4462 -1          A18X+002154Y+151242X0198Y0197R270 S2      
317P3V3_USB_8042    VIA   -    MD0100PA00X+001974Y+150885X0200Y         S0      
327P3V3_USB_8042    U442  -63         A01X+002276Y+150885X0094Y0236R090 S1      
327m0021            R6735 -1   M      A01X+001263Y+150162X0198Y0197     S1      
327m0021            Y9    -1          A01X+001095Y+148965X0480Y0560     S1      
317m0021            VIA   -    M      A01X+001009Y+149425X0200Y         S2      
017m0021            VIA   -    M      A18X+001009Y+149425X0260Y         S2      
017m0021                  -    MD0100PA00X+001009Y+149425                       
327m0021            C4460 -1   M      A01X+001226Y+149678X0198Y0197R180 S1      
327m0021            U442  -61         A01X+002276Y+151278X0094Y0236R090 S1      
327m0022            R6735 -2   M      A01X+001578Y+150162X0198Y0197     S1      
327m0022            Y9    -3          A01X+001764Y+148099X0480Y0560     S1      
317m0022            VIA   -    M      A01X+001589Y+149425X0200Y         S2      
017m0022            VIA   -    M      A18X+001589Y+149425X0260Y         S2      
017m0022                  -    MD0100PA00X+001589Y+149425                       
327m0022            C4459 -1   M      A01X+001622Y+149678X0198Y0197     S1      
327m0022            U442  -62         A01X+002276Y+151081X0094Y0236R090 S1      
327m0023            VIA   -    M      A01X+006866Y+148364X0160Y0041R315 S1      
327m0023            R6751 -1   M      A01X+005434Y+148790X0198Y0197R090 S1      
327m0023            R6734 -1          A01X+021419Y+142591X0180Y0200R270 S1      
327m0023            U442  -18         A01X+005740Y+150885X0094Y0236R090 S1      
327m0024            VIA   -    M      A01X+007140Y+145246X0160Y0041R270 S1      
327m0024            R6752 -1   M      A01X+005435Y+148396X0198Y0197R270 S1      
327m0024            R6733 -1          A01X+022154Y+142581X0180Y0200R270 S1      
327m0024            U442  -17         A01X+005740Y+150688X0094Y0236R090 S1      
327m0025            VIA   -    M      A01X+003162Y+146346X0160Y0041R270 S1      
327m0025            R6732 -1          A01X+041149Y+149497X0180Y0200R270 S1      
327m0025            U442  -10         A01X+004303Y+150432X0094Y0236     S1      
327m0026            VIA   -    M      A01X+003054Y+147928X0160Y0041R270 S1      
327m0026            R6731 -1          A01X+041884Y+149488X0180Y0200R270 S1      
327m0026            U442  -9          A01X+004106Y+150432X0094Y0236     S1      
327m0027            R6747 -1   M      A01X+001177Y+152535X0198Y0197R270 S1      
317m0027            VIA   -    MD0100PA01X+000798Y+152564X0200Y         S0      
327m0027            U442  -54         A01X+002276Y+152656X0094Y0236R090 S1      
327m0027            R6728 -2          A01X+039362Y+151330X0180Y0200R090 S1      
317m0027            VIA   -    MD0100PA01X+003922Y+146484X0200Y         S0      
327m0027            VIA   -    M      A01X+006424Y+143419X0160Y0041R315 S1      
327m0028            U442  -53         A01X+002276Y+152853X0094Y0236R090 S1      
317m0028            VIA   -    MD0100PA01X+000798Y+152904X0200Y         S0      
327m0028            R6748 -1   M      A01X+001178Y+152931X0198Y0197R090 S1      
327m0028            VIA   -    M      A01X+008264Y+141701X0160Y0041     S1      
317m0028            VIA   -    MD0100PA01X+003582Y+146484X0200Y         S0      
327m0028            R6727 -2          A01X+040090Y+151341X0180Y0200R090 S1      
327m0029            VIA   -    M      A01X+006161Y+153976X0300Y         S1      
327m0029            R6756 -2          A01X+006233Y+154457X0198Y0197R180 S1      
327m0029            U442  -33         A01X+005484Y+153896X0094Y0236     S1      
317P3V3_USB_HUB     VIA   -    MD0100PA00X+006075Y+155589X0200Y         S0      
327P3V3_USB_HUB     R6842 -2          A01X+006001Y+155327X0198Y0197R090 S1      
327P3V3_USB_HUB     L150  -2          A18X+001118Y+150327X0440Y0540R270 S2      
317P3V3_USB_HUB     VIA   -    MD0100PA00X+000649Y+150133X0200Y         S0      
317P3V3_USB_HUB     VIA   -    M      A01X+001630Y+146820X0200Y         S2      
017P3V3_USB_HUB     VIA   -    M      A18X+001630Y+146820X0260Y         S2      
017P3V3_USB_HUB           -    MD0100PA00X+001630Y+146820                       
327P3V3_USB_HUB     Q251  -D          A01X+001630Y+145761X0320Y0360     S1      
327P3V3_USB_HUB     R6759 -1   M      A01X+001630Y+146461X0198Y0197     S1      
327m0030            VIA   -    M      A01X+005760Y+154476X0300Y         S1      
327m0030            R6755 -2          A01X+006475Y+155011X0198Y0197R270 S1      
327m0030            U442  -35         A01X+005091Y+153896X0094Y0236     S1      
327m0031            R6736 -2          A01X+001438Y+154750X0198Y0197R270 S1      
327m0031            VIA   -    M      A01X+001608Y+154168X0300Y         S1      
327m0031            U442  -49         A01X+002276Y+153640X0094Y0236R090 S1      
327m0032            C4475 -1          A01X+000656Y+154754X0198Y0197R090 S1      
327m0032            R6757 -2   M      A01X+001085Y+154170X0198Y0197R090 S1      
327m0032            VIA   -    M      A01X+001646Y+153622X0300Y         S1      
327m0032            U442  -50         A01X+002276Y+153444X0094Y0236R090 S1      
327m0032            R6744 -2   M      A01X+001037Y+154750X0198Y0197R270 S1      
327m0033            R6842 -1          A01X+006001Y+155012X0198Y0197R090 S1      
327m0033            VIA   -    M      A01X+005226Y+154519X0300Y         S1      
327m0033            R6746 -2   M      A01X+005611Y+155012X0198Y0197R270 S1      
327m0033            U442  -40         A01X+004106Y+153896X0094Y0236     S1      
327m0034            VIA   -    M      A01X+004682Y+154466X0300Y         S1      
327m0034            U442  -42         A01X+003713Y+153896X0094Y0236     S1      
327m0034            R6745 -2          A01X+005205Y+155012X0198Y0197R270 S1      
327m0035            VIA   -    M      A01X+002407Y+149652X0300Y         S1      
327m0035            R6737 -1          A01X+002567Y+149187X0198Y0197R270 S1      
327m0035            U442  -64         A01X+002276Y+150688X0094Y0236R090 S1      
317m0036            X73   -1    D0098PA00X+091728Y+172899X0395Y    R180 S3      
317m0036            X72   -4    D0098PA00X+116933Y+172899X0395Y         S3      
317m0037            X81   -1    D0098PA00X+116926Y+175257X0395Y    R180 S3      
317m0037            X80   -4    D0098PA00X+091716Y+175257X0395Y         S3      
317m0038            X76   -1    D0098PA00X+062986Y+176176X0395Y         S3      
317m0038            X77   -4    D0098PA00X+088191Y+176176X0395Y    R180 S3      
317m0039            X73   -4    D0098PA00X+091728Y+173899X0395Y    R180 S3      
317m0039            X72   -1    D0098PA00X+116933Y+173899X0395Y         S3      
317m0040            X76   -4    D0098PA00X+062986Y+175176X0395Y         S3      
317m0040            X77   -1    D0098PA00X+088191Y+175176X0395Y    R180 S3      
317m0041            X68   -4    D0098PA00X+091707Y+178601X0395Y    R180 S3      
317m0041            X69   -1    D0098PA00X+116912Y+178601X0395Y         S3      
317m0042            X79   -1    D0098PA00X+088152Y+179884X0395Y    R180 S3      
317m0042            X78   -4    D0098PA00X+062948Y+179884X0395Y         S3      
317m0043            X79   -4    D0098PA00X+088152Y+180884X0395Y    R180 S3      
317m0043            X78   -1    D0098PA00X+062948Y+180884X0395Y         S3      
317m0044            X71   -1    D0098PA00X+062971Y+177544X0395Y    R180 S3      
317m0044            X70   -4    D0098PA00X+088176Y+177544X0395Y         S3      
317m0045            X66   -4    D0098PA00X+063008Y+173829X0395Y    R180 S3      
317m0045            X67   -1    D0098PA00X+088218Y+173829X0395Y         S3      
317m0046            X66   -1    D0098PA00X+063008Y+172829X0395Y    R180 S3      
317m0046            X67   -4    D0098PA00X+088218Y+172829X0395Y         S3      
317m0047            X81   -4    D0098PA00X+116926Y+176257X0395Y    R180 S3      
317m0047            X80   -1    D0098PA00X+091716Y+176257X0395Y         S3      
317m0048            X68   -1    D0098PA00X+091707Y+177601X0395Y    R180 S3      
317m0048            X69   -4    D0098PA00X+116912Y+177601X0395Y         S3      
317m0049            X75   -4    D0098PA00X+091717Y+180044X0395Y         S3      
317m0049            X74   -1    D0098PA00X+116922Y+180044X0395Y    R180 S3      
317m0050            X71   -4    D0098PA00X+062971Y+178544X0395Y    R180 S3      
317m0050            X70   -1    D0098PA00X+088176Y+178544X0395Y         S3      
317m0051            X75   -1    D0098PA00X+091717Y+181044X0395Y         S3      
317m0051            X74   -4    D0098PA00X+116922Y+181044X0395Y    R180 S3      
327m0052            R6720 -1          A01X+125130Y+119885X0198Y0197R090 S1      
317m0052            VIA   -    MD0100PA00X+125306Y+119492X0200Y         S0      
327m0052            PEX2  -L34        A01X+118268Y+121732X0180Y         S1      
317m0052            VIA   -    M      A01X+118455Y+121545X0160Y         S2      
017m0052            VIA   -    M      A18X+118455Y+121545X0200Y         S2      
017m0052                  -    MD0080PA00X+118455Y+121545                       
317m0053            VIA   -    MD0080PA00X+119577Y+121171X0160Y         S0      
317m0053            VIA   -    M      A01X+126080Y+119110X0200Y         S2      
017m0053            VIA   -    M      A18X+126080Y+119110X0260Y         S2      
017m0053                  -    MD0100PA00X+126080Y+119110                       
327m0053            R6719 -1          A01X+126077Y+119374X0198Y0197R090 S1      
327m0053            PEX2  -M38        A01X+119764Y+121358X0180Y         S1      
317m0054            VIA   -    MD0080PA00X+165285Y+121171X0160Y         S0      
317m0054            VIA   -    M      A01X+171297Y+122984X0200Y         S2      
017m0054            VIA   -    M      A18X+171297Y+122984X0260Y         S2      
017m0054                  -    MD0100PA00X+171297Y+122984                       
327m0054            R6721 -1          A01X+171297Y+122727X0198Y0197R270 S1      
327m0054            PEX3  -M38        A01X+165472Y+121358X0180Y         S1      
317m0055            VIA   -    MD0100PA00X+171082Y+123169X0200Y         S0      
327m0055            R6722 -1          A01X+170874Y+122728X0198Y0197R270 S1      
327m0055            PEX3  -L34        A01X+163976Y+121732X0180Y         S1      
317m0055            VIA   -    M      A01X+164163Y+121545X0160Y         S2      
017m0055            VIA   -    M      A18X+164163Y+121545X0200Y         S2      
017m0055                  -    MD0080PA00X+164163Y+121545                       
317m0056            VIA   -    MD0080PA00X+072746Y+121545X0160Y         S0      
327m0056            PEX1  -L34        A01X+072559Y+121732X0180Y         S1      
317m0056            VIA   -    M      A01X+079238Y+119166X0200Y         S2      
017m0056            VIA   -    M      A18X+079238Y+119166X0260Y         S2      
017m0056                  -    MD0100PA00X+079238Y+119166                       
327m0056            R6718 -1          A01X+079516Y+118862X0198Y0197R090 S1      
317m0057            VIA   -    MD0080PA00X+073868Y+121171X0160Y         S0      
327m0057            R6717 -1          A01X+080233Y+119494X0198Y0197R090 S1      
327m0057            PEX1  -M38        A01X+074055Y+121358X0180Y         S1      
317m0057            VIA   -    M      A01X+080446Y+119311X0200Y         S2      
017m0057            VIA   -    M      A18X+080446Y+119311X0260Y         S2      
017m0057                  -    MD0100PA00X+080446Y+119311                       
327PWRGD_P1V2_AUX   U342  -5          A01X+099523Y+083832X0110Y0360R090 S1      
327PWRGD_P1V2_AUX   R5538 -2          A01X+098478Y+082516X0198Y0197     S1      
327PWRGD_P1V2_AUX   R4433 -2   M      A01X+098478Y+082916X0198Y0197     S1      
317PWRGD_P1V2_AUX   VIA   -    M      A01X+098770Y+082916X0200Y         S2      
017PWRGD_P1V2_AUX   VIA   -    M      A18X+098770Y+082916X0260Y         S2      
017PWRGD_P1V2_AUX         -    MD0100PA00X+098770Y+082916                       
327P1V2_AUX_ADJ     U342  -4          A01X+099523Y+084029X0110Y0360R270 S1      
317P1V2_AUX_ADJ     VIA   -    M      A01X+098770Y+083716X0200Y         S2      
017P1V2_AUX_ADJ     VIA   -    M      A18X+098770Y+083716X0260Y         S2      
017P1V2_AUX_ADJ           -    MD0100PA00X+098770Y+083716                       
327P1V2_AUX_ADJ     R4432 -2          A01X+098478Y+083316X0198Y0197     S1      
327P1V2_AUX_ADJ     R4434 -1   M      A01X+098478Y+083716X0198Y0197R180 S1      
317HSC_TYPE_ADC_R   VIA   -    MD0100PA00X+092861Y+086419X0180Y         S0      
327HSC_TYPE_ADC_R   U5    -J1         A01X+092704Y+086262X0160Y    R180 S1      
317HSC_TYPE_ADC_R   VIA   -    M      A01X+097351Y+083499X0200Y         S2      
017HSC_TYPE_ADC_R   VIA   -    M      A18X+097351Y+083499X0260Y         S2      
017HSC_TYPE_ADC_R         -    MD0100PA00X+097351Y+083499                       
327HSC_TYPE_ADC_R   R6714 -1          A01X+097352Y+082791X0198Y0197     S1      
327HSC_TYPE_ADC_R   C4458 -1   M      A01X+097351Y+083180X0198Y0197     S1      
327HSC_TYPE_ADC_R   R6713 -2          A18X+099378Y+138920X0198Y0197R180 S2      
327HSC_TYPE_ADC_R   R6823 -1   M      A18X+098532Y+135873X0198Y0197R270 S2      
317HSC_TYPE_ADC_R   VIA   -    MD0100PA00X+090418Y+135996X0200Y         S0      
317m0058            VIA   -    MD0100PA00X+131376Y+084247X0180Y         S0      
327m0058            U6    -V1         A01X+131533Y+084404X0160Y         S1      
317m0058            VIA   -    MD0100PA00X+152295Y+089795X0200Y         S0      
317m0058            VIA   -    MD0100PA00X+139054Y+090009X0200Y         S0      
327m0058            R6692 -1          A01X+180005Y+143757X0198Y0197R090 S1      
317m0058            VIA   -    M      A01X+181220Y+143262X0200Y         S2      
017m0058            VIA   -    M      A18X+181220Y+143262X0260Y         S2      
017m0058                  -    MD0100PA00X+181220Y+143262                       
327m0059            R6694 -1   M      A01X+179021Y+143096X0198Y0197R180 S1      
327m0059            R6689 -1   M      A01X+180388Y+144072X0198Y0197R270 S1      
327m0059            C4454 -1          A01X+180739Y+144072X0120Y0150R270 S1      
327m0059            R6692 -2   M      A01X+180005Y+144072X0198Y0197R090 S1      
317m0059            VIA   -    M      A01X+177219Y+142837X0200Y         S2      
017m0059            VIA   -    M      A18X+177219Y+142837X0260Y         S2      
017m0059                  -    MD0100PA00X+177219Y+142837                       
317m0059            VIA   -    MD0100PA00X+159746Y+146066X0200Y         S0      
327m0059            Q242  -3          A01X+159746Y+146336X0240Y0240R180 S1      
317m0060            VIA   -    MD0100PA00X+132320Y+084247X0180Y         S0      
327m0060            U6    -V4         A01X+132478Y+084404X0160Y         S1      
317m0060            VIA   -    MD0100PA00X+152288Y+090103X0200Y         S0      
317m0060            VIA   -    MD0100PA00X+138750Y+089993X0200Y         S0      
327m0060            R6686 -1          A01X+179992Y+146976X0198Y0197R090 S1      
317m0060            VIA   -    M      A01X+180281Y+146402X0200Y         S2      
017m0060            VIA   -    M      A18X+180281Y+146402X0260Y         S2      
017m0060                  -    MD0100PA00X+180281Y+146402                       
327m0061            Q243  -3          A01X+178306Y+147295X0240Y0240R270 S1      
327m0061            R6688 -1   M      A01X+178306Y+146270X0198Y0197     S1      
327m0061            VIA   -    M      A01X+179510Y+146368X0300Y         S1      
327m0061            C4453 -1          A01X+180727Y+147291X0120Y0150R270 S1      
327m0061            R6683 -1   M      A01X+180376Y+147290X0198Y0197R270 S1      
327m0061            R6686 -2   M      A01X+179992Y+147291X0198Y0197R090 S1      
317m0062            VIA   -    M      A01X+179537Y+144454X0200Y         S2      
017m0062            VIA   -    M      A18X+179537Y+144454X0260Y         S2      
017m0062                  -    MD0100PA00X+179537Y+144454                       
327m0062            R6690 -1          A01X+179995Y+144454X0198Y0197     S1      
317m0062            VIA   -    MD0100PA00X+160197Y+145344X0200Y         S0      
327m0062            Q242  -5          A01X+160041Y+145628X0160Y0240R180 S1      
327m0062            Q242  -6   M      A01X+160336Y+145628X0240Y0240R180 S1      
327m0063            Q243  -6          A01X+179014Y+147886X0240Y0240R270 S1      
327m0063            VIA   -    M      A01X+179515Y+147815X0300Y         S1      
327m0063            R6684 -1          A01X+179982Y+147673X0198Y0197     S1      
327m0063            Q243  -5   M      A01X+179014Y+147590X0160Y0240R270 S1      
327m0064            R6660 -1          A01X+033832Y+119090X0198Y0197R090 S1      
317m0064            VIA   -    MD0100PA00X+033550Y+118822X0200Y         S0      
327m0064            PEX0  -L34        A01X+026850Y+121732X0180Y         S1      
317m0064            VIA   -    M      A01X+027037Y+121545X0160Y         S2      
017m0064            VIA   -    M      A18X+027037Y+121545X0200Y         S2      
017m0064                  -    MD0080PA00X+027037Y+121545                       
327m0065            R6659 -1          A01X+035434Y+119160X0198Y0197R180 S1      
317m0065            VIA   -    MD0100PA00X+036052Y+119228X0200Y         S0      
327m0065            PEX0  -M38        A01X+028346Y+121358X0180Y         S1      
317m0065            VIA   -    M      A01X+028159Y+121171X0160Y         S2      
017m0065            VIA   -    M      A18X+028159Y+121171X0200Y         S2      
017m0065                  -    MD0080PA00X+028159Y+121171                       
327m0066            VIA   -    M      A01X+071561Y+074798X0300Y         S1      
327m0066            U52   -4          A01X+072973Y+074368X0240Y0420R090 S1      
327m0066            Q240  -G          A01X+071494Y+073443X0320Y0360R090 S1      
327m0067            VIA   -    M      A18X+114667Y+077841X0260Y         S2      
327m0067            Q241  -G          A18X+113962Y+078291X0320Y0360R090 S2      
327m0067            U64   -4          A18X+115343Y+078287X0240Y0420     S2      
327m0068            R6655 -1          A01X+103900Y+137164X0198Y0197R270 S1      
327m0068            VIA   -    M      A01X+103900Y+137627X0300Y         S1      
327m0068            U437  -D          A01X+103334Y+137696X0320Y0360R270 S1      
327A_HSC_LOW_GATE   R6653 -2   M      A01X+101406Y+138080X0198Y0197     S1      
327A_HSC_LOW_GATE   R6654 -1          A01X+101405Y+137675X0198Y0197R180 S1      
327A_HSC_LOW_GATE   VIA   -    M      A01X+101933Y+138080X0300Y         S1      
327A_HSC_LOW_GATE   U436  -1   M      A01X+103788Y+134446X0250Y0480R270 S1      
327A_HSC_LOW_GATE   U437  -G   M      A01X+102547Y+138070X0320Y0360R270 S1      
327A_HSC_LOW_GATE   R6793 -2          A01X+105756Y+131144X0198Y0197     S1      
327A_HSC_LOW_GATE   R6797 -2   M      A01X+105761Y+131560X0198Y0197     S1      
327A_HSC_HIGH       R6649 -2   M      A01X+101926Y+136340X0198Y0197R270 S1      
327A_HSC_HIGH       R6651 -1          A01X+101404Y+136353X0198Y0197R180 S1      
327A_HSC_HIGH       VIA   -    M      A01X+102432Y+135834X0300Y         S1      
327A_HSC_HIGH       U436  -4          A01X+102757Y+135194X0250Y0480R270 S1      
327m0069            U6    -Y2         A01X+131848Y+083774X0160Y         S1      
317m0069            VIA   -    MD0100PA00X+131691Y+083617X0180Y         S0      
317m0069            VIA   -    MD0100PA00X+144873Y+086440X0200Y         S0      
317m0069            VIA   -    MD0100PA00X+151271Y+086742X0200Y         S0      
317m0069            VIA   -    M      A01X+159679Y+144256X0200Y         S2      
017m0069            VIA   -    M      A18X+159679Y+144256X0260Y         S2      
017m0069                  -    MD0100PA00X+159679Y+144256                       
327m0069            R6679 -1          A01X+159388Y+144256X0198Y0197R180 S1      
327A_HSC_LOW        R6648 -2          A01X+101407Y+136884X0198Y0197     S1      
327A_HSC_LOW        R6650 -1          A01X+101406Y+137273X0198Y0197R180 S1      
327A_HSC_LOW        VIA   -    M      A01X+100581Y+135158X0300Y         S1      
327A_HSC_LOW        U436  -3          A01X+103788Y+135194X0250Y0480R270 S1      
317m0070            VIA   -    MD0100PA00X+159302Y+145756X0200Y         S0      
327m0070            R6680 -1   M      A01X+158775Y+145756X0198Y0197R090 S1      
327m0070            R6679 -2   M      A01X+159073Y+144256X0198Y0197R180 S1      
327m0070            C4452 -1          A01X+159394Y+143911X0120Y0150R270 S1      
327m0070            VIA   -    M      A01X+159071Y+145147X0300Y         S1      
327m0070            R6678 -1   M      A01X+159071Y+144649X0198Y0197     S1      
317m0070            VIA   -    MD0100PA00X+178318Y+143755X0200Y         S0      
327m0070            Q244  -3          A01X+178318Y+144076X0240Y0240R270 S1      
317m0071            VIA   -    M      A01X+178774Y+143776X0200Y         S2      
017m0071            VIA   -    M      A18X+178774Y+143776X0260Y         S2      
017m0071                  -    MD0100PA00X+178774Y+143776                       
327m0071            Q244  -6          A01X+179026Y+144667X0240Y0240R270 S1      
327m0071            Q244  -5   M      A01X+179026Y+144372X0160Y0240R270 S1      
317m0071            VIA   -    MD0100PA00X+160033Y+144907X0200Y         S0      
327m0071            R6677 -1          A01X+160033Y+144656X0198Y0197R270 S1      
327m0072            R6669 -1          A01X+049960Y+065515X0198Y0197     S1      
317m0072            VIA   -    M      A01X+049953Y+065784X0200Y         S2      
017m0072            VIA   -    M      A18X+049953Y+065784X0260Y         S2      
017m0072                  -    MD0100PA00X+049953Y+065784                       
327m0072            R6661 -2          A01X+049953Y+066044X0198Y0197R180 S1      
327m0072            U114  -L8         A01X+052548Y+069055X0090Y         S1      
317m0072            VIA   -    MD0100PA00X+052449Y+069244X0180Y         S0      
327m0073            VIA   -    M      A01X+071340Y+070995X0300Y         S1      
327m0073            R6671 -1          A01X+071338Y+070531X0198Y0197R270 S1      
317m0073            VIA   -    MD0100PA00X+071020Y+070756X0200Y         S0      
327m0073            R6663 -2          A01X+070716Y+070930X0198Y0197     S1      
327m0073            U114  -K11        A01X+053138Y+069252X0090Y         S1      
317m0073            VIA   -    MD0100PA00X+052949Y+069494X0180Y         S0      
317m0074            VIA   -    M      A01X+048174Y+065748X0200Y         S2      
017m0074            VIA   -    M      A18X+048174Y+065748X0260Y         S2      
017m0074                  -    MD0100PA00X+048174Y+065748                       
327m0074            R6670 -1          A01X+047883Y+064897X0198Y0197     S1      
327m0074            R6662 -2   M      A01X+047879Y+065291X0198Y0197R180 S1      
327m0074            U114  -L10        A01X+052941Y+069055X0090Y         S1      
317m0074            VIA   -    MD0100PA00X+052699Y+069244X0180Y         S0      
317m0075            VIA   -    MD0100PA00X+154850Y+091569X0200Y         S0      
317m0075            VIA   -    MD0100PA00X+141728Y+091101X0200Y         S0      
327m0075            U6    -R7         A01X+133423Y+085349X0160Y         S1      
317m0075            VIA   -    MD0100PA00X+133265Y+085192X0180Y         S0      
327m0075            R6698 -1          A01X+141159Y+154653X0198Y0197R270 S1      
317m0075            VIA   -    MD0100PA00X+144310Y+152720X0200Y         S0      
327m0075            VIA   -    M      A01X+143645Y+154961X0300Y         S1      
327m0076            VIA   -    M      A01X+051878Y+075416X0300Y         S1      
317m0076            VIA   -    MD0100PA00X+052460Y+075339X0200Y         S0      
327m0076            U114  -C11        A01X+053138Y+070630X0090Y         S1      
317m0076            VIA   -    MD0100PA00X+052950Y+070262X0180Y         S0      
327m0076            R6667 -2          A01X+052432Y+075881X0198Y0197R270 S1      
327m0076            R6675 -1   M      A01X+051878Y+074944X0198Y0197R180 S1      
317m0077            VIA   -    M      A01X+051350Y+075580X0200Y         S2      
017m0077            VIA   -    M      A18X+051350Y+075580X0260Y         S2      
017m0077                  -    MD0100PA00X+051350Y+075580                       
327m0077            R6676 -1          A01X+050910Y+075886X0198Y0197R270 S1      
327m0077            R6668 -2   M      A01X+051350Y+075883X0198Y0197R270 S1      
327m0077            U114  -B10        A01X+052941Y+070827X0090Y         S1      
317m0077            VIA   -    MD0100PA00X+052670Y+070639X0193Y         S0      
317m0078            VIA   -    MD0100PA00X+154863Y+092784X0200Y         S0      
317m0078            VIA   -    MD0100PA00X+142608Y+091028X0200Y         S0      
327m0078            U6    -R5         A01X+132793Y+085349X0160Y         S1      
317m0078            VIA   -    MD0100PA00X+132636Y+085192X0180Y         S0      
327m0078            R6704 -1          A01X+141109Y+156921X0198Y0197R270 S1      
317m0078            VIA   -    MD0100PA00X+144614Y+153088X0200Y         S0      
327m0078            VIA   -    M      A01X+144460Y+156617X0300Y         S1      
327m0079            VIA   -    M      A01X+057530Y+074349X0300Y         S1      
327m0079            R6674 -1          A01X+057450Y+075031X0198Y0197R090 S1      
317m0079            VIA   -    MD0100PA00X+057378Y+074744X0200Y         S0      
327m0079            R6666 -2          A01X+057060Y+074312X0198Y0197     S1      
327m0079            U114  -E11        A01X+053138Y+070236X0090Y         S1      
317m0079            VIA   -    MD0100PA00X+052949Y+069994X0180Y         S0      
327m0080            VIA   -    M      A01X+072499Y+069062X0300Y         S1      
327m0080            R6672 -1          A01X+072026Y+069655X0198Y0197R090 S1      
317m0080            VIA   -    MD0100PA00X+072247Y+069372X0200Y         S0      
327m0080            R6664 -2          A01X+072036Y+069161X0198Y0197     S1      
327m0080            U114  -H11        A01X+053138Y+069646X0090Y         S1      
317m0080            VIA   -    MD0100PA00X+052949Y+069744X0180Y         S0      
317m0081            VIA   -    MD0100PA00X+154862Y+093160X0200Y         S0      
317m0081            VIA   -    MD0100PA00X+142906Y+090858X0200Y         S0      
327m0081            U6    -T1         A01X+131533Y+085034X0160Y         S1      
317m0081            VIA   -    MD0100PA00X+131376Y+084877X0180Y         S0      
327m0081            R6710 -1          A01X+142340Y+149854X0198Y0197     S1      
317m0081            VIA   -    M      A01X+142196Y+150281X0200Y         S2      
017m0081            VIA   -    M      A18X+142196Y+150281X0260Y         S2      
017m0081                  -    MD0100PA00X+142196Y+150281                       
327m0082            R6673 -1          A01X+056846Y+075805X0198Y0197R270 S1      
317m0082            VIA   -    M      A01X+056436Y+075798X0200Y         S2      
017m0082            VIA   -    M      A18X+056436Y+075798X0260Y         S2      
017m0082                  -    MD0100PA00X+056436Y+075798                       
327m0082            R6665 -2          A01X+056436Y+075499X0198Y0197     S1      
327m0082            U114  -E12        A01X+053335Y+070236X0090Y         S1      
317m0082            VIA   -    M      A01X+053609Y+070236X0200Y         S2      
017m0082            VIA   -    M      A18X+053609Y+070236X0260Y         S2      
017m0082                  -    MD0100PA00X+053609Y+070236                       
327m0083            VIA   -    M      A01X+142659Y+150330X0300Y    R270 S1      
327m0083            C4457 -1          A01X+142655Y+149120X0120Y0150R180 S1      
327m0083            R6707 -1   M      A01X+142655Y+149471X0198Y0197R180 S1      
327m0083            R6710 -2   M      A01X+142655Y+149854X0198Y0197     S1      
327m0083            Q247  -3          A01X+142659Y+151541X0240Y0240R180 S1      
327m0083            R6712 -1   M      A01X+141668Y+151472X0198Y0197R270 S1      
327m0084            Q246  -3          A01X+142808Y+156398X0240Y0240R090 S1      
327m0084            R6706 -1   M      A01X+141595Y+156949X0198Y0197     S1      
327m0084            VIA   -    M      A01X+141596Y+156432X0300Y    R180 S1      
327m0084            C4456 -1          A01X+140375Y+156606X0120Y0150R090 S1      
327m0084            R6701 -1   M      A01X+140726Y+156606X0198Y0197R090 S1      
327m0084            R6704 -2   M      A01X+141109Y+156606X0198Y0197R270 S1      
327m0085            Q245  -3          A01X+142845Y+154334X0240Y0240R090 S1      
327m0085            R6700 -1   M      A01X+141659Y+154822X0198Y0197     S1      
327m0085            VIA   -    M      A01X+141632Y+154338X0300Y    R180 S1      
327m0085            C4455 -1          A01X+140424Y+154338X0120Y0150R090 S1      
327m0085            R6695 -1   M      A01X+140775Y+154338X0198Y0197R090 S1      
327m0085            R6698 -2   M      A01X+141159Y+154338X0198Y0197R270 S1      
327m0086            Q245  -6          A01X+142137Y+153743X0240Y0240R090 S1      
327m0086            VIA   -    M      A01X+141640Y+153814X0300Y    R180 S1      
327m0086            Q245  -5   M      A01X+142137Y+154038X0160Y0240R090 S1      
327m0086            R6696 -1          A01X+141169Y+153956X0198Y0197R180 S1      
327m0087            VIA   -    M      A01X+141524Y+155642X0300Y         S1      
327m0087            Q246  -6   M      A01X+142100Y+155807X0240Y0240R090 S1      
327m0087            R6702 -1          A01X+141119Y+156224X0198Y0197R180 S1      
327m0087            Q246  -5          A01X+142100Y+156102X0160Y0240R090 S1      
327m0088            Q247  -6          A01X+143250Y+150833X0240Y0240R180 S1      
327m0088            VIA   -    M      A01X+143179Y+150331X0300Y    R270 S1      
327m0088            Q247  -5   M      A01X+142955Y+150833X0160Y0240R180 S1      
327m0088            R6708 -1          A01X+143037Y+149864X0198Y0197R270 S1      
317MB_3V3IO_RSVD4   VIA   -    MD0100PA00X+142959Y+152745X0200Y         S0      
327MB_3V3IO_RSVD4   VIA   -    M      A01X+142156Y+151153X0300Y    R270 S1      
327MB_3V3IO_RSVD4   R6712 -2          A01X+141668Y+151157X0198Y0197R270 S1      
327MB_3V3IO_RSVD4   Q247  -2   M      A01X+142955Y+151541X0160Y0240R180 S1      
327MB_3V3IO_RSVD4   R6709 -2   M      A01X+142951Y+152036X0198Y0197     S1      
327MB_3V3IO_RSVD4   R6711 -1   M      A01X+142952Y+152425X0198Y0197R180 S1      
317MB_3V3IO_RSVD4   J14   -I10  D0122PA00X+155626Y+158067X0282Y    R180 S3      
317MB_3V3IO_RSVD3   VIA   -    MD0100PA00X+144015Y+156309X0200Y         S0      
327MB_3V3IO_RSVD3   VIA   -    M      A01X+142382Y+156949X0300Y    R180 S1      
327MB_3V3IO_RSVD3   R6706 -2          A01X+141910Y+156949X0198Y0197     S1      
327MB_3V3IO_RSVD3   Q246  -2   M      A01X+142808Y+156102X0160Y0240R090 S1      
327MB_3V3IO_RSVD3   R6703 -2   M      A01X+143291Y+156310X0198Y0197R270 S1      
327MB_3V3IO_RSVD3   R6705 -1   M      A01X+143680Y+156309X0198Y0197R090 S1      
317MB_3V3IO_RSVD3   J14   -D9   D0122PA00X+154760Y+160705X0282Y    R180 S3      
327m0089            VIA   -    M      A01X+050883Y+076556X0300Y         S1      
327m0089            R6668 -1          A01X+051350Y+076198X0198Y0197R270 S1      
327m0089            U441  -4          A01X+051464Y+076926X0140Y0440R180 S1      
317MB_3V3IO_RSVD1   VIA   -    MD0100PA00X+144114Y+154042X0200Y         S0      
327MB_3V3IO_RSVD1   VIA   -    M      A01X+142457Y+154835X0300Y    R180 S1      
327MB_3V3IO_RSVD1   R6700 -2          A01X+141974Y+154822X0198Y0197     S1      
327MB_3V3IO_RSVD1   Q245  -2   M      A01X+142845Y+154038X0160Y0240R090 S1      
327MB_3V3IO_RSVD1   R6697 -2   M      A01X+143340Y+154042X0198Y0197R270 S1      
327MB_3V3IO_RSVD1   R6699 -1   M      A01X+143729Y+154042X0198Y0197R090 S1      
317MB_3V3IO_RSVD1   J14   -A9   D0122PA00X+154760Y+162240X0282Y    R180 S3      
327m0090            VIA   -    M      A01X+052621Y+076801X0300Y         S1      
327m0090            R6667 -1          A01X+052432Y+076196X0198Y0197R270 S1      
327m0090            U441  -6          A01X+051975Y+076926X0140Y0440R180 S1      
327m0091            VIA   -    M      A01X+056744Y+073842X0300Y         S1      
327m0091            R6666 -1          A01X+056744Y+074312X0198Y0197     S1      
327m0091            U440  -4          A01X+056183Y+074460X0140Y0440R270 S1      
327m0092            VIA   -    M      A01X+055633Y+075543X0300Y         S1      
327m0092            R6665 -1          A01X+056121Y+075499X0198Y0197     S1      
327m0092            U440  -6          A01X+056183Y+074972X0140Y0440R270 S1      
327m0093            VIA   -    M      A01X+071174Y+069161X0300Y         S1      
327m0093            R6664 -1          A01X+071721Y+069161X0198Y0197     S1      
327m0093            U439  -4          A01X+070766Y+069709X0140Y0440R270 S1      
327m0094            VIA   -    M      A01X+069927Y+070777X0300Y         S1      
327m0094            R6663 -1          A01X+070401Y+070930X0198Y0197     S1      
327m0094            U439  -6          A01X+070766Y+070221X0140Y0440R270 S1      
327m0095            VIA   -    M      A01X+048662Y+065545X0300Y         S1      
327m0095            U438  -4          A01X+048876Y+066333X0140Y0440R180 S1      
327m0095            R6662 -1          A01X+048194Y+065291X0198Y0197R180 S1      
327m0096            VIA   -    M      A01X+049926Y+066563X0300Y         S1      
327m0096            R6661 -1          A01X+050268Y+066044X0198Y0197R180 S1      
327m0096            U438  -6          A01X+049388Y+066333X0140Y0440R180 S1      
327HS_GATE2_R_4     VIA   -    M      A18X+104522Y+144460X0260Y         S2      
317HS_GATE2_R_4     VIA   -    MD0100PA00X+104840Y+144461X0200Y         S0      
327HS_GATE2_R_4     PQ6605-4          A01X+104425Y+144461X0280Y0460     S1      
327HS_GATE2_R_4     PR6611-2          A18X+104010Y+144460X0198Y0197R180 S2      
317P12V_HSC_GATE2   VIA   -    MD0100PA00X+095238Y+137559X0200Y         S0      
327P12V_HSC_GATE2   J69   -3          A01X+095897Y+137559X0240Y0950R090 S1      
317P12V_HSC_GATE2   VIA   -    MD0100PA00X+094938Y+137559X0200Y         S0      
327P12V_HSC_GATE2   VIA   -    M      A18X+095204Y+140122X0260Y         S2      
327P12V_HSC_GATE2   PC6001-2          A18X+105945Y+143850X0198Y0197R270 S2      
327P12V_HSC_GATE2   PC6002-2   M      A18X+105153Y+144559X0198Y0197R270 S2      
327P12V_HSC_GATE2   PR6611-1   M      A18X+103694Y+144460X0198Y0197R180 S2      
327P12V_HSC_GATE2   PR6610-1   M      A18X+101128Y+144451X0198Y0197R180 S2      
327P12V_HSC_GATE2   PR6609-1   M      A18X+098717Y+144424X0198Y0197R180 S2      
327P12V_HSC_GATE2   PR6608-1   M      A18X+096498Y+144447X0198Y0197R180 S2      
327m0097            PR6603-1B         A01X+101787Y+149280X0100Y0200R270 S1      
317m0097            VIA   -    M      A01X+101677Y+148983X0200Y         S2      
017m0097            VIA   -    M      A18X+101677Y+148983X0260Y         S2      
017m0097                  -    MD0100PA00X+101677Y+148983                       
317m0097            VIA   -    MD0100PA00X+093116Y+138323X0200Y    R180 S0      
327m0097            PR7154-2          A18X+092672Y+138326X0198Y0197R180 S2      
327m0097            PR7148-2          A18X+093398Y+140603X0198Y0197     S2      
317m0097            VIA   -    M      A01X+093116Y+140603X0300Y    R180 S1      
017m0097            VIA   -    M      A18X+093116Y+140603X0200Y    R180 S1      
017m0097                  -    MD0100PA00X+093116Y+140603                       
317m0098            VIA   -    M      A01X+110140Y+153170X0200Y         S2      
017m0098            VIA   -    M      A18X+110140Y+153170X0260Y         S2      
017m0098                  -    MD0100PA00X+110140Y+153170                       
327m0098            PU6601-4          A01X+109934Y+152165X0170Y0590     S1      
327m0098            PR7159-1          A18X+110138Y+151340X0198Y0197     S2      
327m0098            VIA   -    M      A18X+110140Y+151820X0260Y         S2      
327m0099            VIA   -    M      A18X+105094Y+143800X0260Y         S2      
327m0099            PC6002-1          A18X+105153Y+144244X0198Y0197R270 S2      
327m0099            PR6612-1          A18X+105552Y+143850X0198Y0197R090 S2      
317m0100            VIA   -    M      A01X+093116Y+139083X0300Y    R180 S1      
017m0100            VIA   -    M      A18X+093116Y+139083X0200Y    R180 S1      
017m0100                  -    MD0100PA00X+093116Y+139083                       
327m0100            PR7157-2          A18X+092677Y+139084X0198Y0197R180 S2      
327m0100            PR7151-2          A18X+093398Y+139843X0198Y0197     S2      
317m0100            VIA   -    MD0100PA00X+093116Y+139843X0200Y    R180 S0      
317m0100            VIA   -    MD0100PA00X+102002Y+148964X0200Y         S0      
327m0100            PR6603-2B         A01X+101787Y+148668X0100Y0200R270 S1      
327P12V_HSC_GATE1   PR6607-1          A18X+093894Y+144390X0198Y0197R180 S2      
327P12V_HSC_GATE1   VIA   -    M      A18X+095858Y+138944X0260Y         S2      
317P12V_HSC_GATE1   VIA   -     D0100PA00X+094947Y+137953X0200Y         S0      
327P12V_HSC_GATE1   J69   -4          A01X+095897Y+137953X0240Y0950R090 S1      
317P12V_HSC_GATE1   VIA   -    MD0100PA00X+095242Y+137953X0200Y         S0      
327m0101            R6640 -2          A01X+028240Y+093959X0198Y0197R090 S1      
327m0101            VIA   -    M      A01X+028808Y+093940X0300Y         S1      
327m0101            J73   -2          A01X+030797Y+093940X0500Y1350R090 S1      
327m0102            VIA   -    M      A01X+028678Y+085890X0300Y         S1      
327m0102            J70   -3          A01X+031846Y+085890X0500Y1350R090 S1      
327m0102            R6633 -2          A01X+028050Y+085879X0198Y0197R090 S1      
327m0103            VIA   -    M      A01X+028060Y+089420X0300Y         S1      
327m0103            J72   -3          A01X+023806Y+089420X0500Y1350R090 S1      
327m0103            R6637 -2          A01X+028630Y+089399X0198Y0197R090 S1      
327m0104            VIA   -    M      A01X+027950Y+090420X0300Y         S1      
327m0104            J72   -2          A01X+022657Y+090420X0500Y1350R090 S1      
327m0104            R6638 -2          A01X+028630Y+090429X0198Y0197R090 S1      
317m0105            VIA   -    M      A01X+024631Y+081900X0200Y         S2      
017m0105            VIA   -    M      A18X+024631Y+081900X0260Y         S2      
017m0105                  -    MD0100PA00X+024631Y+081900                       
327m0105            R6635 -2          A01X+024631Y+081630X0198Y0197R180 S1      
327m0105            J71   -3          A01X+023806Y+082690X0500Y1350R090 S1      
327m0106            VIA   -    M      A01X+028747Y+086890X0300Y         S1      
327m0106            J70   -2          A01X+030697Y+086890X0500Y1350R090 S1      
327m0106            R6634 -2          A01X+028050Y+086889X0198Y0197R090 S1      
327m0107            R6636 -2          A01X+024531Y+083680X0198Y0197R180 S1      
317m0107            VIA   -    M      A01X+023840Y+083690X0200Y         S2      
017m0107            VIA   -    M      A18X+023840Y+083690X0260Y         S2      
017m0107                  -    MD0100PA00X+023840Y+083690                       
327m0107            J71   -2          A01X+022657Y+083690X0500Y1350R090 S1      
327m0108            R6639 -2          A01X+028230Y+092949X0198Y0197R090 S1      
327m0108            VIA   -    M      A01X+028858Y+092940X0300Y         S1      
327m0108            J73   -3          A01X+031946Y+092940X0500Y1350R090 S1      
327m0109            VIA   -    M      A01X+156281Y+095405X0300Y         S1      
327m0109            J67   -3          A01X+156376Y+097040X0500Y1350R090 S1      
327m0109            R6613 -2          A01X+155429Y+095660X0198Y0197     S1      
327m0110            R6619 -2          A01X+164838Y+094214X0198Y0197R180 S1      
317m0110            VIA   -    M      A01X+164432Y+094212X0200Y         S2      
017m0110            VIA   -    M      A18X+164432Y+094212X0260Y         S2      
017m0110                  -    MD0100PA00X+164432Y+094212                       
327m0110            J66   -3          A01X+163458Y+094212X0500Y1350R090 S1      
327m0111            J66   -2          A01X+162308Y+095212X0500Y1350R090 S1      
317m0111            VIA   -    M      A01X+163777Y+095212X0200Y         S2      
017m0111            VIA   -    M      A18X+163777Y+095212X0260Y         S2      
017m0111                  -    MD0100PA00X+163777Y+095212                       
327m0111            R6620 -2          A01X+164078Y+095212X0198Y0197R180 S1      
327m0112            R6617 -2          A01X+164878Y+090928X0198Y0197R180 S1      
317m0112            VIA   -    M      A01X+164472Y+090926X0200Y         S2      
017m0112            VIA   -    M      A18X+164472Y+090926X0260Y         S2      
017m0112                  -    MD0100PA00X+164472Y+090926                       
327m0112            J65   -3          A01X+158478Y+090661X0500Y1350R090 S1      
327m0113            R6616 -2          A01X+164068Y+088200X0198Y0197R180 S1      
327m0113            J68   -2          A01X+162365Y+088135X0500Y1350R090 S1      
317m0113            VIA   -    M      A01X+163518Y+088676X0200Y         S2      
017m0113            VIA   -    M      A18X+163518Y+088676X0260Y         S2      
017m0113                  -    MD0100PA00X+163518Y+088676                       
327m0114            R6615 -2          A01X+164824Y+087134X0198Y0197R180 S1      
327m0114            J68   -3          A01X+163515Y+087135X0500Y1350R090 S1      
317m0114            VIA   -    M      A01X+164455Y+087135X0200Y         S2      
017m0114            VIA   -    M      A18X+164455Y+087135X0260Y         S2      
017m0114                  -    MD0100PA00X+164455Y+087135                       
327m0115            VIA   -    M      A01X+153522Y+097182X0300Y         S1      
327m0115            R6614 -2          A01X+154357Y+096974X0198Y0197R180 S1      
327m0115            J67   -2          A01X+155227Y+098040X0500Y1350R090 S1      
327m0116            R6618 -2          A01X+164102Y+091724X0198Y0197R180 S1      
317m0116            VIA   -    M      A01X+163500Y+091926X0200Y         S2      
017m0116            VIA   -    M      A18X+163500Y+091926X0260Y         S2      
017m0116                  -    MD0100PA00X+163500Y+091926                       
327m0116            J65   -2          A01X+157328Y+091661X0500Y1350R090 S1      
317m0117            VIA   -    MD0100PA00X+093767Y+148814X0200Y         S0      
327m0117            PR6001-4          A01X+094259Y+147702X0160Y0440     S1      
317m0117            VIA   -    M      A01X+094424Y+140626X0200Y         S2      
017m0117            VIA   -    M      A18X+094424Y+140626X0260Y         S2      
017m0117                  -    MD0100PA00X+094424Y+140626                       
327m0117            J69   -9          A01X+095897Y+139921X0240Y0950R090 S1      
327m0117            PR7149-2          A18X+093712Y+137588X0198Y0197R180 S2      
327m0118            VIA   -    M      A18X+098460Y+138680X0260Y         S2      
327m0118            J69   -18         A01X+097251Y+139331X0240Y0950R270 S1      
317m0118            VIA   -    MD0100PA00X+098014Y+139331X0200Y         S0      
327m0118            PR7163-1          A18X+099062Y+138520X0198Y0197R180 S2      
317P12V_HSC_ADC_P   VIA   -    MD0100PA00X+095256Y+138346X0200Y         S0      
327P12V_HSC_ADC_P   J69   -5          A01X+095897Y+138346X0240Y0950R090 S1      
317P12V_HSC_ADC_P   VIA   -    MD0100PA00X+093956Y+140223X0200Y         S0      
327P12V_HSC_ADC_P   PR7145-1   M      A18X+093713Y+140223X0198Y0197     S2      
327P12V_HSC_ADC_P   PR7148-1          A18X+093713Y+140603X0198Y0197     S2      
327P12V_HSC_ADC_P   PR7144-1          A18X+093390Y+137195X0198Y0197R180 S2      
317P12V_HSC_ADC_P   VIA   -    M      A01X+093120Y+137195X0300Y    R270 S1      
017P12V_HSC_ADC_P   VIA   -    M      A18X+093120Y+137195X0200Y    R270 S1      
017P12V_HSC_ADC_P         -    MD0100PA00X+093120Y+137195                       
327HSC_CSOUT        R6801 -1   M      A01X+103582Y+136501X0198Y0197     S1      
327HSC_CSOUT        VIA   -    M      A18X+099868Y+138992X0260Y         S2      
317HSC_CSOUT        VIA   -    MD0100PA00X+100785Y+136884X0200Y         S0      
327HSC_CSOUT        R6656 -1          A01X+103581Y+136129X0198Y0197     S1      
327HSC_CSOUT        R6648 -1   M      A01X+101092Y+136884X0198Y0197     S1      
327HSC_CSOUT        R6649 -1   M      A01X+101926Y+136655X0198Y0197R270 S1      
327HSC_CSOUT        R6647 -1   M      A18X+099062Y+139420X0198Y0197R180 S2      
327HSC_CSOUT        J69   -17         A01X+097251Y+138937X0240Y0950R270 S1      
317HSC_CSOUT        VIA   -    MD0100PA00X+098009Y+138937X0200Y         S0      
317HSC_CSOUT        VIA   -    MD0100PA00X+099050Y+132076X0200Y         S0      
327HSC_CSOUT        R6791 -1          A01X+101733Y+131659X0198Y0197R270 S1      
317m0119            VIA   -    MD0100PA00X+138316Y+099183X0200Y         S0      
317m0119            VIA   -    MD0100PA00X+105000Y+129328X0200Y         S0      
327m0119            R6715 -1          A18X+139444Y+098404X0198Y0197R180 S2      
317m0119            VIA   -    M      A01X+099928Y+137740X0200Y         S2      
017m0119            VIA   -    M      A18X+099928Y+137740X0260Y         S2      
017m0119                  -    MD0100PA00X+099928Y+137740                       
327m0119            J69   -14         A01X+097251Y+137756X0240Y0950R270 S1      
317m0119            VIA   -    MD0100PA00X+098020Y+137756X0200Y         S0      
327P12V_STBY_R1     VIA   -           A18X+093446Y+147945X0260Y         S2      
327P12V_STBY_R1     PR6001-2          A01X+094259Y+147308X1260Y0591     S1      
327P12V_STBY_R1     PQ6601-5          A01X+094161Y+145959X1850Y1811     S1      
317P12V_STBY_R1     VIA   -    MD0100PA00X+093044Y+146104X0200Y         S0      
317P12V_STBY_R1     VIA   -    MD0100PA00X+093044Y+146404X0200Y         S0      
317P12V_STBY_R1     VIA   -    MD0100PA00X+093044Y+146704X0200Y         S0      
317P12V_STBY_R1     VIA   -    MD0100PA00X+093044Y+145804X0200Y         S0      
317P12V_STBY_R1     VIA   -    MD0100PA00X+093044Y+145504X0200Y         S0      
317P12V_STBY_R1     VIA   -    MD0100PA00X+095268Y+146704X0200Y         S0      
317P12V_STBY_R1     VIA   -    MD0100PA00X+095268Y+145504X0200Y         S0      
317P12V_STBY_R1     VIA   -    MD0100PA00X+095268Y+145804X0200Y         S0      
317P12V_STBY_R1     VIA   -    MD0100PA00X+095268Y+146404X0200Y         S0      
317P12V_STBY_R1     VIA   -    MD0100PA00X+095268Y+146104X0200Y         S0      
327m0120            PR7164-1          A18X+099060Y+139827X0198Y0197R180 S2      
317m0120            VIA   -    M      A01X+098545Y+139827X0200Y         S2      
017m0120            VIA   -    M      A18X+098545Y+139827X0260Y         S2      
017m0120                  -    MD0100PA00X+098545Y+139827                       
327m0120            J69   -13         A01X+097251Y+137362X0240Y0950R270 S1      
317m0121            VIA   -    MD0100PA00X+093116Y+138703X0200Y    R180 S0      
327m0121            PR7156-2          A18X+092675Y+138704X0198Y0197R180 S2      
317m0121            VIA   -    MD0100PA00X+093116Y+139463X0200Y    R180 S0      
327m0121            PR7150-2          A18X+093398Y+139463X0198Y0197     S2      
327m0121            PR6602-2B         A01X+098008Y+148668X0100Y0200R270 S1      
317m0121            VIA   -    M      A01X+098224Y+148964X0200Y         S2      
017m0121            VIA   -    M      A18X+098224Y+148964X0260Y         S2      
017m0121                  -    MD0100PA00X+098224Y+148964                       
317m0122            VIA   -    M      A01X+093767Y+149214X0200Y         S2      
017m0122            VIA   -    M      A18X+093767Y+149214X0260Y         S2      
017m0122                  -    MD0100PA00X+093767Y+149214                       
327m0122            PR6001-3          A01X+094259Y+149828X0160Y0440     S1      
317m0122            VIA   -    MD0100PA00X+094824Y+140626X0200Y         S0      
327m0122            J69   -10         A01X+095897Y+140315X0240Y0950R090 S1      
327m0122            PR7144-2          A18X+093705Y+137195X0198Y0197R180 S2      
317P12V_HSC_ADC_N   VIA   -    MD0100PA00X+095272Y+138740X0200Y         S0      
327P12V_HSC_ADC_N   J69   -6          A01X+095897Y+138740X0240Y0950R090 S1      
317P12V_HSC_ADC_N   VIA   -    M      A01X+093956Y+139843X0300Y         S1      
017P12V_HSC_ADC_N   VIA   -    M      A18X+093956Y+139843X0200Y         S1      
017P12V_HSC_ADC_N         -    MD0100PA00X+093956Y+139843                       
327P12V_HSC_ADC_N   PR7151-1   M      A18X+093713Y+139843X0198Y0197     S2      
327P12V_HSC_ADC_N   PR7150-1          A18X+093713Y+139463X0198Y0197     S2      
327P12V_HSC_ADC_N   PR7149-1          A18X+093397Y+137588X0198Y0197R180 S2      
317P12V_HSC_ADC_N   VIA   -    MD0100PA00X+093114Y+137588X0200Y    R270 S0      
327P12V_HSC_EN      VIA   -    M      A18X+097488Y+139208X0260Y         S2      
327P12V_HSC_EN      J69   -19         A01X+097251Y+139724X0240Y0950R270 S1      
317P12V_HSC_EN      VIA   -    MD0100PA00X+098005Y+139724X0200Y         S0      
327P12V_HSC_EN      PR7162-1          A18X+099062Y+137340X0198Y0197R180 S2      
327m0123            VIA   -    M      A18X+098618Y+136768X0260Y         S2      
327m0123            PR7161-1          A18X+099062Y+136920X0198Y0197R180 S2      
317m0123            VIA   -    MD0100PA00X+098017Y+137362X0200Y         S0      
327m0123            J69   -20         A01X+097251Y+140118X0240Y0950R270 S1      
327HSC_D_OC_BIC_N   VIA   -    M      A01X+103793Y+084722X0300Y         S1      
327HSC_D_OC_BIC_N   R6646 -1          A01X+103306Y+084722X0198Y0197R180 S1      
317HSC_D_OC_BIC_N   VIA   -    MD0100PA00X+098170Y+085630X0200Y         S0      
327HSC_D_OC_BIC_N   U5    -T15        A01X+088294Y+088466X0160Y    R180 S1      
317HSC_D_OC_BIC_N   VIA   -    MD0100PA00X+088137Y+088624X0180Y    R270 S0      
317m0124            VIA   -    MD0100PA00X+105266Y+129326X0200Y         S0      
317m0124            VIA   -    MD0100PA00X+139885Y+098728X0200Y         S0      
327m0124            R6716 -1          A18X+140874Y+099286X0198Y0197R180 S2      
317m0124            VIA   -    MD0100PA00X+099740Y+138120X0200Y         S0      
327m0124            VIA   -    M      A18X+098340Y+138150X0260Y         S2      
327m0124            J69   -15         A01X+097251Y+138150X0240Y0950R270 S1      
317m0124            VIA   -    MD0100PA00X+098014Y+138150X0200Y         S0      
317m0125            VIA   -    MD0100PA00X+092026Y+138326X0200Y         S0      
327m0125            PR7153-1          A18X+092354Y+137941X0198Y0197R180 S2      
327m0125            PR7154-1   M      A18X+092357Y+138326X0198Y0197R180 S2      
317m0125            VIA   -    M      A01X+095240Y+139528X0200Y         S2      
017m0125            VIA   -    M      A18X+095240Y+139528X0260Y         S2      
017m0125                  -    MD0100PA00X+095240Y+139528                       
327m0125            J69   -8          A01X+095897Y+139528X0240Y0950R090 S1      
317m0126            VIA   -    M      A01X+092036Y+138704X0300Y         S1      
017m0126            VIA   -    M      A18X+092036Y+138704X0200Y         S1      
017m0126                  -    MD0100PA00X+092036Y+138704                       
327m0126            PR7156-1   M      A18X+092360Y+138704X0198Y0197R180 S2      
327m0126            PR7157-1          A18X+092362Y+139084X0198Y0197R180 S2      
327m0126            J69   -7          A01X+095897Y+139134X0240Y0950R090 S1      
317m0126            VIA   -    MD0100PA00X+095251Y+139134X0200Y         S0      
327m0127            R6645 -1          A01X+127675Y+084814X0198Y0197R180 S1      
317m0127            VIA   -    MD0100PA00X+128302Y+084830X0200Y         S0      
327m0127            U6    -L4         A01X+132478Y+086609X0160Y         S1      
317m0127            VIA   -    M      A01X+132320Y+086766X0180Y         S2      
017m0127            VIA   -    M      A18X+132320Y+086766X0200Y         S2      
017m0127                  -    MD0100PA00X+132320Y+086766                       
317P12V_STBY_R2     VIA   -    MD0100PA00X+102514Y+146960X0200Y         S0      
317P12V_STBY_R2     VIA   -    MD0100PA00X+100254Y+146970X0200Y         S0      
317P12V_STBY_R2     VIA   -    MD0100PA00X+097954Y+146980X0200Y         S0      
317P12V_STBY_R2     VIA   -    MD0100PA00X+095624Y+146990X0200Y         S0      
327P12V_STBY_R2     VIA   -           A18X+095795Y+148467X0260Y         S2      
327P12V_STBY_R2     PR6603-2A         A01X+101787Y+148088X1260Y2700R090 S1      
327P12V_STBY_R2     PR6602-2A         A01X+098008Y+148088X1260Y2700R090 S1      
327P12V_STBY_R2     PQ6605-5          A01X+103675Y+146006X1850Y1811     S1      
327P12V_STBY_R2     PQ6604-5          A01X+101387Y+145994X1850Y1811     S1      
327P12V_STBY_R2     PQ6603-5          A01X+099083Y+145984X1850Y1811     S1      
327P12V_STBY_R2     PQ6602-5          A01X+096777Y+145984X1850Y1811     S1      
317P12V_STBY_R2     VIA   -    MD0100PA00X+095624Y+146714X0200Y         S0      
317P12V_STBY_R2     VIA   -    MD0100PA00X+095624Y+146414X0200Y         S0      
317P12V_STBY_R2     VIA   -    MD0100PA00X+095624Y+146114X0200Y         S0      
317P12V_STBY_R2     VIA   -    MD0100PA00X+095624Y+145814X0200Y         S0      
317P12V_STBY_R2     VIA   -    MD0100PA00X+095624Y+145514X0200Y         S0      
317P12V_STBY_R2     VIA   -    MD0100PA00X+102514Y+145484X0200Y         S0      
317P12V_STBY_R2     VIA   -    MD0100PA00X+102514Y+145784X0200Y         S0      
317P12V_STBY_R2     VIA   -    MD0100PA00X+102514Y+146084X0200Y         S0      
317P12V_STBY_R2     VIA   -    MD0100PA00X+102514Y+146384X0200Y         S0      
317P12V_STBY_R2     VIA   -    MD0100PA00X+102514Y+146684X0200Y         S0      
317P12V_STBY_R2     VIA   -    MD0100PA00X+100254Y+145494X0200Y         S0      
317P12V_STBY_R2     VIA   -    MD0100PA00X+100254Y+145794X0200Y         S0      
317P12V_STBY_R2     VIA   -    MD0100PA00X+100254Y+146094X0200Y         S0      
317P12V_STBY_R2     VIA   -    MD0100PA00X+100254Y+146394X0200Y         S0      
317P12V_STBY_R2     VIA   -    MD0100PA00X+100254Y+146694X0200Y         S0      
317P12V_STBY_R2     VIA   -    MD0100PA00X+097954Y+145504X0200Y         S0      
317P12V_STBY_R2     VIA   -    MD0100PA00X+097954Y+145804X0200Y         S0      
317P12V_STBY_R2     VIA   -    MD0100PA00X+097954Y+146104X0200Y         S0      
317P12V_STBY_R2     VIA   -    MD0100PA00X+097954Y+146404X0200Y         S0      
317P12V_STBY_R2     VIA   -    MD0100PA00X+097954Y+146704X0200Y         S0      
317HSC_TYPE_ADC     VIA   -    M      A01X+098000Y+138610X0200Y         S2      
017HSC_TYPE_ADC     VIA   -    M      A18X+098000Y+138610X0260Y         S2      
017HSC_TYPE_ADC           -    MD0100PA00X+098000Y+138610                       
327HSC_TYPE_ADC     J69   -16         A01X+097251Y+138543X0240Y0950R270 S1      
327HSC_TYPE_ADC     R6713 -1          A18X+099062Y+138920X0198Y0197R180 S2      
317m0128            VIA   -    M      A01X+093116Y+137943X0300Y    R180 S1      
017m0128            VIA   -    M      A18X+093116Y+137943X0200Y    R180 S1      
017m0128                  -    MD0100PA00X+093116Y+137943                       
327m0128            PR7153-2          A18X+092669Y+137941X0198Y0197R180 S2      
317m0128            VIA   -    MD0100PA00X+093116Y+140223X0200Y    R180 S0      
327m0128            PR7145-2          A18X+093398Y+140223X0198Y0197     S2      
327m0128            PR6602-1B         A01X+098008Y+149280X0100Y0200R270 S1      
317m0128            VIA   -    MD0100PA00X+097899Y+148983X0200Y         S0      
327m0129            R6640 -1          A01X+028240Y+093644X0198Y0197R090 S1      
317m0129            VIA   -    MD0100PA00X+027874Y+093644X0200Y         S0      
327m0129            VIA   -    M      A18X+028180Y+092940X0260Y         S2      
317m0129            VIA   -    MD0100PA00X+051770Y+082660X0200Y         S0      
327m0129            R985  -1          A18X+052213Y+083103X0198Y0197R180 S2      
327m0129            U105  -6          A18X+050914Y+083047X0140Y0440R270 S2      
317m0129            VIA   -    MD0100PA00X+043060Y+079740X0200Y         S0      
327m0129            R6631 -1          A01X+041620Y+079868X0198Y0197R270 S1      
327m0130            VIA   -    M      A01X+038261Y+076450X0300Y         S1      
327m0130            R6626 -1          A01X+037746Y+076450X0198Y0197R180 S1      
327m0130            U435  -4          A01X+039078Y+077166X0110Y0340R270 S1      
327m0131            R987  -1          A18X+052217Y+083615X0198Y0197R180 S2      
327m0131            U105  -4   M      A18X+050914Y+083559X0140Y0440R270 S2      
327m0131            VIA   -    M      A18X+027540Y+089420X0260Y         S2      
317m0131            VIA   -    MD0100PA00X+027540Y+089940X0200Y         S0      
327m0131            R6638 -1          A01X+028630Y+090114X0198Y0197R090 S1      
327m0131            R6629 -1          A01X+042600Y+078938X0198Y0197R270 S1      
317m0131            VIA   -    MD0100PA00X+042120Y+078640X0200Y         S0      
327m0132            VIA   -    M      A01X+038650Y+078210X0300Y         S1      
327m0132            R6625 -2          A01X+037748Y+078640X0198Y0197     S1      
327m0132            U435  -1          A01X+039078Y+077756X0110Y0340R270 S1      
327m0133            VIA   -    M      A01X+041180Y+079090X0300Y         S1      
327m0133            R6632 -1          A01X+041210Y+079554X0198Y0197R090 S1      
327m0133            U435  -57         A01X+040732Y+078032X0110Y0340R180 S1      
327m0134            VIA   -    M      A01X+038460Y+075000X0300Y         S1      
327m0134            U435  -15         A01X+039078Y+075000X0110Y0340R270 S1      
327m0134            R6627 -2          A01X+037918Y+075000X0198Y0197     S1      
327m0135            VIA   -    M      A01X+043160Y+077756X0300Y         S1      
327m0135            R6629 -2          A01X+042600Y+078622X0198Y0197R270 S1      
327m0135            U435  -48         A01X+042582Y+077756X0110Y0340R090 S1      
327m0136            U107  -4   M      A18X+050782Y+084939X0140Y0440R270 S2      
327m0136            R999  -1          A18X+052181Y+084983X0198Y0197R180 S2      
317m0136            VIA   -    MD0100PA00X+042630Y+079740X0200Y         S0      
327m0136            VIA   -    M      A18X+027994Y+085986X0260Y         S2      
317m0136            VIA   -    MD0100PA00X+027540Y+086440X0200Y         S0      
327m0136            R6634 -1          A01X+028050Y+086574X0198Y0197R090 S1      
317m0136            VIA   -    MD0100PA00X+036585Y+077395X0200Y         S0      
327m0136            R6625 -1          A01X+037432Y+078640X0198Y0197     S1      
327m0137            VIA   -    M      A01X+038390Y+074410X0300Y         S1      
327m0137            R6628 -1          A01X+037916Y+074530X0198Y0197R180 S1      
327m0137            U435  -16         A01X+039078Y+074804X0110Y0340R270 S1      
327m0138            VIA   -    M      A01X+042040Y+079070X0300Y         S1      
327m0138            R6630 -1          A01X+042040Y+079554X0198Y0197R090 S1      
327m0138            U435  -49         A01X+042306Y+078032X0110Y0340R180 S1      
327m0139            VIA   -    M      A18X+036310Y+075000X0260Y         S2      
317m0139            VIA   -    MD0100PA00X+025210Y+083680X0200Y         S0      
327m0139            R6636 -1          A01X+024846Y+083680X0198Y0197R180 S1      
317m0139            VIA   -    MD0100PA00X+037230Y+075000X0200Y         S0      
327m0139            R6627 -1          A01X+037602Y+075000X0198Y0197     S1      
317m0139            VIA   -    MD0100PA00X+047970Y+084760X0200Y         S0      
327m0139            U107  -6   M      A18X+050782Y+084427X0140Y0440R270 S2      
327m0139            R997  -1          A18X+052217Y+084065X0198Y0197R180 S2      
327m0140            VIA   -    M      A01X+041620Y+078670X0300Y         S1      
327m0140            R6631 -2          A01X+041620Y+079552X0198Y0197R270 S1      
327m0140            U435  -56         A01X+040928Y+078032X0110Y0340R180 S1      
327m0141            U435  -63         A01X+039550Y+078032X0110Y0340R180 S1      
317m0141            VIA   -    MD0100PA01X+038902Y+079272X0200Y         S0      
317m0141            VIA   -    MD0100PA01X+093933Y+032404X0200Y         S0      
327m0141            R6724 -1   M      A01X+093829Y+033052X0180Y0200     S1      
327m0141            R6624 -1          A01X+093829Y+033052X0180Y0200R270 S1      
327m0142            U435  -62         A01X+039747Y+078032X0110Y0340R180 S1      
317m0142            VIA   -    MD0100PA01X+039242Y+079272X0200Y         S0      
317m0142            VIA   -    MD0100PA01X+094273Y+032404X0200Y         S0      
327m0142            R6723 -1   M      A01X+094379Y+033052X0180Y0200R180 S1      
327m0142            R6623 -1          A01X+094379Y+033052X0180Y0200R270 S1      
327m0143            VIA   -    M      A01X+175788Y+087921X0300Y         S1      
327m0143            R6610 -1          A01X+175318Y+087920X0198Y0197R180 S1      
327m0143            U434  -16         A01X+176348Y+088064X0110Y0340R270 S1      
327m0144            VIA   -    M      A01X+180460Y+091018X0300Y         S1      
327m0144            R6607 -2          A01X+180970Y+091018X0198Y0197R090 S1      
327m0144            U434  -48         A01X+179852Y+091016X0110Y0340R090 S1      
327m0145            R6621 -2          A01X+037471Y+079019X0198Y0197R270 S1      
327m0145            R6622 -1   M      A01X+037847Y+079019X0198Y0197R090 S1      
327m0145            VIA   -    M      A01X+038320Y+079022X0300Y         S1      
327m0145            U435  -64         A01X+039354Y+078032X0110Y0340R180 S1      
327m0146            VIA   -    M      A01X+178977Y+091895X0300Y         S1      
327m0146            R6608 -2          A01X+179347Y+092441X0198Y0197R270 S1      
327m0146            U434  -56         A01X+178198Y+091292X0110Y0340R180 S1      
327m0147            VIA   -    M      A01X+179576Y+091870X0300Y         S1      
327m0147            U434  -49         A01X+179576Y+091292X0110Y0340R180 S1      
327m0147            R6611 -1          A01X+179737Y+092437X0198Y0197R090 S1      
327m0148            R6602 -2   M      A01X+175728Y+093110X0198Y0197     S1      
327m0148            R6601 -1          A01X+175728Y+093510X0198Y0197R180 S1      
327m0148            VIA   -    M      A01X+175728Y+092620X0300Y         S1      
327m0148            U434  -64         A01X+176624Y+091292X0110Y0340R180 S1      
327m0149            VIA   -    M      A01X+178236Y+091915X0300Y         S1      
327m0149            R6612 -1          A01X+178954Y+092450X0198Y0197R090 S1      
327m0149            U434  -57         A01X+178002Y+091292X0110Y0340R180 S1      
327m0150            U434  -62         A01X+177017Y+091292X0110Y0340R180 S1      
317m0150            VIA   -    MD0100PA00X+176906Y+092372X0200Y         S0      
327m0150            VIA   -    M      A01X+091846Y+031774X0160Y0041R270 S1      
327m0150            R6603 -1   M      A01X+092075Y+032330X0180Y0200R270 S1      
317m0150            VIA   -    MD0100PA00X+093700Y+031568X0200Y         S0      
327m0150            R6726 -1          A01X+092075Y+032330X0180Y0200R180 S1      
327m0151            VIA   -    M      A01X+175791Y+088467X0300Y         S1      
327m0151            U434  -15         A01X+176348Y+088260X0110Y0340R270 S1      
327m0151            R6606 -2          A01X+175318Y+088465X0198Y0197     S1      
327m0152            VIA   -    M      A01X+175793Y+089726X0300Y         S1      
327m0152            R6609 -1          A01X+175324Y+089728X0198Y0197R180 S1      
327m0152            U434  -4          A01X+176348Y+090426X0110Y0340R270 S1      
327m0153            VIA   -    M      A01X+175780Y+091334X0300Y         S1      
327m0153            R6605 -2          A01X+175242Y+091545X0198Y0197     S1      
327m0153            U434  -1          A01X+176348Y+091016X0110Y0340R270 S1      
327m0154            U434  -63         A01X+176820Y+091292X0110Y0340R180 S1      
317m0154            VIA   -    MD0100PA00X+176566Y+092372X0200Y         S0      
327m0154            VIA   -    M      A01X+093108Y+031344X0160Y0041R180 S1      
327m0154            R6604 -1   M      A01X+091524Y+032330X0180Y0200R270 S1      
317m0154            VIA   -    MD0100PA00X+093700Y+031228X0200Y         S0      
327m0154            R6725 -1          A01X+091524Y+032330X0180Y0200     S1      
327m0155            PU1   -26         A01X+080499Y+144378X0090Y0150     S1      
327m0155            R6600 -2          A01X+080327Y+143656X0198Y0197R180 S1      
317m0155            VIA   -    M      A01X+080557Y+144152X0200Y    R270 S2      
017m0155            VIA   -    M      A18X+080557Y+144152X0260Y    R270 S2      
017m0155                  -    MD0100PA00X+080557Y+144152                       
327m0156            PR6618-1          A18X+109186Y+153726X0198Y0197     S2      
317m0156            VIA   -    M      A01X+109678Y+153540X0200Y         S2      
017m0156            VIA   -    M      A18X+109678Y+153540X0260Y         S2      
017m0156                  -    MD0100PA00X+109678Y+153540                       
327m0156            PU6601-6          A01X+109678Y+154015X0170Y0590     S1      
327m0157            PR6617-1          A01X+098705Y+110030X0198Y0197R180 S1      
317m0157            VIA   -    MD0100PA00X+098951Y+109768X0200Y         S0      
317m0157            VIA   -    MD0100PA00X+091114Y+134556X0200Y         S0      
327m0157            PU6601-7          A01X+109422Y+154015X0170Y0590     S1      
317m0157            VIA   -    M      A01X+109862Y+154618X0200Y         S2      
017m0157            VIA   -    M      A18X+109862Y+154618X0260Y         S2      
017m0157                  -    MD0100PA00X+109862Y+154618                       
327m0158            PU6601-8          A01X+109166Y+154015X0170Y0590     S1      
317m0158            VIA   -    M      A01X+109152Y+154630X0200Y    R180 S2      
017m0158            VIA   -    M      A18X+109152Y+154630X0260Y    R180 S2      
017m0158                  -    MD0100PA00X+109152Y+154630                       
327m0158            PR6616-1          A01X+098701Y+110462X0198Y0197R180 S1      
317m0158            VIA   -    MD0100PA00X+098664Y+110846X0200Y         S0      
317m0158            VIA   -    MD0100PA00X+091403Y+134561X0200Y         S0      
327m0159            PR6615-2          A01X+106141Y+145649X0198Y0197     S1      
317m0159            VIA   -    M      A01X+106886Y+145131X0200Y         S2      
017m0159            VIA   -    M      A18X+106886Y+145131X0260Y         S2      
017m0159                  -    MD0100PA00X+106886Y+145131                       
327m0159            PC6603-2          A18X+109550Y+152100X0280Y0320R270 S2      
317m0159            VIA   -    M      A01X+109678Y+152670X0200Y         S2      
017m0159            VIA   -    M      A18X+109678Y+152670X0260Y         S2      
017m0159                  -    MD0100PA00X+109678Y+152670                       
327m0159            PU6601-3          A01X+109678Y+152165X0170Y0590     S1      
327m0160            PR6614-2          A01X+106626Y+144554X0198Y0197R090 S1      
317m0160            VIA   -    M      A01X+106964Y+144554X0200Y         S2      
017m0160            VIA   -    M      A18X+106964Y+144554X0260Y         S2      
017m0160                  -    MD0100PA00X+106964Y+144554                       
327m0160            PC6603-1          A18X+108970Y+152100X0280Y0320R270 S2      
317m0160            VIA   -    M      A01X+109153Y+152872X0200Y         S2      
017m0160            VIA   -    M      A18X+109153Y+152872X0260Y         S2      
017m0160                  -    MD0100PA00X+109153Y+152872                       
327m0160            PU6601-2          A01X+109422Y+152165X0170Y0590     S1      
327m0161            VIA   -    M      A01X+105319Y+145649X0300Y    R180 S1      
327m0161            PQ6606-E          A01X+105319Y+145090X0320Y0360     S1      
327m0161            PR6615-1          A01X+105826Y+145649X0198Y0197     S1      
327m0162            VIA   -    M      A01X+106205Y+143793X0300Y         S1      
327m0162            PR6614-1          A01X+106626Y+144239X0198Y0197R090 S1      
327m0162            PQ6606-C   M      A01X+105693Y+144302X0320Y0360     S1      
327m0162            PQ6606-B          A01X+106067Y+145090X0320Y0360     S1      
327HS_GATE2_R_1     VIA   -    M      A18X+097381Y+144439X0260Y         S2      
327HS_GATE2_R_1     PR6608-2          A18X+096813Y+144447X0198Y0197R180 S2      
317HS_GATE2_R_1     VIA   -    MD0100PA00X+097893Y+144439X0200Y         S0      
327HS_GATE2_R_1     PQ6602-4          A01X+097527Y+144439X0280Y0460     S1      
327HS_GATE1_R_1     VIA   -    M      A18X+094741Y+144390X0260Y         S2      
327HS_GATE1_R_1     PR6607-2          A18X+094209Y+144390X0198Y0197R180 S2      
317HS_GATE1_R_1     VIA   -    MD0100PA00X+095270Y+144414X0200Y         S0      
327HS_GATE1_R_1     PQ6601-4          A01X+094911Y+144414X0280Y0460     S1      
327HS_GATE2_R_3     VIA   -    M      A18X+102020Y+144449X0260Y         S2      
327HS_GATE2_R_3     PR6610-2          A18X+101443Y+144451X0198Y0197R180 S2      
317HS_GATE2_R_3     VIA   -    MD0100PA00X+102562Y+144449X0200Y         S0      
327HS_GATE2_R_3     PQ6604-4          A01X+102137Y+144449X0280Y0460     S1      
327HS_GATE2_R_2     VIA   -    M      A18X+099499Y+144424X0260Y         S2      
327HS_GATE2_R_2     PR6609-2          A18X+099032Y+144424X0198Y0197R180 S2      
317HS_GATE2_R_2     VIA   -    MD0100PA00X+100219Y+144439X0200Y         S0      
327HS_GATE2_R_2     PQ6603-4          A01X+099833Y+144439X0280Y0460     S1      
327P0V8_PEX2_SVID   PR7143-2          A18X+140743Y+102827X0198Y0197     S2      
327P0V8_PEX2_SVID   VIA   -    M      A18X+140281Y+102418X0260Y         S2      
327P0V8_PEX2_SVID   PR7142-2   M      A18X+140743Y+102425X0198Y0197     S2      
327P0V8_PEX2_SVID   PU11  -17         A01X+139912Y+101966X0070Y0240R090 S1      
327P0V8_PEX2_SVID   PU11  -18         A01X+139912Y+102124X0070Y0240R090 S1      
317P0V8_PEX2_SVID   VIA   -    MD0100PA00X+140222Y+102044X0200Y         S0      
327P0V8_PEX0_SVID   PR7141-2          A18X+049335Y+102816X0198Y0197     S2      
327P0V8_PEX0_SVID   PR7140-2   M      A18X+049336Y+102416X0198Y0197     S2      
327P0V8_PEX0_SVID   VIA   -    M      A18X+048879Y+102408X0260Y         S2      
327P0V8_PEX0_SVID   PU6   -17         A01X+048494Y+101966X0070Y0240R090 S1      
327P0V8_PEX0_SVID   PU6   -18         A01X+048494Y+102124X0070Y0240R090 S1      
317P0V8_PEX0_SVID   VIA   -    MD0100PA00X+048804Y+102044X0200Y         S0      
327m0163            VIA   -           A18X+094338Y+083540X0260Y         S2      
327m0163            R6591 -2          A01X+095820Y+084168X0198Y0197R090 S1      
327m0163            R6592 -1   M      A01X+094720Y+084168X0198Y0197R270 S1      
327m0163            C4435 -1   M      A01X+095110Y+084168X0198Y0197R270 S1      
317m0163            VIA   -    MD0100PA00X+093720Y+084100X0200Y         S0      
317m0163            VIA   -    MD0100PA00X+092546Y+084529X0180Y         S0      
327m0163            U5    -D2         A01X+092389Y+084687X0160Y    R180 S1      
327m0164            VIA   -    M      A18X+138629Y+083650X0260Y         S2      
327m0164            R6588 -1          A01X+180512Y+098506X0198Y0197R180 S1      
317m0164            VIA   -    MD0100PA00X+180801Y+098483X0200Y    R270 S0      
317m0164            VIA   -    MD0100PA00X+147668Y+082763X0200Y         S0      
317m0164            VIA   -    MD0100PA00X+137675Y+083932X0180Y         S0      
327m0164            U6    -W20        A01X+137517Y+084089X0160Y         S1      
317m0164            VIA   -    MD0100PA00X+139987Y+084511X0200Y         S0      
327m0165            R6582 -1          A01X+103048Y+095422X0198Y0197R180 S1      
317m0165            VIA   -    MD0100PA00X+103337Y+095399X0200Y         S0      
327m0165            VIA   -    M      A01X+127982Y+096892X0300Y         S1      
327m0165            U6    -AA22       A01X+138147Y+083460X0160Y         S1      
317m0165            VIA   -    MD0100PA00X+139596Y+083270X0200Y         S0      
317m0165            VIA   -    MD0100PA00X+129079Y+096136X0200Y         S0      
327m0166            R6576 -1          A01X+058886Y+095721X0198Y0197R180 S1      
317m0166            VIA   -    M      A01X+059175Y+095698X0200Y         S2      
017m0166            VIA   -    M      A18X+059175Y+095698X0260Y         S2      
017m0166                  -    MD0100PA00X+059175Y+095698                       
327m0166            U6    -U20        A01X+137517Y+084719X0160Y         S1      
317m0166            VIA   -    MD0100PA00X+137675Y+084562X0180Y         S0      
317m0166            VIA   -    MD0100PA00X+101349Y+075077X0200Y         S0      
317m0166            VIA   -    MD0100PA00X+096613Y+077638X0200Y         S0      
327m0167            R6576 -2          A01X+058571Y+095721X0198Y0197R180 S1      
327m0167            U431  -5          A01X+058571Y+095164X0110Y0360R270 S1      
327m0167            R6575 -2          A18X+058098Y+096180X0198Y0197R180 S2      
317m0167            VIA   -    M      A01X+058610Y+096181X0200Y    R270 S2      
017m0167            VIA   -    M      A18X+058610Y+096181X0260Y    R270 S2      
017m0167                  -    MD0100PA00X+058610Y+096181                       
327m0168            VIA   -           A01X+059687Y+094965X0300Y         S1      
327m0168            R6573 -2          A01X+059210Y+094538X0198Y0197R090 S1      
327m0168            R6574 -1   M      A01X+059210Y+094965X0198Y0197R090 S1      
327m0168            U431  -4          A01X+058571Y+094967X0110Y0360R090 S1      
327m0169            R6572 -2          A01X+057323Y+096181X0198Y0197R180 S1      
327m0169            U431  -6          A01X+057350Y+095164X0110Y0360R270 S1      
327m0169            R6571 -2          A18X+056610Y+095623X0198Y0197R090 S2      
317m0169            VIA   -    M      A01X+057060Y+095721X0200Y         S2      
017m0169            VIA   -    M      A18X+057060Y+095721X0260Y         S2      
017m0169                  -    MD0100PA00X+057060Y+095721                       
327m0169            C4423 -1          A01X+057323Y+095721X0198Y0197     S1      
327m0170            VIA   -           A01X+007769Y+084736X0300Y         S1      
327m0170            R6566 -2          A01X+007505Y+083129X0198Y0197R090 S1      
327m0170            R6567 -1   M      A01X+007505Y+083556X0198Y0197R090 S1      
327m0170            U430  -4          A01X+006865Y+083558X0110Y0360R090 S1      
327m0171            R6569 -2          A01X+006866Y+084312X0198Y0197R180 S1      
327m0171            U430  -5          A01X+006865Y+083755X0110Y0360R270 S1      
327m0171            R6568 -2          A18X+006372Y+084763X0198Y0197R180 S2      
317m0171            VIA   -    MD0100PA00X+006905Y+084772X0200Y    R270 S2      
327m0172            R6570 -2          A01X+005617Y+084772X0198Y0197R180 S1      
327m0172            U430  -6          A01X+005645Y+083755X0110Y0360R270 S1      
327m0172            R6565 -2          A18X+004905Y+084214X0198Y0197R090 S2      
317m0172            VIA   -    M      A01X+005355Y+084312X0200Y         S2      
017m0172            VIA   -    M      A18X+005355Y+084312X0260Y         S2      
017m0172                  -    MD0100PA00X+005355Y+084312                       
327m0172            C4418 -1          A01X+005617Y+084312X0198Y0197     S1      
327m0173            R6594 -2   M      A01X+093940Y+089122X0198Y0197     S1      
327m0173            R6596 -1   M      A01X+093945Y+088751X0198Y0197R180 S1      
317m0173            VIA   -    M      A01X+094219Y+089122X0200Y         S2      
017m0173            VIA   -    M      A18X+094219Y+089122X0260Y         S2      
017m0173                  -    MD0100PA00X+094219Y+089122                       
327m0173            C4437 -1          A01X+093944Y+088379X0198Y0197R180 S1      
317m0173            VIA   -    M      A01X+093873Y+087440X0300Y         S1      
017m0173            VIA   -    M      A18X+093873Y+087440X0200Y         S1      
017m0173                  -    MD0100PA00X+093873Y+087440                       
327m0173            U5    -H1         A01X+092704Y+085946X0160Y    R180 S1      
327m0174            R6593 -2          A01X+094052Y+089503X0198Y0197R270 S1      
327m0174            R6595 -1   M      A01X+093272Y+089503X0198Y0197R090 S1      
317m0174            VIA   -    M      A01X+092918Y+089503X0200Y         S2      
017m0174            VIA   -    M      A18X+092918Y+089503X0260Y         S2      
017m0174                  -    MD0100PA00X+092918Y+089503                       
327m0174            C4436 -1   M      A01X+093662Y+089503X0198Y0197R090 S1      
317m0174            VIA   -    MD0100PA00X+092546Y+085789X0180Y         S0      
327m0174            U5    -H2         A01X+092389Y+085946X0160Y    R180 S1      
327m0175            R6589 -2          A01X+095790Y+085042X0198Y0197R270 S1      
327m0175            R6590 -1   M      A01X+095400Y+085042X0198Y0197R090 S1      
327m0175            VIA   -    M      A01X+094510Y+085240X0300Y         S1      
327m0175            C4434 -1   M      A01X+095010Y+085042X0198Y0197R090 S1      
327m0175            U5    -D1         A01X+092704Y+084687X0160Y    R180 S1      
327m0176            R6588 -2          A01X+180197Y+098506X0198Y0197R180 S1      
327m0176            U433  -5          A01X+180197Y+097949X0110Y0360R270 S1      
327m0176            R6587 -2          A18X+180186Y+098506X0198Y0197     S2      
317m0176            VIA   -    M      A01X+180236Y+098966X0200Y    R270 S2      
017m0176            VIA   -    M      A18X+180236Y+098966X0260Y    R270 S2      
017m0176                  -    MD0100PA00X+180236Y+098966                       
327m0177            R6582 -2          A01X+102733Y+095422X0198Y0197R180 S1      
327m0177            U432  -5          A01X+102732Y+094866X0110Y0360R270 S1      
327m0177            R6581 -2          A18X+102722Y+095422X0198Y0197     S2      
317m0177            VIA   -    M      A01X+102772Y+095882X0200Y    R270 S2      
017m0177            VIA   -    M      A18X+102772Y+095882X0260Y    R270 S2      
017m0177                  -    MD0100PA00X+102772Y+095882                       
327m0178            R6584 -2          A01X+178949Y+098966X0198Y0197R180 S1      
327m0178            U433  -6          A01X+178976Y+097949X0110Y0360R270 S1      
317m0178            VIA   -    M      A01X+178686Y+098506X0200Y         S2      
017m0178            VIA   -    M      A18X+178686Y+098506X0260Y         S2      
017m0178                  -    MD0100PA00X+178686Y+098506                       
327m0178            R6583 -2          A18X+178940Y+098959X0198Y0197     S2      
327m0178            C4433 -1          A01X+178949Y+098506X0198Y0197     S1      
327m0179            VIA   -           A01X+181311Y+097324X0300Y         S1      
327m0179            R6585 -2   M      A01X+180836Y+097324X0198Y0197R090 S1      
327m0179            R6586 -1          A01X+180836Y+097750X0198Y0197R090 S1      
327m0179            U433  -4          A01X+180197Y+097752X0110Y0360R090 S1      
327m0180            R6569 -1          A01X+007181Y+084312X0198Y0197R180 S1      
317m0180            VIA   -    MD0100PA00X+069045Y+081441X0200Y         S0      
317m0180            VIA   -    M      A01X+007470Y+084289X0200Y         S2      
017m0180            VIA   -    M      A18X+007470Y+084289X0260Y         S2      
017m0180                  -    MD0100PA00X+007470Y+084289                       
327m0180            U6    -W22        A01X+138147Y+084089X0160Y         S1      
317m0180            VIA   -    MD0100PA00X+138305Y+083932X0180Y         S0      
317m0180            VIA   -    MD0100PA00X+081355Y+081400X0200Y         S0      
327m0181            R6578 -2          A01X+101484Y+095882X0198Y0197R180 S1      
327m0181            U432  -6          A01X+101512Y+094866X0110Y0360R270 S1      
327m0181            R6577 -2          A18X+100772Y+095325X0198Y0197R090 S2      
317m0181            VIA   -    M      A01X+101222Y+095422X0200Y         S2      
017m0181            VIA   -    M      A18X+101222Y+095422X0260Y         S2      
017m0181                  -    MD0100PA00X+101222Y+095422                       
327m0181            C4428 -1          A01X+101484Y+095422X0198Y0197     S1      
327m0182            VIA   -           A01X+103843Y+094666X0300Y         S1      
327m0182            R6579 -2          A01X+103372Y+094240X0198Y0197R090 S1      
327m0182            R6580 -1   M      A01X+103372Y+094666X0198Y0197R090 S1      
327m0182            U432  -4          A01X+102732Y+094669X0110Y0360R090 S1      
327P12V_STBY_FUSE   PD1   -C          A01X+098965Y+155627X0950Y1300     S1      
327P12V_STBY_FUSE   FS1   -2          A01X+097169Y+155504X1280Y1350     S1      
317P12V_STBY_FUSE   VIA   -    MD0100PA00X+098077Y+154608X0200Y         S0      
317P12V_STBY_FUSE   VIA   -    MD0100PA00X+098377Y+154608X0200Y         S0      
317P12V_STBY_FUSE   VIA   -    MD0100PA00X+098677Y+154608X0200Y         S0      
317P12V_STBY_FUSE   VIA   -    MD0100PA00X+097155Y+154608X0200Y         S0      
317P12V_STBY_FUSE   VIA   -    MD0100PA00X+097455Y+154608X0200Y         S0      
317P12V_STBY_FUSE   VIA   -    MD0100PA00X+097755Y+154608X0200Y         S0      
327P12V_STBY_FUSE   VIA   -    M      A18X+110720Y+143891X0260Y         S2      
327P12V_STBY_FUSE   VIA   -    M      A18X+079933Y+141676X0260Y         S2      
327P12V_STBY_FUSE   R494  -1          A18X+080304Y+142515X0198Y0197R180 S2      
327m0183            VIA   -    M      A01X+085990Y+100869X0300Y         S1      
327m0183            C4300 -1          A01X+085924Y+099233X0400Y0500R090 S1      
327m0183            R6503 -2          A01X+085788Y+101408X0198Y0197R270 S1      
327m0184            VIA   -    M      A01X+090448Y+101100X0300Y         S1      
327m0184            R6502 -2          A01X+090222Y+101565X0198Y0197R270 S1      
327m0184            C4299 -1          A01X+090072Y+100363X0280Y0320R180 S1      
327m0185            VIA   -    M      A01X+089422Y+100925X0300Y         S1      
327m0185            R6500 -2          A01X+089361Y+101422X0198Y0197R270 S1      
327m0185            C4297 -1          A01X+089107Y+100363X0280Y0320R180 S1      
327m0186            R6476 -2          A18X+050573Y+126856X0198Y0197R270 S2      
327m0186            VIA   -    M      A18X+050603Y+127354X0260Y         S2      
327m0186            C4255 -1          A18X+050603Y+127904X0280Y0320     S2      
327m0187            VIA   -    M      A01X+091135Y+101214X0300Y         S1      
327m0187            R6495 -2          A01X+090626Y+101571X0198Y0197R270 S1      
327m0187            C4286 -1          A01X+090795Y+100529X0400Y0500R090 S1      
327m0188            R6484 -2          A18X+047259Y+126688X0198Y0197R270 S2      
327m0188            VIA   -    M      A18X+047262Y+127181X0260Y         S2      
327m0188            C4269 -1          A18X+047259Y+127736X0280Y0320     S2      
327m0189            VIA   -    M      A01X+086051Y+100069X0300Y         S1      
327m0189            C4301 -1          A01X+086614Y+099233X0400Y0500R090 S1      
327m0189            R6504 -2          A01X+086401Y+101408X0198Y0197R270 S1      
327m0190            VIA   -    M      A01X+087909Y+100911X0300Y         S1      
327m0190            R6493 -2          A01X+088145Y+101408X0198Y0197R270 S1      
327m0190            C4284 -1          A01X+087628Y+100363X0280Y0320R180 S1      
327m0191            VIA   -    M      A01X+086893Y+100927X0300Y         S1      
327m0191            R6491 -2          A01X+087040Y+101408X0198Y0197R270 S1      
327m0191            C4282 -1          A01X+086645Y+100363X0280Y0320R180 S1      
327m0192            VIA   -    M      A18X+051188Y+127208X0260Y         S2      
327m0192            R6488 -2          A18X+051913Y+126864X0198Y0197R270 S2      
327m0192            C4273 -1          A18X+051188Y+127784X0280Y0320     S2      
327m0193            R6477 -2          A18X+050030Y+126856X0198Y0197R270 S2      
327m0193            VIA   -    M      A18X+050033Y+127316X0260Y         S2      
327m0193            C4256 -1          A18X+050030Y+127904X0280Y0320     S2      
327m0194            R6486 -2          A18X+048350Y+126688X0198Y0197R270 S2      
327m0194            VIA   -    M      A18X+048354Y+127170X0260Y         S2      
327m0194            C4271 -1          A18X+048350Y+127736X0280Y0320     S2      
327m0195            VIA   -    M      A18X+052571Y+127299X0200Y         S2      
327m0195            C4259 -1          A18X+052276Y+127784X0280Y0320     S2      
327m0195            R6480 -2          A18X+052672Y+126868X0198Y0197R270 S2      
327m0196            R6483 -2          A18X+046698Y+126691X0198Y0197R270 S2      
327m0196            VIA   -    M      A18X+046701Y+127191X0260Y         S2      
327m0196            C4268 -1          A18X+046697Y+127736X0280Y0320     S2      
327m0197            R6478 -2          A18X+048912Y+126688X0198Y0197R270 S2      
327m0197            VIA   -    M      A18X+048915Y+127159X0260Y         S2      
327m0197            C4257 -1          A18X+048912Y+127736X0280Y0320     S2      
327m0198            VIA   -    M      A01X+089931Y+100920X0300Y         S1      
327m0198            R6501 -2          A01X+089805Y+101416X0198Y0197R270 S1      
327m0198            C4298 -1          A01X+089599Y+100363X0280Y0320R180 S1      
327m0199            VIA   -    M      A18X+051858Y+127300X0200Y         S2      
327m0199            C4272 -1          A18X+051733Y+127784X0280Y0320     S2      
327m0199            R6487 -2          A18X+052294Y+126864X0198Y0197R270 S2      
327m0200            VIA   -    M      A18X+053281Y+127317X0260Y         S2      
327m0200            C4258 -1          A18X+052814Y+127784X0280Y0320     S2      
327m0200            R6479 -2          A18X+053045Y+126871X0198Y0197R270 S2      
327m0201            R6475 -2          A18X+049490Y+126856X0198Y0197R270 S2      
327m0201            VIA   -    M      A18X+049490Y+127308X0260Y         S2      
327m0201            C4254 -1          A18X+049490Y+127904X0280Y0320     S2      
327m0202            VIA   -    M      A01X+087400Y+100940X0300Y         S1      
327m0202            R6492 -2          A01X+087595Y+101408X0198Y0197R270 S1      
327m0202            C4283 -1          A01X+087139Y+100363X0280Y0320R180 S1      
327m0203            VIA   -    M      A01X+088920Y+100918X0300Y         S1      
327m0203            R6499 -2          A01X+088909Y+101408X0198Y0197R270 S1      
327m0203            C4296 -1          A01X+088622Y+100363X0280Y0320R180 S1      
327m0204            VIA   -    M      A01X+085277Y+100103X0300Y         S1      
327m0204            C4287 -1          A01X+085212Y+099233X0400Y0500R090 S1      
327m0204            R6496 -2          A01X+085249Y+101408X0198Y0197R270 S1      
327m0205            R6485 -2          A18X+047810Y+126688X0198Y0197R270 S2      
327m0205            VIA   -    M      A18X+047813Y+127181X0260Y         S2      
327m0205            C4270 -1          A18X+047810Y+127736X0280Y0320     S2      
327m0206            VIA   -    M      A01X+088411Y+100926X0300Y         S1      
327m0206            R6494 -2          A01X+088521Y+101408X0198Y0197R270 S1      
327m0206            C4285 -1          A01X+088128Y+100363X0280Y0320R180 S1      
327m0207            VIA   -    M      A18X+137303Y+127857X0260Y         S2      
327m0207            C4313 -1          A18X+137303Y+128424X0280Y0320     S2      
327m0207            R6508 -2          A18X+137215Y+127381X0198Y0197R270 S2      
327m0208            C4343 -1          A01X+094828Y+100344X0400Y0500R090 S1      
327m0208            VIA   -    M      A01X+095039Y+100935X0300Y         S1      
327m0208            R6526 -2          A01X+095099Y+101408X0198Y0197R270 S1      
327m0209            VIA   -           A18X+130680Y+127954X0260Y         S2      
327m0209            C4328 -1   M      A18X+131462Y+128021X0280Y0320     S2      
327m0209            R6517 -2          A18X+131460Y+127384X0198Y0197R270 S2      
327m0210            VIA   -    M      A01X+094517Y+100919X0300Y         S1      
327m0210            C4341 -1          A01X+094226Y+100363X0280Y0320R180 S1      
327m0210            R6524 -2          A01X+094543Y+101408X0198Y0197R270 S1      
327m0211            VIA   -    M      A01X+096084Y+100894X0300Y         S1      
327m0211            C4353 -1          A01X+096111Y+100328X0280Y0320R180 S1      
327m0211            R6530 -2          A01X+096382Y+101416X0198Y0197R270 S1      
327m0212            VIA   -    M      A18X+135686Y+127886X0260Y         S2      
327m0212            C4312 -1          A18X+135687Y+128429X0280Y0320     S2      
327m0212            R6507 -2          A18X+135686Y+127384X0198Y0197R270 S2      
327m0213            VIA   -    M      A18X+136783Y+127886X0260Y         S2      
327m0213            C4324 -1          A18X+136768Y+128429X0280Y0320     S2      
327m0213            R6513 -2          A18X+136783Y+127384X0198Y0197R270 S2      
327m0214            VIA   -    M      A01X+092358Y+100929X0300Y         S1      
327m0214            C4355 -1          A01X+092048Y+100363X0280Y0320R180 S1      
327m0214            R6532 -2          A01X+092186Y+101408X0198Y0197R270 S1      
327m0215            VIA   -    M      A01X+092907Y+100910X0300Y         S1      
327m0215            C4338 -1          A01X+092597Y+100363X0280Y0320R180 S1      
327m0215            R6521 -2          A01X+092798Y+101408X0198Y0197R270 S1      
327m0216            C4357 -1          A01X+097913Y+100426X0400Y0500R090 S1      
327m0216            VIA   -    M      A01X+098002Y+100999X0300Y         S1      
327m0216            R6534 -2          A01X+097566Y+101435X0198Y0197R270 S1      
327m0217            VIA   -    M      A18X+132890Y+127884X0260Y         S2      
327m0217            C4326 -1          A18X+132544Y+128429X0280Y0320     S2      
327m0217            R6515 -2          A18X+132548Y+127384X0198Y0197R270 S2      
327m0218            C4213 -1          A18X+044621Y+127726X0280Y0320     S2      
327m0218            VIA   -    M      A18X+044625Y+127178X0260Y         S2      
327m0218            R6456 -2          A18X+044625Y+126682X0198Y0197R270 S2      
327m0219            VIA   -    M      A01X+091850Y+100940X0300Y         S1      
327m0219            C4339 -1          A01X+091375Y+100463X0280Y0320R180 S1      
327m0219            R6522 -2          A01X+091646Y+101408X0198Y0197R270 S1      
327m0220            C4212 -1          A18X+045134Y+127732X0280Y0320     S2      
327m0220            VIA   -    M      A18X+045138Y+127184X0260Y         S2      
327m0220            R6455 -2          A18X+045138Y+126687X0198Y0197R270 S2      
327m0221            VIA   -    M      A01X+093997Y+100918X0300Y         S1      
327m0221            C4340 -1          A01X+093687Y+100363X0280Y0320R180 S1      
327m0221            R6523 -2          A01X+093993Y+101408X0198Y0197R270 S1      
327m0222            VIA   -    M      A18X+042083Y+127366X0260Y         S2      
327m0222            C4215 -1          A18X+042587Y+127721X0280Y0320     S2      
327m0222            R6458 -2          A18X+042577Y+126855X0198Y0197R270 S2      
327m0223            VIA   -    M      A18X+133694Y+127838X0260Y         S2      
327m0223            C4311 -1          A18X+133587Y+128429X0280Y0320     S2      
327m0223            R6506 -2          A18X+133594Y+127384X0198Y0197R270 S2      
327m0224            C4216 -1          A01X+045559Y+126017X0280Y0320     S1      
327m0224            R6459 -2          A01X+045562Y+125557X0198Y0197R090 S1      
327m0225            VIA   -    M      A18X+133291Y+127857X0260Y         S2      
327m0225            C4329 -1          A18X+133059Y+128429X0280Y0320     S2      
327m0225            R6518 -2          A18X+133058Y+127384X0198Y0197R270 S2      
327m0226            C4217 -1          A01X+046110Y+126017X0280Y0320     S1      
327m0226            R6460 -2          A01X+046057Y+125557X0198Y0197R090 S1      
327m0227            VIA   -    M      A18X+135167Y+127870X0260Y         S2      
327m0227            C4315 -1          A18X+135167Y+128429X0280Y0320     S2      
327m0227            R6510 -2          A18X+135167Y+127384X0198Y0197R270 S2      
327m0228            VIA   -    M      A18X+043111Y+127270X0200Y         S2      
327m0228            C4214 -1          A18X+043111Y+127751X0280Y0320     S2      
327m0228            R6457 -2          A18X+043166Y+126855X0198Y0197R270 S2      
327m0229            VIA   -    M      A01X+093452Y+100935X0300Y         S1      
327m0229            C4354 -1          A01X+093142Y+100363X0280Y0320R180 S1      
327m0229            R6531 -2          A01X+093438Y+101408X0198Y0197R270 S1      
327m0230            VIA   -    M      A01X+097180Y+100932X0300Y         S1      
327m0230            C4352 -1          A01X+097308Y+100346X0280Y0320R180 S1      
327m0230            R6529 -2          A01X+097176Y+101433X0198Y0197R270 S1      
327m0231            C4356 -1          A01X+095516Y+100349X0400Y0500R090 S1      
327m0231            VIA   -    M      A01X+095558Y+100933X0300Y         S1      
327m0231            R6533 -2          A01X+095487Y+101408X0198Y0197R270 S1      
327m0232            VIA   -    M      A18X+136231Y+127886X0260Y         S2      
327m0232            C4325 -1          A18X+136227Y+128429X0280Y0320     S2      
327m0232            R6514 -2          A18X+136231Y+127384X0198Y0197R270 S2      
327m0233            C4342 -1          A01X+096703Y+100354X0400Y0500R090 S1      
327m0233            VIA   -    M      A01X+096647Y+100924X0300Y         S1      
327m0233            R6525 -2          A01X+096762Y+101431X0198Y0197R270 S1      
327m0234            VIA   -    M      A18X+134636Y+127870X0260Y         S2      
327m0234            C4314 -1          A18X+134637Y+128429X0280Y0320     S2      
327m0234            R6509 -2          A18X+134636Y+127384X0198Y0197R270 S2      
327m0235            VIA   -    M      A18X+132489Y+127896X0200Y         S2      
327m0235            C4310 -1          A18X+132007Y+128015X0280Y0320     S2      
327m0235            R6505 -2          A18X+132000Y+127384X0198Y0197R270 S2      
327m0236            VIA   -    M      A18X+134123Y+127859X0260Y         S2      
327m0236            C4327 -1          A18X+134114Y+128429X0280Y0320     S2      
327m0236            R6516 -2          A18X+134123Y+127384X0198Y0197R270 S2      
327m0237            VIA   -    M      A18X+144736Y+127322X0260Y         S2      
327m0237            R6540 -2          A18X+144438Y+126868X0198Y0197R270 S2      
327m0237            C4371 -1          A18X+144219Y+127334X0280Y0320     S2      
327m0238            VIA   -    M      A01X+178547Y+101066X0300Y         S1      
327m0238            C4395 -1          A01X+178678Y+100525X0280Y0320R180 S1      
327m0238            R6552 -2          A01X+178414Y+101548X0198Y0197R270 S1      
327m0239            R6548 -2          A18X+141945Y+126863X0198Y0197R270 S2      
327m0239            C4385 -1          A18X+142485Y+127334X0280Y0320     S2      
327m0240            C4398 -1          A01X+180401Y+100486X0400Y0500R090 S1      
327m0240            VIA   -    M      A01X+180243Y+101061X0300Y         S1      
327m0240            R6555 -2          A01X+180243Y+101548X0198Y0197R270 S1      
327m0241            VIA   -    M      A01X+177976Y+101067X0300Y         S1      
327m0241            C4411 -1          A01X+178139Y+100525X0280Y0320R180 S1      
327m0241            R6562 -2          A01X+177804Y+101548X0198Y0197R270 S1      
327m0242            VIA   -    M      A18X+141307Y+127290X0200Y         S2      
327m0242            R6545 -2          A18X+141518Y+126868X0198Y0197R270 S2      
327m0242            C4382 -1          A18X+141828Y+127334X0280Y0320     S2      
327m0243            VIA   -    M      A01X+176713Y+101060X0300Y         S1      
327m0243            R6551 -2          A01X+176513Y+101548X0198Y0197R270 S1      
327m0243            C4394 -1          A01X+177049Y+100525X0280Y0320R180 S1      
327m0244            VIA   -    M      A18X+140507Y+127290X0200Y         S2      
327m0244            C4383 -1          A18X+140723Y+127795X0280Y0320     S2      
327m0244            R6546 -2          A18X+140692Y+126868X0198Y0197R270 S2      
327m0245            VIA   -    M      A01X+177328Y+101064X0300Y         S1      
327m0245            C4410 -1          A01X+177595Y+100525X0280Y0320R180 S1      
327m0245            R6561 -2          A01X+177199Y+101548X0198Y0197R270 S1      
327m0246            C4412 -1          A01X+181796Y+100486X0400Y0500R090 S1      
327m0246            VIA   -    M      A01X+181270Y+101072X0300Y         S1      
327m0246            R6563 -2          A01X+181226Y+101548X0198Y0197R270 S1      
327m0247            C4399 -1          A01X+181113Y+100486X0400Y0500R090 S1      
327m0247            VIA   -    M      A01X+180769Y+101062X0300Y         S1      
327m0247            R6556 -2          A01X+180832Y+101548X0198Y0197R270 S1      
327m0248            VIA   -    M      A01X+179082Y+101074X0300Y         S1      
327m0248            C4396 -1          A01X+179228Y+100525X0280Y0320R180 S1      
327m0248            R6553 -2          A01X+179004Y+101548X0198Y0197R270 S1      
327m0249            C4380 -1          A18X+139065Y+127640X0280Y0320     S2      
327m0249            VIA   -    M      A18X+139127Y+127092X0260Y         S2      
327m0249            R6543 -2          A18X+139127Y+126595X0198Y0197R270 S2      
327m0250            VIA   -    M      A01X+175606Y+101075X0300Y         S1      
327m0250            C4408 -1          A01X+175927Y+100525X0280Y0320R180 S1      
327m0250            R6559 -2          A01X+175630Y+101548X0198Y0197R270 S1      
327m0251            VIA   -    M      A01X+179659Y+101060X0300Y         S1      
327m0251            C4397 -1          A01X+179772Y+100525X0280Y0320R180 S1      
327m0251            R6554 -2          A01X+179634Y+101548X0198Y0197R270 S1      
327m0252            C4413 -1          A01X+182481Y+100490X0400Y0500R090 S1      
327m0252            VIA   -    M      A01X+181893Y+101072X0300Y         S1      
327m0252            R6564 -2          A01X+181626Y+101548X0198Y0197R270 S1      
327m0253            VIA   -    M      A18X+140907Y+127290X0200Y         S2      
327m0253            R6537 -2          A18X+141118Y+126868X0198Y0197R270 S2      
327m0253            C4368 -1          A18X+141239Y+127796X0280Y0320     S2      
327m0254            C4366 -1          A18X+138550Y+127643X0280Y0320     S2      
327m0254            VIA   -    M      A18X+138612Y+127095X0260Y         S2      
327m0254            R6535 -2          A18X+138612Y+126599X0198Y0197R270 S2      
327m0255            C4367 -1          A18X+138031Y+127638X0280Y0320     S2      
327m0255            VIA   -    M      A18X+138094Y+127090X0260Y         S2      
327m0255            R6536 -2          A18X+138094Y+126593X0198Y0197R270 S2      
327m0256            R6539 -2          A18X+144041Y+126868X0198Y0197R270 S2      
327m0256            C4370 -1          A18X+143625Y+127334X0280Y0320     S2      
327m0257            R6547 -2          A18X+143644Y+126871X0198Y0197R270 S2      
327m0257            C4384 -1          A18X+143034Y+127334X0280Y0320     S2      
327m0258            VIA   -    M      A01X+176174Y+101062X0300Y         S1      
327m0258            R6560 -2          A01X+176049Y+101548X0198Y0197R270 S1      
327m0258            C4409 -1          A01X+176500Y+100525X0280Y0320R180 S1      
327m0259            C4369 -1          A18X+140080Y+127785X0280Y0320     S2      
327m0259            VIA   -    M      A18X+140143Y+127092X0260Y         S2      
327m0259            R6538 -2          A18X+140143Y+126595X0198Y0197R270 S2      
327m0260            C4381 -1          A18X+139567Y+127640X0280Y0320     S2      
327m0260            VIA   -    M      A18X+139630Y+127092X0260Y         S2      
327m0260            R6544 -2          A18X+139630Y+126595X0198Y0197R270 S2      
327m0261            C4241 -1          A01X+001451Y+099232X0280Y0320R180 S1      
327m0261            VIA   -    M      A01X+001145Y+099767X0300Y         S1      
327m0261            R6470 -2          A01X+001070Y+100255X0198Y0197R270 S1      
327m0262            R6463 -2          A01X+003955Y+100255X0198Y0197R270 S1      
327m0262            C4228 -1          A01X+004179Y+099232X0280Y0320R180 S1      
327m0262            VIA   -    M      A01X+004033Y+099780X0300Y         S1      
327m0263            C4244 -1          A01X+005791Y+099218X0400Y0500R090 S1      
327m0263            R6473 -2          A01X+005783Y+100255X0198Y0197R270 S1      
327m0263            VIA   -    M      A01X+005721Y+099788X0300Y         S1      
327m0264            C4242 -1          A01X+002001Y+099232X0280Y0320R180 S1      
327m0264            VIA   -    M      A01X+001665Y+099767X0300Y         S1      
327m0264            R6471 -2          A01X+001464Y+100255X0198Y0197R270 S1      
327m0265            R6472 -2          A01X+002151Y+100255X0198Y0197R270 S1      
327m0265            VIA   -    M      A01X+002279Y+099771X0300Y         S1      
327m0265            C4243 -1          A01X+002546Y+099232X0280Y0320R180 S1      
327m0266            C4231 -1          A01X+006156Y+097830X0400Y0500R090 S1      
327m0266            R6466 -2          A01X+006178Y+100255X0198Y0197R270 S1      
327m0266            VIA   -    M      A01X+006221Y+099789X0300Y         S1      
327m0267            C4230 -1          A01X+006834Y+099201X0400Y0500R090 S1      
327m0267            R6465 -2          A01X+006577Y+100255X0198Y0197R270 S1      
327m0267            VIA   -    M      A01X+006845Y+099779X0300Y         S1      
327m0268            R6461 -2          A01X+002756Y+100255X0198Y0197R270 S1      
327m0268            C4226 -1          A01X+003090Y+099232X0280Y0320R180 S1      
327m0268            VIA   -    M      A01X+002928Y+099774X0300Y         S1      
327m0269            R6469 -2          A01X+000681Y+100255X0198Y0197R270 S1      
327m0269            C4240 -1          A01X+000879Y+099232X0280Y0320R180 S1      
327m0269            VIA   -    M      A01X+000638Y+099770X0300Y         S1      
327m0270            C4229 -1          A01X+004723Y+099232X0280Y0320R180 S1      
327m0270            VIA   -    M      A01X+004611Y+099766X0300Y         S1      
327m0270            R6464 -2          A01X+004586Y+100255X0198Y0197R270 S1      
327m0271            C4245 -1          A01X+005060Y+097830X0400Y0500R090 S1      
327m0271            VIA   -    M      A01X+005195Y+099768X0300Y         S1      
327m0271            R6474 -2          A01X+005195Y+100255X0198Y0197R270 S1      
327m0272            C4202 -1          A18X+046164Y+127736X0280Y0320     S2      
327m0272            VIA   -    M      A18X+046168Y+127188X0260Y         S2      
327m0272            R6449 -2          A18X+046168Y+126691X0198Y0197R270 S2      
327m0273            C4227 -1          A01X+003629Y+099232X0280Y0320R180 S1      
327m0273            VIA   -    M      A01X+003499Y+099772X0300Y         S1      
327m0273            R6462 -2          A01X+003366Y+100255X0198Y0197R270 S1      
327m0274            R6454 -2          A01X+046132Y+121791X0198Y0197R270 S1      
327m0274            C4207 -1          A01X+046132Y+121208X0280Y0320R180 S1      
327m0275            R6453 -2          A01X+045602Y+121791X0198Y0197R270 S1      
327m0275            C4206 -1          A01X+045597Y+121208X0280Y0320R180 S1      
327m0276            C4205 -1          A18X+043629Y+127723X0280Y0320     S2      
327m0276            VIA   -    M      A18X+043619Y+127175X0260Y         S2      
327m0276            R6452 -2          A18X+043632Y+126678X0198Y0197R270 S2      
327m0277            C4204 -1          A18X+044104Y+127723X0280Y0320     S2      
327m0277            VIA   -    M      A18X+044122Y+127178X0260Y         S2      
327m0277            R6451 -2          A18X+044108Y+126678X0198Y0197R270 S2      
327m0278            C4203 -1          A18X+045644Y+127734X0280Y0320     S2      
327m0278            VIA   -    M      A18X+045647Y+127186X0260Y         S2      
327m0278            R6450 -2          A18X+045647Y+126689X0198Y0197R270 S2      
327m0279            VIA   -    M      A01X+161666Y+076930X0300Y         S1      
327m0279            Q233  -3          A01X+161666Y+077483X0240Y0240R270 S1      
327m0279            R6429 -1          A01X+161658Y+076458X0198Y0197R270 S1      
327m0280            VIA   -    M      A01X+162950Y+078230X0300Y         S1      
327m0280            R6428 -1          A01X+163408Y+077778X0198Y0197R270 S1      
327m0280            Q233  -5          A01X+162374Y+077778X0160Y0240R270 S1      
327m0280            Q233  -6   M      A01X+162374Y+078074X0240Y0240R270 S1      
317m0281            VIA   -    M      A01X+140540Y+081992X0200Y    R270 S2      
017m0281            VIA   -    M      A18X+140540Y+081992X0260Y    R270 S2      
017m0281                  -    MD0100PA00X+140540Y+081992                       
327m0281            R6423 -2          A01X+140783Y+081982X0198Y0197R180 S1      
317m0281            VIA   -    MD0100PA00X+136415Y+084877X0180Y         S0      
327m0281            U6    -T16        A01X+136257Y+085034X0160Y         S1      
327m0282            VIA   -    M      A01X+160286Y+082974X0300Y         S1      
327m0282            R6423 -1          A01X+141098Y+081982X0198Y0197R180 S1      
327m0282            Q238  -2          A01X+161626Y+081868X0160Y0240R270 S1      
327m0283            U6    -AA21       A01X+137832Y+083460X0160Y         S1      
317m0283            VIA   -    MD0100PA00X+137990Y+083302X0180Y         S0      
317m0283            VIA   -    M      A01X+140130Y+082048X0200Y    R270 S2      
017m0283            VIA   -    M      A18X+140130Y+082048X0260Y    R270 S2      
017m0283                  -    MD0100PA00X+140130Y+082048                       
327m0283            R6422 -2          A01X+140802Y+081568X0198Y0197R180 S1      
317m0284            VIA   -    MD0100PA00X+162050Y+072320X0200Y         S0      
327m0284            Q239  -2          A01X+162716Y+072078X0160Y0240R270 S1      
317m0284            VIA   -    M      A01X+160671Y+081916X0200Y         S2      
017m0284            VIA   -    M      A18X+160671Y+081916X0260Y         S2      
017m0284                  -    MD0100PA00X+160671Y+081916                       
327m0284            R6422 -1          A01X+141117Y+081568X0198Y0197R180 S1      
327m0285            VIA   -    M      A01X+160325Y+079701X0300Y         S1      
327m0285            Q236  -2          A01X+162746Y+075358X0160Y0240R270 S1      
327m0285            R6421 -1          A01X+137702Y+080642X0198Y0197R090 S1      
327m0286            VIA   -    M      A01X+137560Y+081470X0300Y         S1      
317m0286            VIA   -    MD0100PA00X+137519Y+081172X0200Y         S2      
327m0286            U6    -AB20       A01X+137517Y+083144X0160Y         S1      
327m0286            R6421 -2          A01X+137702Y+080957X0198Y0197R090 S1      
317m0287            VIA   -    MD0100PA00X+136730Y+083932X0180Y         S0      
327m0287            U6    -W17        A01X+136572Y+084089X0160Y         S1      
327m0287            R6420 -2          A01X+140648Y+080929X0198Y0197R090 S1      
317m0287            VIA   -    M      A01X+140648Y+081172X0200Y    R180 S2      
017m0287            VIA   -    M      A18X+140648Y+081172X0260Y    R180 S2      
017m0287                  -    MD0100PA00X+140648Y+081172                       
327m0288            VIA   -    M      A01X+160397Y+081680X0300Y         S1      
327m0288            R6420 -1          A01X+140648Y+080614X0198Y0197R090 S1      
327m0288            Q237  -2          A01X+161616Y+080458X0160Y0240R270 S1      
317m0289            VIA   -    MD0100PA00X+162060Y+070590X0200Y         S0      
327m0289            Q234  -2          A01X+162716Y+070288X0160Y0240R270 S1      
317m0289            VIA   -    M      A01X+160619Y+080377X0200Y         S2      
017m0289            VIA   -    M      A18X+160619Y+080377X0260Y         S2      
017m0289                  -    MD0100PA00X+160619Y+080377                       
327m0289            R6419 -1          A01X+140252Y+080614X0198Y0197R090 S1      
327m0290            U6    -Y17        A01X+136572Y+083774X0160Y         S1      
317m0290            VIA   -    MD0100PA00X+136730Y+083617X0180Y         S0      
317m0290            VIA   -    M      A01X+140242Y+081169X0200Y    R180 S2      
017m0290            VIA   -    M      A18X+140242Y+081169X0260Y    R180 S2      
017m0290                  -    MD0100PA00X+140242Y+081169                       
327m0290            R6419 -2          A01X+140252Y+080929X0198Y0197R090 S1      
317m0291            VIA   -    M      A01X+139853Y+081172X0200Y    R180 S2      
017m0291            VIA   -    M      A18X+139853Y+081172X0260Y    R180 S2      
017m0291                  -    MD0100PA00X+139853Y+081172                       
327m0291            R6418 -2          A01X+139852Y+080929X0198Y0197R090 S1      
317m0291            VIA   -    MD0100PA00X+136415Y+083302X0180Y         S0      
327m0291            U6    -AA16       A01X+136257Y+083460X0160Y         S1      
327m0292            VIA   -    M      A01X+160260Y+080285X0300Y         S1      
327m0292            Q235  -2          A01X+161646Y+079048X0160Y0240R270 S1      
327m0292            R6418 -1          A01X+139852Y+080614X0198Y0197R090 S1      
317m0293            VIA   -    MD0100PA00X+160950Y+077610X0200Y         S0      
327m0293            Q233  -2          A01X+161666Y+077778X0160Y0240R270 S1      
317m0293            VIA   -    M      A01X+147080Y+073928X0200Y         S2      
017m0293            VIA   -    M      A18X+147080Y+073928X0260Y         S2      
017m0293                  -    MD0100PA00X+147080Y+073928                       
327m0293            R6417 -1          A01X+135282Y+079042X0198Y0197R090 S1      
317m0293            VIA   -    MD0100PA00X+135282Y+078800X0200Y         S0      
327m0294            U6    -AB15       A01X+135942Y+083144X0160Y         S1      
317m0294            VIA   -    MD0100PA00X+135942Y+082900X0180Y         S0      
327m0294            R6417 -2          A01X+135282Y+079358X0198Y0197R090 S1      
317m0294            VIA   -    M      A01X+135282Y+079600X0200Y    R180 S2      
017m0294            VIA   -    M      A18X+135282Y+079600X0260Y    R180 S2      
017m0294                  -    MD0100PA00X+135282Y+079600                       
327m0295            VIA   -    M      A01X+160980Y+081730X0300Y         S1      
327m0295            R6446 -1          A01X+160828Y+081228X0198Y0197R270 S1      
327m0295            Q238  -3          A01X+161626Y+081573X0240Y0240R270 S1      
327m0296            VIA   -    M      A01X+162550Y+082690X0300Y         S1      
327m0296            R6443 -1          A01X+161958Y+082812X0198Y0197R180 S1      
327m0296            Q238  -6   M      A01X+162334Y+082164X0240Y0240R270 S1      
327m0296            Q238  -5          A01X+162334Y+081868X0160Y0240R270 S1      
327m0297            VIA   -    M      A01X+162050Y+071783X0300Y         S1      
327m0297            Q239  -3          A01X+162716Y+071783X0240Y0240R270 S1      
327m0297            R6447 -1          A01X+161418Y+071782X0198Y0197R180 S1      
317m0298            VIA   -    MD0100PA00X+162010Y+073830X0200Y         S0      
327m0298            Q232  -2          A01X+162746Y+073538X0160Y0240R270 S1      
317m0298            VIA   -    M      A01X+147101Y+074482X0200Y         S2      
017m0298            VIA   -    M      A18X+147101Y+074482X0260Y         S2      
017m0298                  -    MD0100PA00X+147101Y+074482                       
317m0298            VIA   -    MD0100PA00X+134892Y+078800X0200Y         S0      
327m0298            R6416 -1          A01X+134892Y+079042X0198Y0197R090 S1      
327m0299            VIA   -    M      A01X+164010Y+072320X0300Y         S1      
327m0299            Q239  -6   M      A01X+163424Y+072374X0240Y0240R270 S1      
327m0299            Q239  -5          A01X+163424Y+072078X0160Y0240R270 S1      
327m0299            R6445 -1          A01X+164158Y+072812X0198Y0197R180 S1      
317m0300            VIA   -    M      A01X+134892Y+079600X0200Y    R180 S2      
017m0300            VIA   -    M      A18X+134892Y+079600X0260Y    R180 S2      
017m0300                  -    MD0100PA00X+134892Y+079600                       
327m0300            R6416 -2          A01X+134892Y+079358X0198Y0197R090 S1      
317m0300            VIA   -    MD0100PA00X+135785Y+084247X0180Y         S0      
327m0300            U6    -V14        A01X+135628Y+084404X0160Y         S1      
327m0301            VIA   -    M      A01X+162170Y+075063X0300Y         S1      
327m0301            Q236  -3          A01X+162746Y+075063X0240Y0240R270 S1      
327m0301            R6440 -1          A01X+161668Y+075058X0198Y0197R270 S1      
327m0302            VIA   -    M      A01X+163454Y+076176X0300Y         S1      
327m0302            R6437 -1          A01X+162988Y+076272X0198Y0197R180 S1      
327m0302            Q236  -6   M      A01X+163454Y+075654X0240Y0240R270 S1      
327m0302            Q236  -5          A01X+163454Y+075358X0160Y0240R270 S1      
327m0303            VIA   -    M      A01X+160940Y+080380X0300Y         S1      
327m0303            Q237  -3          A01X+161616Y+080163X0240Y0240R270 S1      
327m0303            R6441 -1          A01X+160838Y+079828X0198Y0197R270 S1      
327m0304            VIA   -    M      A01X+162840Y+080940X0300Y         S1      
327m0304            R6439 -1          A01X+163138Y+080458X0198Y0197R270 S1      
327m0304            Q237  -5          A01X+162324Y+080458X0160Y0240R270 S1      
327m0304            Q237  -6   M      A01X+162324Y+080754X0240Y0240R270 S1      
327m0305            VIA   -    M      A01X+162060Y+069993X0300Y         S1      
327m0305            Q234  -3          A01X+162716Y+069993X0240Y0240R270 S1      
327m0305            R6434 -1          A01X+161418Y+069992X0198Y0197R180 S1      
327m0306            VIA   -    M      A01X+163930Y+070890X0300Y         S1      
327m0306            R6431 -1          A01X+163418Y+071142X0198Y0197R180 S1      
327m0306            Q234  -6   M      A01X+163424Y+070584X0240Y0240R270 S1      
327m0306            Q234  -5          A01X+163424Y+070288X0160Y0240R270 S1      
327m0307            VIA   -    M      A01X+160875Y+078815X0300Y         S1      
327m0307            R6435 -1          A01X+160848Y+078348X0198Y0197R270 S1      
327m0307            Q235  -3          A01X+161646Y+078753X0240Y0240R270 S1      
327m0308            VIA   -    M      A01X+162970Y+079570X0300Y         S1      
327m0308            R6433 -1          A01X+163258Y+079048X0198Y0197R270 S1      
327m0308            Q235  -6   M      A01X+162354Y+079344X0240Y0240R270 S1      
327m0308            Q235  -5          A01X+162354Y+079048X0160Y0240R270 S1      
327m0309            VIA   -    M      A01X+162120Y+073243X0300Y         S1      
327m0309            Q232  -3          A01X+162746Y+073243X0240Y0240R270 S1      
327m0309            R6426 -1          A01X+161448Y+073242X0198Y0197R180 S1      
327m0310            VIA   -    M      A01X+163530Y+074340X0300Y         S1      
327m0310            R6425 -1          A01X+163058Y+074432X0198Y0197R180 S1      
327m0310            Q232  -6   M      A01X+163454Y+073834X0240Y0240R270 S1      
327m0310            Q232  -5          A01X+163454Y+073538X0160Y0240R270 S1      
317m0311            VIA   -    MD0080PA00X+165285Y+120797X0160Y         S0      
327m0311            PEX3  -P38        A01X+165472Y+120610X0180Y         S1      
317m0311            VIA   -    M      A01X+171272Y+118850X0200Y         S2      
017m0311            VIA   -    M      A18X+171272Y+118850X0260Y         S2      
017m0311                  -    MD0100PA00X+171272Y+118850                       
327m0311            R6398 -2          A01X+171272Y+118512X0198Y0197R090 S1      
327m0312            R6382 -1          A18X+043285Y+138503X0198Y0197     S2      
317m0312            VIA   -    MD0100PA00X+144026Y+131070X0200Y         S0      
327m0312            PEX3  -AE1        A01X+151634Y+116496X0180Y         S1      
327m0313            R6380 -1          A18X+043285Y+138903X0198Y0197     S2      
317m0313            VIA   -    MD0100PA00X+144366Y+131070X0200Y         S0      
327m0313            PEX3  -AE2        A01X+152008Y+116496X0180Y         S1      
317m0314            VIA   -    MD0100PA00X+100933Y+134329X0200Y    R270 S0      
327m0314            PEX2  -AE1        A01X+105925Y+116496X0180Y         S1      
327m0314            R6379 -1          A18X+041820Y+141388X0198Y0197R090 S2      
317m0315            VIA   -    MD0100PA00X+100933Y+134669X0200Y    R270 S0      
327m0315            PEX2  -AE2        A01X+106299Y+116496X0180Y         S1      
327m0315            R6378 -1          A18X+041420Y+141388X0198Y0197R090 S2      
317m0316            VIA   -    M      A01X+125563Y+118834X0200Y         S2      
017m0316            VIA   -    M      A18X+125563Y+118834X0260Y         S2      
017m0316                  -    MD0100PA00X+125563Y+118834                       
327m0316            R6394 -2          A01X+125563Y+118512X0198Y0197R090 S1      
327m0316            PEX2  -P38        A01X+119764Y+120610X0180Y         S1      
317m0316            VIA   -    MD0080PA00X+119577Y+120797X0160Y         S0      
327m0317            PEX1  -AE1        A01X+060216Y+116496X0180Y         S1      
317m0317            VIA   -    MD0100PA00X+040589Y+141728X0200Y         S0      
327m0317            R6377 -1          A18X+040619Y+141072X0198Y0197R090 S2      
327m0318            PEX1  -AE2        A01X+060590Y+116496X0180Y         S1      
317m0318            VIA   -    MD0100PA00X+040249Y+141728X0200Y         S0      
327m0318            R6376 -1          A18X+040219Y+141072X0198Y0197R090 S2      
327m0319            PEX1  -P38        A01X+074055Y+120610X0180Y         S1      
317m0319            VIA   -    MD0080PA00X+073868Y+120797X0160Y         S0      
327m0319            VIA   -    M      A18X+079075Y+119614X0260Y         S2      
317m0319            VIA   -    MD0100PA00X+079854Y+118834X0200Y         S0      
327m0319            R6390 -2          A01X+079854Y+118512X0198Y0197R090 S1      
317m0320            VIA   -    MD0100PA00X+037020Y+131136X0200Y         S0      
327m0320            R6374 -1          A18X+038540Y+138472X0198Y0197R180 S2      
327m0320            PEX0  -AE2        A01X+014882Y+116496X0180Y         S1      
317m0321            VIA   -    MD0100PA00X+037020Y+131476X0200Y         S0      
327m0321            R6375 -1          A18X+038540Y+138872X0198Y0197R180 S2      
327m0321            PEX0  -AE1        A01X+014508Y+116496X0180Y         S1      
317m0322            VIA   -    M      A01X+033978Y+118796X0200Y         S2      
017m0322            VIA   -    M      A18X+033978Y+118796X0260Y         S2      
017m0322                  -    MD0100PA00X+033978Y+118796                       
327m0322            R6386 -2          A01X+034146Y+118512X0198Y0197R090 S1      
327m0322            PEX0  -P38        A01X+028346Y+120610X0180Y         S1      
317m0322            VIA   -    MD0080PA00X+028159Y+120797X0160Y         S0      
317m0323            VIA   -    MD0100PA00X+079835Y+117201X0200Y         S2      
327m0323            R6390 -1          A01X+079854Y+118197X0198Y0197R090 S1      
327m0323            U426  -7          A01X+079835Y+116781X0140Y0520     S1      
327m0324            VIA   -    M      A01X+080261Y+117503X0300Y         S1      
327m0324            U426  -5          A01X+080347Y+116781X0140Y0520     S1      
327m0324            R6392 -1          A01X+080256Y+118190X0198Y0197R090 S1      
317m0325            VIA   -    MD0100PA00X+079384Y+114338X0200Y         S2      
327m0325            R6393 -1          A01X+079384Y+114028X0198Y0197R270 S1      
327m0325            U426  -2          A01X+079835Y+115324X0140Y0520     S1      
327m0326            VIA   -    M      A18X+079473Y+091548X0260Y         S2      
327m0326            R6342 -2          A18X+080367Y+101934X0198Y0197R090 S2      
327m0326            U423  -4   M      A18X+080616Y+100209X0120Y0630R180 S2      
327m0326            R6320 -2          A18X+083626Y+090651X0198Y0197R090 S2      
327m0327            R6348 -2          A18X+082767Y+101934X0198Y0197R090 S2      
327m0327            VIA   -    M      A18X+082355Y+100958X0260Y         S2      
327m0327            U423  -10  M      A18X+082152Y+100209X0120Y0630R180 S2      
327m0327            R6332 -2          A18X+084038Y+092364X0198Y0197R270 S2      
327m0328            R6349 -2          A18X+083167Y+101934X0198Y0197R090 S2      
327m0328            VIA   -    M      A18X+082952Y+101030X0260Y         S2      
327m0328            U423  -11  M      A18X+082408Y+100209X0120Y0630R180 S2      
327m0328            R6334 -2          A18X+084438Y+092364X0198Y0197R270 S2      
327m0329            VIA   -    M      A18X+079718Y+092275X0260Y         S2      
327m0329            R6344 -2          A18X+081167Y+101934X0198Y0197R090 S2      
327m0329            U423  -6   M      A18X+081128Y+100209X0120Y0630R180 S2      
327m0329            R6324 -2          A18X+080989Y+091570X0198Y0197     S2      
327m0330            VIA   -    M      A18X+080351Y+092620X0260Y         S2      
327m0330            R6346 -2          A18X+081967Y+101934X0198Y0197R090 S2      
327m0330            R6328 -2          A18X+082277Y+092139X0198Y0197     S2      
327m0330            U423  -8   M      A18X+081640Y+100209X0120Y0630R180 S2      
327m0331            VIA   -    M      A18X+079258Y+093282X0260Y         S2      
327m0331            R6345 -2          A18X+081567Y+101934X0198Y0197R090 S2      
327m0331            U423  -7   M      A18X+081384Y+100209X0120Y0630R180 S2      
327m0331            R6326 -2          A18X+081536Y+092003X0198Y0197     S2      
327m0332            VIA   -    M      A18X+080002Y+093400X0260Y         S2      
327m0332            R6347 -2          A18X+082367Y+101934X0198Y0197R090 S2      
327m0332            U423  -9   M      A18X+081896Y+100209X0120Y0630R180 S2      
327m0332            R6330 -2          A18X+083000Y+092315X0198Y0197R270 S2      
327m0333            VIA   -    M      A18X+080617Y+091017X0260Y         S2      
327m0333            R6343 -2          A18X+080767Y+101934X0198Y0197R090 S2      
327m0333            U423  -5   M      A18X+080872Y+100209X0120Y0630R180 S2      
327m0333            R6322 -2          A18X+083226Y+090647X0198Y0197R090 S2      
327PEX_MUX_A2       VIA   -    M      A18X+081807Y+097272X0260Y         S2      
327PEX_MUX_A2       R6338 -2          A18X+082949Y+097278X0198Y0197R270 S2      
327PEX_MUX_A2       R6341 -1   M      A18X+082515Y+097272X0198Y0197R090 S2      
327PEX_MUX_A2       U423  -21         A18X+080616Y+098004X0120Y0630R180 S2      
327PEX_MUX_A1       VIA   -    M      A18X+080104Y+101077X0260Y         S2      
327PEX_MUX_A1       U423  -2          A18X+080104Y+100209X0120Y0630R180 S2      
327PEX_MUX_A1       R6340 -1          A18X+079169Y+101934X0198Y0197R270 S2      
327PEX_MUX_A1       R6337 -2   M      A18X+079563Y+101934X0198Y0197R090 S2      
327PEX_MUX_A0       VIA   -    M      A18X+079381Y+101312X0260Y         S2      
327PEX_MUX_A0       U423  -1          A18X+079848Y+100209X0120Y0630R180 S2      
327PEX_MUX_A0       R6336 -2          A18X+078366Y+101934X0198Y0197R090 S2      
327PEX_MUX_A0       R6339 -1   M      A18X+078763Y+101934X0198Y0197R270 S2      
327m0334            VIA   -    M      A18X+082283Y+096061X0260Y         S2      
327m0334            U423  -22         A18X+080360Y+098004X0120Y0630R180 S2      
317m0334            VIA   -    MD0100PA00X+081652Y+093115X0200Y         S0      
327m0334            R6319 -2          A01X+082699Y+092663X0198Y0197R270 S1      
327m0335            VIA   -    M      A18X+081723Y+093534X0260Y         S2      
317m0335            VIA   -    MD0100PA00X+084920Y+092413X0200Y         S0      
327m0335            R6318 -2          A01X+084920Y+092663X0198Y0197R270 S1      
327m0335            U423  -23         A18X+080104Y+098004X0120Y0630R180 S2      
327SWB_HSC_PWRGD    VIA   -    M      A18X+140990Y+144236X0260Y         S2      
327SWB_HSC_PWRGD    R6315 -2          A18X+141098Y+142370X0198Y0197R180 S2      
317SWB_HSC_PWRGD    J13   -A9   D0122PA00X+137437Y+162240X0282Y    R180 S3      
317m0336            VIA   -    MD0100PA00X+034127Y+117196X0200Y         S2      
327m0336            R6386 -1          A01X+034146Y+118197X0198Y0197R090 S1      
327m0336            U425  -7          A01X+034127Y+116781X0140Y0520     S1      
327m0337            VIA   -    M      A01X+034563Y+117490X0300Y         S1      
327m0337            R6387 -1          A01X+034547Y+118190X0198Y0197R090 S1      
327m0337            U425  -5          A01X+034638Y+116781X0140Y0520     S1      
317m0338            VIA   -    MD0100PA00X+033676Y+114349X0200Y         S2      
327m0338            U425  -2          A01X+034127Y+115324X0140Y0520     S1      
327m0338            R6388 -1          A01X+033676Y+114028X0198Y0197R270 S1      
327m0339            VIA   -    M      A01X+082948Y+090376X0300Y         S1      
327m0339            R1545 -1          A01X+082891Y+090847X0198Y0197R090 S1      
327m0339            R1548 -1   M      A01X+083291Y+090847X0198Y0197R090 S1      
327m0339            R1542 -1   M      A01X+083691Y+090847X0198Y0197R090 S1      
327m0339            R1550 -1   M      A01X+084091Y+090847X0198Y0197R090 S1      
327m0339            R6359 -1          A01X+084540Y+092660X0198Y0197R090 S1      
317m0340            VIA   -    M      A01X+083475Y+092237X0200Y         S2      
017m0340            VIA   -    M      A18X+083475Y+092237X0260Y         S2      
017m0340                  -    MD0100PA00X+083475Y+092237                       
327m0340            R1549 -1          A01X+084106Y+092217X0198Y0197R270 S1      
327m0340            R1541 -1   M      A01X+083724Y+092217X0198Y0197R270 S1      
327m0340            R1547 -1   M      A01X+083141Y+092237X0198Y0197R270 S1      
327m0340            R6358 -1          A01X+083091Y+092660X0198Y0197R090 S1      
327m0340            R1543 -1   M      A01X+082741Y+092237X0198Y0197R270 S1      
317m0341            VIA   -    MD0100PA00X+132950Y+088341X0180Y         S0      
327m0341            U6    -F6         A01X+133108Y+088184X0160Y         S1      
317m0341            VIA   -    M      A01X+141934Y+094228X0200Y         S2      
017m0341            VIA   -    M      A18X+141934Y+094228X0260Y         S2      
017m0341                  -    MD0100PA00X+141934Y+094228                       
327m0341            R6405 -2          A01X+142495Y+094760X0198Y0197R180 S1      
327m0342            VIA   -    M      A18X+132355Y+089704X0260Y         S2      
317m0342            VIA   -    MD0100PA00X+146189Y+093606X0200Y         S0      
327m0342            R6404 -2          A01X+146492Y+093289X0198Y0197     S1      
327m0342            U6    -D4         A01X+132478Y+088814X0160Y         S1      
317m0342            VIA   -    MD0100PA00X+132320Y+088971X0180Y         S0      
317m0343            VIA   -    M      A01X+148014Y+094688X0200Y         S2      
017m0343            VIA   -    M      A18X+148014Y+094688X0260Y         S2      
017m0343                  -    MD0100PA00X+148014Y+094688                       
327m0343            R6402 -2          A01X+146974Y+094350X0198Y0197     S1      
327m0343            U6    -D3         A01X+132163Y+088814X0160Y         S1      
317m0343            VIA   -    MD0100PA00X+132006Y+088971X0180Y         S0      
327m0344            VIA   -    M      A01X+143282Y+094144X0300Y         S1      
327m0344            R6405 -1          A01X+142810Y+094760X0198Y0197R180 S1      
327m0344            U429  -2          A01X+143923Y+094341X0140Y0520R270 S1      
327m0344            R6410 -2   M      A01X+142811Y+094339X0198Y0197     S1      
327m0345            R6409 -2          A01X+146177Y+092818X0198Y0197     S1      
327m0345            VIA   -    M      A01X+145667Y+093370X0300Y         S1      
327m0345            R6404 -1   M      A01X+146177Y+093289X0198Y0197     S1      
327m0345            U429  -5          A01X+145380Y+093829X0140Y0520R270 S1      
327m0346            VIA   -    M      A01X+146144Y+094486X0300Y         S1      
327m0346            R6403 -2          A01X+146654Y+094760X0198Y0197R180 S1      
327m0346            U429  -7          A01X+145380Y+094341X0140Y0520R270 S1      
327m0346            R6402 -1          A01X+146659Y+094350X0198Y0197     S1      
327m0347            VIA   -    M      A01X+146158Y+093954X0300Y         S1      
327m0347            U429  -6          A01X+145380Y+094085X0140Y0520R270 S1      
327m0347            R6408 -1          A01X+146662Y+093954X0198Y0197     S1      
327m0348            VIA   -    M      A01X+142821Y+093302X0300Y         S1      
327m0348            R6407 -1          A01X+142129Y+093929X0198Y0197R180 S1      
327m0348            U429  -3          A01X+143923Y+094085X0140Y0520R270 S1      
327m0349            VIA   -    M      A01X+143281Y+094706X0300Y         S1      
327m0349            U429  -1          A01X+143923Y+094597X0140Y0520R270 S1      
327m0349            R6406 -1          A01X+142816Y+095156X0198Y0197R180 S1      
317m0350            VIA   -    MD0100PA00X+041904Y+139887X0200Y    R270 S0      
327m0350            R6368 -1   M      A18X+041636Y+139887X0198Y0197R270 S2      
327m0350            U424  -24         A18X+041512Y+139425X0100Y0220R180 S2      
327m0350            U424  -26         A18X+041758Y+138982X0100Y0220R090 S2      
317m0350            VIA   -    MD0100PA00X+042092Y+139033X0200Y    R270 S0      
327m0350            VIA   -           A18X+042438Y+139079X0260Y    R270 S2      
327m0350            U424  -15         A18X+039888Y+138982X0100Y0220R270 S2      
317m0350            VIA   -    MD0100PA00X+039577Y+138982X0200Y    R270 S0      
327m0350            U424  -18         A18X+040331Y+139425X0100Y0220R180 S2      
327m0350            R6371 -1   M      A18X+040088Y+140024X0198Y0197R270 S2      
317m0350            VIA   -    MD0100PA00X+039834Y+139978X0200Y    R270 S0      
317m0351            VIA   -    MD0100PA00X+170802Y+114270X0200Y         S2      
327m0351            U428  -2          A01X+171253Y+115324X0140Y0520     S1      
327m0351            R6401 -1          A01X+170802Y+114028X0198Y0197R270 S1      
327m0352            VIA   -    M      A01X+171670Y+117453X0300Y         S1      
327m0352            R6400 -1          A01X+171673Y+118190X0198Y0197R090 S1      
327m0352            U428  -5          A01X+171764Y+116781X0140Y0520     S1      
317m0353            VIA   -    MD0100PA00X+171253Y+117195X0200Y         S2      
327m0353            R6398 -1          A01X+171272Y+118197X0198Y0197R090 S1      
327m0353            U428  -7          A01X+171253Y+116781X0140Y0520     S1      
327m0354            R6376 -2          A18X+040219Y+140757X0198Y0197R090 S2      
327m0354            U424  -19         A18X+040528Y+139425X0100Y0220R180 S2      
327m0355            R6374 -2          A18X+038855Y+138472X0198Y0197R180 S2      
327m0355            U424  -13         A18X+039888Y+138588X0100Y0220R270 S2      
327m0356            U424  -27         A18X+041758Y+138785X0100Y0220R090 S2      
327m0356            R6380 -2          A18X+042970Y+138903X0198Y0197     S2      
327m0357            R6377 -2          A18X+040619Y+140757X0198Y0197R090 S2      
327m0357            U424  -20         A18X+040725Y+139425X0100Y0220R180 S2      
327m0358            U424  -6          A18X+040528Y+137555X0100Y0220     S2      
317m0358            VIA   -    M      A01X+039223Y+136450X0200Y         S2      
017m0358            VIA   -    M      A18X+039223Y+136450X0260Y         S2      
017m0358                  -    MD0100PA00X+039223Y+136450                       
317m0358            VIA   -    MD0100PA00X+048760Y+130210X0200Y         S0      
317m0358            VIA   -    MD0100PA00X+087260Y+129833X0200Y         S0      
317m0358            VIA   -    MD0100PA00X+095750Y+078080X0200Y         S0      
327m0358            R6385 -1          A01X+127966Y+034573X0198Y0197R270 S1      
317m0358            VIA   -    MD0100PA00X+116790Y+055330X0200Y         S0      
317m0358            VIA   -    MD0100PA00X+091830Y+062970X0200Y         S0      
327m0359            R6379 -2          A18X+041820Y+141073X0198Y0197R090 S2      
327m0359            U424  -23         A18X+041315Y+139425X0100Y0220R180 S2      
317m0360            VIA   -    MD0100PA00X+049010Y+130210X0200Y         S0      
317m0360            VIA   -    MD0100PA00X+087260Y+130083X0200Y         S0      
317m0360            VIA   -    MD0100PA00X+095602Y+077030X0200Y         S0      
317m0360            VIA   -    MD0100PA00X+091580Y+062970X0200Y         S0      
327m0360            R6384 -1          A01X+127566Y+034578X0198Y0197R270 S1      
317m0360            VIA   -    MD0100PA00X+116540Y+055330X0200Y         S0      
317m0360            VIA   -    M      A01X+039223Y+136958X0200Y         S2      
017m0360            VIA   -    M      A18X+039223Y+136958X0260Y         S2      
017m0360                  -    MD0100PA00X+039223Y+136958                       
327m0360            U424  -7          A18X+040331Y+137555X0100Y0220     S2      
327m0361            R6375 -2          A18X+038855Y+138872X0198Y0197R180 S2      
327m0361            U424  -14         A18X+039888Y+138785X0100Y0220R270 S2      
327m0362            R6378 -2          A18X+041420Y+141073X0198Y0197R090 S2      
327m0362            U424  -22         A18X+041118Y+139425X0100Y0220R180 S2      
327m0363            U424  -28         A18X+041758Y+138588X0100Y0220R090 S2      
327m0363            R6382 -2          A18X+042970Y+138503X0198Y0197     S2      
327m0364            R6373 -2          A18X+039596Y+135813X0198Y0197R270 S2      
327m0364            R6370 -1   M      A18X+039996Y+135813X0198Y0197R090 S2      
327m0364            VIA   -    M      A18X+040529Y+136775X0260Y    R270 S2      
327m0364            U424  -5          A18X+040725Y+137555X0100Y0220     S2      
327m0365            R6366 -1          A18X+040846Y+135813X0198Y0197R090 S2      
327m0365            U424  -3          A18X+041118Y+137555X0100Y0220     S2      
327m0366            R6367 -2          A18X+040446Y+135498X0198Y0197R090 S2      
317m0366            J11   -N10  D0122PA00X+036106Y+151413X0282Y    R180 S3      
317m0366            VIA   -    MD0100PA00X+040476Y+134907X0200Y    R090 S0      
327m0367            R6367 -1          A18X+040446Y+135813X0198Y0197R090 S2      
327m0367            U424  -4          A18X+040922Y+137555X0100Y0220     S2      
327m0368            VIA   -           A18X+042288Y+136230X0260Y    R270 S2      
327m0368            R6369 -2   M      A18X+042213Y+136697X0198Y0197     S2      
327m0368            U424  -32         A18X+041758Y+137801X0100Y0220R090 S2      
327m0368            R6372 -1   M      A18X+042213Y+137097X0198Y0197R180 S2      
327m0369            R6366 -2          A18X+040846Y+135498X0198Y0197R090 S2      
317m0369            J11   -O10  D0122PA00X+036106Y+150902X0282Y    R180 S3      
317m0369            VIA   -    MD0100PA00X+040816Y+134907X0200Y    R090 S0      
317m0370            VIA   -    MD0100PA00X+125093Y+114283X0200Y         S2      
327m0370            R6397 -1          A01X+125093Y+114028X0198Y0197R270 S1      
327m0370            U427  -2          A01X+125544Y+115324X0140Y0520     S1      
327m0371            VIA   -    M      A01X+125980Y+117443X0300Y         S1      
327m0371            R6396 -1          A01X+125964Y+118190X0198Y0197R090 S1      
327m0371            U427  -5          A01X+126056Y+116781X0140Y0520     S1      
327m0372            VIA   -           A18X+043113Y+136520X0260Y    R270 S2      
327m0372            VIA   -           A18X+043332Y+135767X0260Y    R270 S2      
317m0372            VIA   -    MD0100PA00X+041861Y+137159X0200Y    R270 S0      
327m0372            U424  -2          A18X+041315Y+137555X0100Y0220     S2      
327m0372            R6365 -2   M      A18X+041730Y+136826X0280Y0320     S2      
327m0372            C4183 -1   M      A18X+041278Y+136821X0198Y0197R090 S2      
317m0372            VIA   -    MD0100PA00X+042591Y+135714X0200Y    R270 S0      
317m0372            VIA   -    MD0100PA00X+042586Y+136050X0200Y    R270 S0      
327m0372            C4182 -1          A18X+043427Y+137145X0400Y0500R090 S2      
327m0372            U424  -31  M      A18X+041758Y+137998X0100Y0220R090 S2      
327m0372            C4184 -1   M      A18X+042352Y+137915X0198Y0197R090 S2      
327m0372            VIA   -    M      A18X+042808Y+137872X0260Y    R270 S2      
317m0373            VIA   -    MD0100PA00X+125544Y+117201X0200Y         S2      
327m0373            R6394 -1          A01X+125563Y+118197X0198Y0197R090 S1      
327m0373            U427  -7          A01X+125544Y+116781X0140Y0520     S1      
327m0374            R6365 -1          A18X+041730Y+136246X0280Y0320     S2      
317m0374            VIA   -    MD0100PA00X+041730Y+135917X0200Y    R270 S0      
327m0374            VIA   -           A18X+041730Y+135511X0260Y    R270 S2      
327m0374            C4176 -1          A18X+039418Y+139939X0400Y0500R090 S2      
317m0374            VIA   -    MD0100PA00X+039511Y+139569X0200Y    R270 S0      
327m0374            U424  -16         A18X+039888Y+139179X0100Y0220R270 S2      
327m0374            C4180 -1   M      A18X+039185Y+139259X0198Y0197     S2      
317m0374            VIA   -    MD0100PA00X+039185Y+138993X0200Y    R270 S0      
317m0374            VIA   -    MD0100PA00X+039176Y+138348X0200Y    R270 S0      
327m0374            C4181 -1   M      A18X+039176Y+138102X0198Y0197R090 S2      
327m0374            U424  -12         A18X+039888Y+138391X0100Y0220R270 S2      
317m0374            VIA   -    MD0100PA00X+041017Y+140245X0200Y    R270 S0      
327m0374            C4178 -1          A18X+041015Y+140538X0198Y0197R270 S2      
327m0374            VIA   -    M      A18X+040877Y+139966X0260Y    R270 S2      
327m0374            U424  -21         A18X+040922Y+139425X0100Y0220R180 S2      
317m0374            VIA   -    MD0100PA00X+042064Y+138391X0200Y    R270 S0      
327m0374            U424  -29         A18X+041758Y+138391X0100Y0220R090 S2      
327m0374            L149  -2          A18X+042456Y+140429X0440Y0540R270 S2      
327m0374            C4177 -1          A18X+043001Y+139880X0198Y0197R180 S2      
327m0374            C4179 -1          A18X+042998Y+139493X0198Y0197R180 S2      
327m0374            U424  -25         A18X+041758Y+139179X0100Y0220R090 S2      
317m0374            VIA   -    MD0100PA00X+042273Y+140049X0200Y    R270 S0      
317m0374            VIA   -    MD0100PA00X+041843Y+139424X0200Y    R270 S0      
317m0374            VIA   -    MD0100PA00X+042320Y+139750X0200Y    R270 S2      
317m0374            VIA   -    MD0100PA00X+042340Y+139450X0200Y    R270 S0      
327RST_PEX_MUX_N    R6361 -1          A01X+084495Y+090847X0198Y0197R090 S1      
317RST_PEX_MUX_N    VIA   -    M      A01X+087160Y+089858X0200Y         S2      
017RST_PEX_MUX_N    VIA   -    M      A18X+087160Y+089858X0260Y         S2      
017RST_PEX_MUX_N          -    MD0100PA00X+087160Y+089858                       
327RST_PEX_MUX_N    U5    -P14        A01X+088609Y+087836X0160Y    R180 S1      
317RST_PEX_MUX_N    VIA   -    MD0100PA00X+088452Y+087994X0180Y    R270 S0      
327m0375            VIA   -    M      A18X+084366Y+090711X0260Y         S2      
327m0375            R6360 -2          A18X+079963Y+101934X0198Y0197R090 S2      
317m0375            VIA   -    MD0100PA00X+084960Y+091803X0200Y         S0      
327m0375            U423  -3   M      A18X+080360Y+100209X0120Y0630R180 S2      
327m0375            R6361 -2          A01X+084495Y+091162X0198Y0197R090 S1      
327m0376            VIA   -    M      A18X+085271Y+075592X0260Y         S2      
327m0376            R1530 -1          A01X+086142Y+076000X0198Y0197     S1      
327m0376            U122  -6          A01X+085430Y+076072X0140Y0590R270 S1      
327m0376            R1534 -1          A18X+083500Y+075592X0198Y0197R270 S2      
317m0376            VIA   -    MD0100PA00X+085900Y+076000X0200Y         S0      
327m0376            R6313 -2   M      A18X+083900Y+075592X0198Y0197R090 S2      
327m0377            VIA   -    M      A18X+085476Y+076608X0260Y         S2      
327m0377            R1529 -1          A01X+086142Y+076400X0198Y0197     S1      
327m0377            U122  -7          A01X+085430Y+076328X0140Y0590R270 S1      
327m0377            R1535 -1          A18X+083500Y+076608X0198Y0197R090 S2      
317m0377            VIA   -    MD0100PA00X+085900Y+076400X0200Y         S0      
327m0377            R6312 -2   M      A18X+083900Y+076608X0198Y0197R270 S2      
327m0378            VIA   -    M      A18X+085158Y+077392X0260Y         S2      
327m0378            R1523 -1          A01X+086142Y+077800X0198Y0197     S1      
327m0378            U121  -6          A01X+085430Y+077872X0140Y0590R270 S1      
327m0378            R1527 -1          A18X+083500Y+077392X0198Y0197R270 S2      
317m0378            VIA   -    MD0100PA00X+085900Y+077800X0200Y         S0      
327m0378            R6311 -2   M      A18X+083900Y+077392X0198Y0197R090 S2      
327m0379            VIA   -    M      A18X+085384Y+078408X0260Y         S2      
327m0379            R1522 -1          A01X+086142Y+078200X0198Y0197     S1      
327m0379            U121  -7          A01X+085430Y+078128X0140Y0590R270 S1      
327m0379            R1528 -1          A18X+083500Y+078408X0198Y0197R090 S2      
317m0379            VIA   -    MD0100PA00X+085900Y+078100X0200Y         S0      
327m0379            R6310 -2   M      A18X+083900Y+078408X0198Y0197R270 S2      
327m0380            VIA   -    M      A18X+084452Y+079192X0260Y         S2      
327m0380            R6309 -2   M      A18X+083900Y+079192X0198Y0197R090 S2      
327m0380            R1520 -1          A18X+083500Y+079192X0198Y0197R270 S2      
317m0380            VIA   -    MD0100PA00X+085900Y+079600X0200Y         S0      
327m0380            R1516 -1          A01X+086142Y+079600X0198Y0197     S1      
327m0380            U120  -6          A01X+085430Y+079672X0140Y0590R270 S1      
327m0381            VIA   -    M      A18X+085384Y+080208X0260Y         S2      
327m0381            R1515 -1          A01X+086142Y+080000X0198Y0197     S1      
327m0381            U120  -7          A01X+085430Y+079928X0140Y0590R270 S1      
327m0381            R1521 -1          A18X+083500Y+080208X0198Y0197R090 S2      
317m0381            VIA   -    MD0100PA00X+085900Y+080000X0200Y         S0      
327m0381            R6308 -2   M      A18X+083900Y+080208X0198Y0197R270 S2      
327m0382            VIA   -    M      A18X+085225Y+080992X0260Y         S2      
317m0382            VIA   -    MD0100PA00X+085900Y+081400X0200Y         S0      
327m0382            R1509 -1          A01X+086142Y+081400X0198Y0197     S1      
327m0382            U119  -6          A01X+085430Y+081472X0140Y0590R270 S1      
327m0382            R1513 -1          A18X+083500Y+080992X0198Y0197R270 S2      
327m0382            R6307 -2   M      A18X+083900Y+080992X0198Y0197R090 S2      
327m0383            VIA   -    M      A18X+085385Y+081800X0260Y         S2      
317m0383            VIA   -    MD0100PA00X+085900Y+081800X0200Y         S0      
327m0383            R1508 -1          A01X+086142Y+081800X0198Y0197     S1      
327m0383            U119  -7          A01X+085430Y+081728X0140Y0590R270 S1      
327m0383            R1514 -1          A18X+083500Y+082008X0198Y0197R090 S2      
327m0383            R6306 -2   M      A18X+083900Y+082008X0198Y0197R270 S2      
317m0384            VIA   -    MD0100PA00X+089082Y+087679X0180Y    R270 S0      
327m0384            U5    -N12        A01X+089239Y+087521X0160Y    R180 S1      
327m0384            R6305 -1   M      A01X+084600Y+090158X0198Y0197R270 S1      
317m0384            VIA   -    M      A01X+085899Y+089831X0200Y         S2      
017m0384            VIA   -    M      A18X+085899Y+089831X0260Y         S2      
017m0384                  -    MD0100PA00X+085899Y+089831                       
327m0384            R6214 -1   M      A01X+084200Y+090158X0198Y0197R270 S1      
327m0384            R6215 -1          A01X+083808Y+090150X0198Y0197R180 S1      
327m0385            R6304 -1          A18X+149508Y+031800X0198Y0197     S2      
327m0385            R5819 -1          A01X+145151Y+002639X0198Y0197     S1      
327m0385            R5809 -1          A01X+145123Y+003919X0198Y0197     S1      
317m0385            VIA   -    M      A01X+150100Y+031750X0200Y         S2      
017m0385            VIA   -    M      A18X+150100Y+031750X0260Y         S2      
017m0385                  -    MD0100PA00X+150100Y+031750                       
317m0385            VIA   -    MD0100PA00X+144968Y+003423X0200Y         S0      
317m0385            VIA   -    MD0100PA00X+179066Y+007191X0200Y    R180 S0      
327m0386            R5588 -1   M      A01X+176300Y+158508X0198Y0197R270 S1      
317m0386            VIA   -    M      A01X+176631Y+158020X0200Y         S2      
017m0386            VIA   -    M      A18X+176631Y+158020X0260Y         S2      
017m0386                  -    MD0100PA00X+176631Y+158020                       
327m0386            R5603 -1          A01X+176507Y+159319X0198Y0197R090 S1      
327m0386            R6303 -1          A18X+149462Y+032720X0198Y0197     S2      
317m0386            VIA   -    MD0100PA00X+150150Y+032100X0200Y         S0      
317m0386            VIA   -    MD0100PA00X+171676Y+032618X0200Y         S0      
327m0387            R6266 -1   M      A01X+161672Y+034025X0198Y0197     S1      
327m0387            R6268 -1          A01X+161187Y+034025X0198Y0197R180 S1      
317m0387            VIA   -    MD0100PA00X+109884Y+035340X0200Y         S0      
317m0387            VIA   -    MD0100PA00X+162955Y+032907X0200Y         S0      
327m0387            R1465 -2          A01X+097803Y+034311X0198Y0197R180 S1      
317m0387            VIA   -    M      A01X+097563Y+034311X0200Y         S2      
017m0387            VIA   -    M      A18X+097563Y+034311X0260Y         S2      
017m0387                  -    MD0100PA00X+097563Y+034311                       
317m0387            VIA   -    MD0100PA00X+096835Y+040237X0200Y         S0      
317m0387            VIA   -    MD0100PA00X+089953Y+053075X0200Y         S0      
327m0387            R6302 -1          A01X+089558Y+052963X0198Y0197R180 S1      
317m0387            VIA   -    MD0100PA00X+096846Y+042937X0200Y         S0      
327m0388            R6284 -1          A18X+126973Y+086755X0198Y0197R090 S2      
317m0388            VIA   -    M      A01X+127440Y+086690X0200Y         S2      
017m0388            VIA   -    M      A18X+127440Y+086690X0280Y         S2      
017m0388                  -    MD0100PA00X+127440Y+086690                       
327m0388            U6    -E8         A01X+133738Y+088499X0160Y         S1      
317m0388            VIA   -    MD0100PA00X+133580Y+088656X0180Y         S0      
327m0389            R6269 -2          A01X+160872Y+034425X0198Y0197R180 S1      
327m0389            U421  -3   M      A01X+159956Y+034087X0170Y0460R270 S1      
317m0389            VIA   -    M      A01X+159511Y+034266X0200Y         S2      
017m0389            VIA   -    M      A18X+159511Y+034266X0260Y         S2      
017m0389                  -    MD0100PA00X+159511Y+034266                       
327m0389            R6270 -2          A18X+158858Y+034179X0198Y0197R180 S2      
327m0390            R6268 -2          A01X+160872Y+034025X0198Y0197R180 S1      
327m0390            U421  -2   M      A01X+159956Y+033831X0170Y0460R270 S1      
317m0390            VIA   -    M      A01X+159507Y+033736X0200Y         S2      
017m0390            VIA   -    M      A18X+159507Y+033736X0260Y         S2      
017m0390                  -    MD0100PA00X+159507Y+033736                       
327m0390            R6271 -2          A18X+158858Y+033779X0198Y0197R180 S2      
317CLK_ISO_EN       VIA   -    M      A01X+157478Y+034413X0200Y         S2      
017CLK_ISO_EN       VIA   -    M      A18X+157478Y+034413X0260Y         S2      
017CLK_ISO_EN             -    MD0100PA00X+157478Y+034413                       
327CLK_ISO_EN       U421  -5          A01X+158244Y+034372X0240Y0460R270 S1      
327CLK_ISO_EN       R6265 -1          A01X+157478Y+034160X0198Y0197R180 S1      
317CB_ISO_EN        VIA   -    M      A01X+126350Y+033600X0200Y         S2      
017CB_ISO_EN        VIA   -    M      A18X+126350Y+033600X0260Y         S2      
017CB_ISO_EN              -    MD0100PA00X+126350Y+033600                       
327CB_ISO_EN        U420  -5          A01X+126829Y+033607X0240Y0460R270 S1      
327CB_ISO_EN        R6258 -1          A01X+126108Y+033600X0198Y0197R180 S1      
327SMB_ISO_CB_SDA   R6260 -1          A01X+129858Y+033700X0198Y0197R180 S1      
327SMB_ISO_CB_SDA   R6385 -2          A01X+127966Y+034258X0198Y0197R270 S1      
327SMB_ISO_CB_SDA   U420  -3   M      A01X+128542Y+033322X0170Y0460R270 S1      
317SMB_ISO_CB_SDA   VIA   -    M      A01X+129250Y+033500X0200Y         S2      
017SMB_ISO_CB_SDA   VIA   -    M      A18X+129250Y+033500X0260Y         S2      
017SMB_ISO_CB_SDA         -    MD0100PA00X+129250Y+033500                       
327SMB_ISO_CB_SDA   R6263 -2          A18X+127958Y+033450X0198Y0197R180 S2      
327SMB_ISO_CB_SDA   R1471 -2   M      A01X+129542Y+033350X0198Y0197R180 S1      
327SMB_ISO_CB_SCL   R6259 -1          A01X+129858Y+032650X0198Y0197R180 S1      
327SMB_ISO_CB_SCL   R6384 -2          A01X+127566Y+034264X0198Y0197R270 S1      
327SMB_ISO_CB_SCL   R6264 -2          A18X+127958Y+033050X0198Y0197R180 S2      
317SMB_ISO_CB_SCL   VIA   -    M      A01X+128934Y+033066X0200Y         S2      
017SMB_ISO_CB_SCL   VIA   -    M      A18X+128934Y+033066X0260Y         S2      
017SMB_ISO_CB_SCL         -    MD0100PA00X+128934Y+033066                       
327SMB_ISO_CB_SCL   U420  -2   M      A01X+128542Y+033066X0170Y0460R270 S1      
327SMB_ISO_CB_SCL   R1472 -2   M      A01X+129542Y+033000X0198Y0197R180 S1      
327m0391            R5917 -2          A01X+081675Y+090092X0198Y0197R180 S1      
327m0391            VIA   -    M      A01X+081050Y+090000X0300Y         S1      
327m0391            J59   -1          A01X+079176Y+089329X0500Y1350R090 S1      
327m0392            R5916 -2          A01X+081225Y+089342X0198Y0197R180 S1      
327m0392            VIA   -    M      A01X+080950Y+088750X0300Y         S1      
327m0392            J59   -3          A01X+079176Y+087329X0500Y1350R090 S1      
317m0393            VIA   -    M      A01X+159604Y+149200X0200Y         S2      
017m0393            VIA   -    M      A18X+159604Y+149200X0260Y         S2      
017m0393                  -    MD0100PA00X+159604Y+149200                       
327m0393            R6281 -2          A01X+159450Y+150892X0198Y0197R270 S1      
327m0393            U422  -7   M      A01X+159717Y+149632X0170Y0460R180 S1      
327m0393            R6280 -1   M      A01X+159800Y+150892X0198Y0197R090 S1      
327m0393            R6278 -1          A18X+159604Y+148383X0198Y0197R090 S2      
317m0394            VIA   -    M      A01X+160001Y+148849X0200Y         S2      
017m0394            VIA   -    M      A18X+160001Y+148849X0260Y         S2      
017m0394                  -    MD0100PA00X+160001Y+148849                       
327m0394            R6282 -2          A01X+160500Y+150892X0198Y0197R270 S1      
327m0394            R6279 -1   M      A01X+160150Y+150892X0198Y0197R090 S1      
327m0394            U422  -6   M      A01X+159973Y+149632X0170Y0460R180 S1      
327m0394            R6277 -1          A18X+160001Y+148383X0198Y0197R090 S2      
317BIC_UART_SEL1    VIA   -    MD0100PA00X+082261Y+084853X0200Y    R270 S0      
327BIC_UART_SEL1    U89   -6          A01X+082813Y+084865X0110Y0280R180 S1      
327BIC_UART_SEL1    U88   -6          A01X+081604Y+084857X0110Y0280R180 S1      
317BIC_UART_SEL1    VIA   -    M      A01X+082441Y+093966X0200Y         S2      
017BIC_UART_SEL1    VIA   -    M      A18X+082441Y+093966X0260Y         S2      
017BIC_UART_SEL1          -    MD0100PA00X+082441Y+093966                       
327BIC_UART_SEL1    J60   -2          A01X+078148Y+093381X0500Y1350R090 S1      
327m0395            VIA   -    M      A01X+077054Y+090048X0300Y         S1      
327m0395            J60   -3          A01X+079298Y+092381X0500Y1350R090 S1      
327m0395            J59   -2          A01X+078026Y+088329X0500Y1350R090 S1      
317m0396            VIA   -    M      A01X+089137Y+094113X0200Y         S2      
017m0396            VIA   -    M      A18X+089137Y+094113X0260Y         S2      
017m0396                  -    MD0100PA00X+089137Y+094113                       
317m0396            VIA   -    MD0100PA00X+082962Y+093958X0200Y         S0      
327m0396            J60   -1          A01X+079298Y+094381X0500Y1350R090 S1      
327m0396            R6216 -2          A01X+090406Y+093754X0198Y0197R270 S1      
327m0397            R6269 -1          A01X+161187Y+034425X0198Y0197R180 S1      
327m0397            R6267 -1   M      A01X+161672Y+034425X0198Y0197     S1      
317m0397            VIA   -    M      A01X+110501Y+035350X0200Y         S2      
017m0397            VIA   -    M      A18X+110501Y+035350X0260Y         S2      
017m0397                  -    MD0100PA00X+110501Y+035350                       
317m0397            VIA   -    MD0100PA00X+162951Y+033173X0200Y         S0      
317m0397            VIA   -    MD0100PA00X+040099Y+033559X0200Y         S0      
317m0397            VIA   -    MD0100PA00X+097563Y+034661X0200Y         S0      
327m0397            R1466 -2          A01X+097803Y+034661X0198Y0197R180 S1      
317m0397            VIA   -    MD0100PA00X+097172Y+040776X0200Y         S0      
317m0397            VIA   -    MD0100PA00X+096669Y+042760X0200Y         S0      
317m0397            VIA   -    MD0100PA00X+088593Y+053409X0200Y         S0      
327m0397            R4218 -2          A01X+088593Y+053649X0198Y0197R270 S1      
317m0397            VIA   -    MD0100PA00X+056994Y+037832X0200Y         S0      
327m0397            R1469 -2          A01X+040398Y+033559X0198Y0197R180 S1      
317m0397            VIA   -    MD0100PA00X+051881Y+066287X0200Y         S0      
327m0397            R1467 -2          A18X+051378Y+067338X0198Y0197R090 S2      
317m0397            VIA   -    MD0100PA00X+044091Y+128920X0200Y         S0      
327m0397            R1475 -2          A18X+043791Y+128920X0198Y0197R090 S2      
327m0398            R6302 -2   M      A01X+089242Y+052963X0198Y0197R180 S1      
317m0398            VIA   -    MD0100PA00X+040099Y+033159X0200Y         S0      
327m0398            R4217 -2          A01X+088943Y+053649X0198Y0197R270 S1      
317m0398            VIA   -    M      A01X+057348Y+037470X0200Y         S2      
017m0398            VIA   -    M      A18X+057348Y+037470X0260Y         S2      
017m0398                  -    MD0100PA00X+057348Y+037470                       
327m0398            R1470 -2          A01X+040398Y+033159X0198Y0197R180 S1      
327m0398            R1468 -2          A18X+051778Y+067338X0198Y0197R090 S2      
317m0398            VIA   -    MD0100PA00X+052187Y+066658X0200Y         S0      
327m0398            R1476 -2   M      A18X+052215Y+067112X0198Y0197     S2      
327m0399            U422  -3          A01X+159973Y+147919X0170Y0460R180 S1      
327m0399            R6277 -2          A18X+160001Y+148068X0198Y0197R090 S2      
317m0399            VIA   -    MD0100PA00X+159973Y+147499X0200Y         S0      
317m0399            VIA   -    M      A01X+094421Y+132074X0200Y         S2      
017m0399            VIA   -    M      A18X+094421Y+132074X0260Y         S2      
017m0399                  -    MD0100PA00X+094421Y+132074                       
317m0399            VIA   -    MD0100PA00X+142473Y+130160X0200Y         S0      
317m0399            VIA   -    MD0100PA00X+085118Y+087946X0200Y         S0      
327m0399            R4882 -1          A01X+084303Y+087946X0198Y0197R180 S1      
327m0399            R1485 -2          A01X+085368Y+087946X0198Y0197R180 S1      
317m0399            VIA   -    MD0100PA00X+084807Y+102219X0200Y         S0      
327m0400            U422  -2          A01X+159717Y+147919X0170Y0460R180 S1      
327m0400            R6278 -2          A18X+159604Y+148068X0198Y0197R090 S2      
317m0400            VIA   -    MD0100PA00X+159704Y+147510X0200Y         S0      
317m0400            VIA   -    M      A01X+094731Y+132504X0200Y         S2      
017m0400            VIA   -    M      A18X+094731Y+132504X0260Y         S2      
017m0400                  -    MD0100PA00X+094731Y+132504                       
317m0400            VIA   -    MD0100PA00X+142801Y+130176X0200Y         S0      
327m0400            R4881 -1          A01X+084303Y+088346X0198Y0197R180 S1      
327m0400            R1483 -2          A01X+085368Y+088346X0198Y0197R180 S1      
317m0400            VIA   -    MD0100PA00X+085080Y+088350X0200Y         S0      
317m0400            VIA   -    MD0100PA00X+084804Y+101931X0200Y         S0      
317MB_I3C_ISO_EN    VIA   -    M      A01X+160850Y+150600X0200Y         S2      
017MB_I3C_ISO_EN    VIA   -    M      A18X+160850Y+150600X0260Y         S2      
017MB_I3C_ISO_EN          -    MD0100PA00X+160850Y+150600                       
327MB_I3C_ISO_EN    R6272 -1          A01X+160850Y+150892X0198Y0197R090 S1      
327MB_I3C_ISO_EN    U422  -5          A01X+160258Y+149632X0240Y0460R180 S1      
317m0401            J11   -A3   D0122PA00X+030043Y+162240X0282Y    R180 S3      
327m0401            R6256 -1          A01X+023775Y+153414X0198Y0197R090 S1      
317m0401            VIA   -    M      A01X+023763Y+151191X0200Y         S2      
017m0401            VIA   -    M      A18X+023763Y+151191X0260Y         S2      
017m0401                  -    MD0100PA00X+023763Y+151191                       
327MB_HSC_EN        C4006 -1          A01X+079161Y+159959X0198Y0197R270 S1      
317MB_HSC_EN        VIA   -    M      A01X+078405Y+160044X0200Y    R180 S2      
017MB_HSC_EN        VIA   -    M      A18X+078405Y+160044X0260Y    R180 S2      
017MB_HSC_EN              -    MD0100PA00X+078405Y+160044                       
327MB_HSC_EN        R6253 -1   M      A01X+078745Y+159961X0198Y0197R270 S1      
327MB_HSC_EN        Q123  -2          A01X+077850Y+159826X0170Y0240     S1      
317MB_HSC_EN        VIA   -    MD0100PA00X+074944Y+145878X0200Y         S0      
317MB_HSC_EN        J13   -Z8   D0122PA00X+136571Y+145272X0282Y    R180 S3      
327MB_HSC_EN        C4128 -2   M      A18X+136562Y+142290X0198Y0197     S2      
327m0402            VIA   -           A01X+139142Y+100105X0300Y         S1      
327m0402            PU11  -6          A01X+139046Y+100785X0070Y0240     S1      
327m0403            VIA   -           A01X+139142Y+099605X0300Y         S1      
327m0403            PU11  -5          A01X+138888Y+100785X0070Y0240     S1      
327m0404            PR7136-1          A01X+136984Y+104705X0198Y0197R180 S1      
327m0404            VIA   -    M      A01X+138205Y+104236X0300Y         S1      
327m0404            PU11  -25         A01X+139046Y+102675X0070Y0240     S1      
327m0405            PR7137-1          A01X+136992Y+104314X0198Y0197R180 S1      
327m0405            VIA   -    M      A01X+137607Y+104179X0300Y         S1      
327m0405            PU11  -26         A01X+138888Y+102675X0070Y0240     S1      
327m0406            R1489 -2          A18X+084580Y+087548X0198Y0197R180 S2      
327m0406            R4884 -1          A01X+084582Y+087551X0198Y0197R180 S1      
317m0406            VIA   -    MD0100PA00X+134650Y+092550X0200Y         S0      
317m0406            VIA   -    MD0100PA00X+084838Y+087546X0200Y         S0      
317m0406            VIA   -    M      A01X+085303Y+093469X0200Y         S2      
017m0406            VIA   -    M      A18X+085303Y+093469X0260Y         S2      
017m0406                  -    MD0100PA00X+085303Y+093469                       
327m0406            U6    -A12        A01X+134998Y+089759X0160Y         S1      
317m0407            VIA   -    MD0100PA00X+135151Y+090000X0200Y         S0      
327m0407            U6    -B12        A01X+134998Y+089444X0160Y         S1      
317m0407            VIA   -    MD0100PA00X+131955Y+092558X0200Y         S0      
317m0407            VIA   -    MD0100PA00X+084838Y+087146X0200Y         S0      
327m0407            R4883 -1          A18X+084336Y+087146X0198Y0197     S2      
327m0407            R1487 -2          A18X+085368Y+087146X0198Y0197     S2      
317m0407            VIA   -    M      A01X+085860Y+093450X0200Y         S2      
017m0407            VIA   -    M      A18X+085860Y+093450X0260Y         S2      
017m0407                  -    MD0100PA00X+085860Y+093450                       
317m0408            VIA   -    M      A01X+096233Y+093623X0200Y    R270 S2      
017m0408            VIA   -    M      A18X+096233Y+093623X0260Y    R270 S2      
017m0408                  -    MD0100PA00X+096233Y+093623                       
327m0408            U419  -23         A01X+095979Y+094442X0160Y0540R180 S1      
327m0408            R6243 -1          A01X+096257Y+093339X0198Y0197R270 S1      
317m0409            VIA   -    M      A01X+095724Y+093640X0200Y    R270 S2      
017m0409            VIA   -    M      A18X+095724Y+093640X0260Y    R270 S2      
017m0409                  -    MD0100PA00X+095724Y+093640                       
327m0409            R6241 -1          A01X+095857Y+093339X0198Y0197R270 S1      
327m0409            U419  -22         A01X+095724Y+094442X0160Y0540R180 S1      
317m0410            VIA   -    M      A01X+092974Y+096701X0200Y         S2      
017m0410            VIA   -    M      A18X+092974Y+096701X0260Y         S2      
017m0410                  -    MD0100PA00X+092974Y+096701                       
327m0410            U418  -1          A01X+088643Y+094838X0220Y0530R270 S1      
327m0410            R6257 -2   M      A01X+090613Y+095916X0198Y0197R090 S1      
327m0410            R6244 -1          A01X+094567Y+098882X0198Y0197R270 S1      
317m0411            VIA   -    M      A01X+094567Y+098219X0200Y         S2      
017m0411            VIA   -    M      A18X+094567Y+098219X0260Y         S2      
017m0411                  -    MD0100PA00X+094567Y+098219                       
327m0411            R6244 -2          A01X+094567Y+098567X0198Y0197R270 S1      
327m0411            U419  -5          A01X+095212Y+096746X0160Y0540R180 S1      
317m0412            VIA   -    MD0100PA00X+084874Y+084746X0200Y         S0      
317m0412            VIA   -    M      A01X+087021Y+094938X0200Y         S2      
017m0412            VIA   -    M      A18X+087021Y+094938X0260Y         S2      
017m0412                  -    MD0100PA00X+087021Y+094938                       
327m0412            U418  -2          A01X+088643Y+094464X0220Y0530R270 S1      
327m0412            R6218 -1   M      A01X+087974Y+094428X0198Y0197R270 S1      
327m0412            R5716 -1          A18X+085368Y+084746X0198Y0197R180 S2      
317m0413            VIA   -    M      A01X+090098Y+094090X0200Y         S2      
017m0413            VIA   -    M      A18X+090098Y+094090X0260Y         S2      
017m0413                  -    MD0100PA00X+090098Y+094090                       
327m0413            U418  -4          A01X+089607Y+094090X0220Y0530R270 S1      
327m0413            R6216 -1          A01X+090406Y+094069X0198Y0197R270 S1      
317m0414            VIA   -    M      A01X+094967Y+097792X0200Y         S2      
017m0414            VIA   -    M      A18X+094967Y+097792X0260Y         S2      
017m0414                  -    MD0100PA00X+094967Y+097792                       
327m0414            R6227 -2          A01X+094967Y+098567X0198Y0197R270 S1      
327m0414            U419  -4          A01X+095468Y+096746X0160Y0540R180 S1      
317m0415            VIA   -    M      A01X+096567Y+098219X0200Y         S2      
017m0415            VIA   -    M      A18X+096567Y+098219X0260Y         S2      
017m0415                  -    MD0100PA00X+096567Y+098219                       
327m0415            U419  -1          A01X+096275Y+096746X0240Y0540R180 S1      
327m0415            R6219 -2          A01X+096567Y+098567X0198Y0197R270 S1      
317m0416            VIA   -    M      A01X+095367Y+098219X0200Y         S2      
017m0416            VIA   -    M      A18X+095367Y+098219X0260Y         S2      
017m0416                  -    MD0100PA00X+095367Y+098219                       
327m0416            R6220 -2          A01X+095367Y+098567X0198Y0197R270 S1      
327m0416            U419  -3          A01X+095724Y+096746X0160Y0540R180 S1      
317m0417            VIA   -    M      A01X+095767Y+097792X0200Y         S2      
017m0417            VIA   -    M      A18X+095767Y+097792X0260Y         S2      
017m0417                  -    MD0100PA00X+095767Y+097792                       
327m0417            R6238 -1          A01X+095767Y+098567X0198Y0197R090 S1      
327m0417            R6226 -2   M      A01X+096167Y+098567X0198Y0197R270 S1      
327m0417            U419  -2          A01X+095979Y+096746X0160Y0540R180 S1      
327m0418            J58   -3          A01X+076585Y+140762X0500Y1350R090 S1      
317m0418            VIA   -    M      A01X+079355Y+139769X0200Y         S2      
017m0418            VIA   -    M      A18X+079355Y+139769X0260Y         S2      
017m0418                  -    MD0100PA00X+079355Y+139769                       
327m0418            R6255 -2          A01X+079697Y+139775X0198Y0197R090 S1      
327P3V3_AUX_JTAG    VIA   -           A01X+105336Y+082650X0300Y         S1      
327P3V3_AUX_JTAG    C3991 -2          A01X+105323Y+081746X0280Y0320     S1      
327P3V3_AUX_JTAG    D24   -2          A01X+104514Y+082584X0460Y0690R090 S1      
317P3V3_AUX_JTAG    JP2   -1   MD0410PA00X+103064Y+082455X0610Y0610     S3      
327P3V3_AUX_JTAG    C2811 -2          A01X+101947Y+082598X0198Y0197     S1      
317m0419            VIA   -    M      A01X+095186Y+093617X0200Y    R270 S2      
017m0419            VIA   -    M      A18X+095186Y+093617X0260Y    R270 S2      
017m0419                  -    MD0100PA00X+095186Y+093617                       
327m0419            R6237 -1          A01X+095057Y+093339X0198Y0197R270 S1      
327m0419            U419  -21         A01X+095468Y+094442X0160Y0540R180 S1      
327m0419            R6225 -2   M      A01X+095457Y+093339X0198Y0197R090 S1      
327m0420            VIA   -           A01X+047725Y+099605X0300Y         S1      
327m0420            PU6   -5          A01X+047471Y+100785X0070Y0240     S1      
327m0421            J2    -B9         A01X+090330Y+025039X0150Y0530R090 S1      
317m0421            VIA   -    MD0100PA00X+088715Y+024967X0200Y         S0      
317m0421            VIA   -    MD0100PA00X+084224Y+032485X0200Y         S0      
327m0421            R6215 -2          A01X+083492Y+090150X0198Y0197R180 S1      
317m0421            VIA   -    M      A01X+082480Y+089840X0200Y         S2      
017m0421            VIA   -    M      A18X+082480Y+089840X0260Y         S2      
017m0421                  -    MD0100PA00X+082480Y+089840                       
327m0422            PR7133-1          A01X+045574Y+104314X0198Y0197R180 S1      
327m0422            VIA   -    M      A01X+046190Y+104179X0300Y         S1      
327m0422            PU6   -26         A01X+047471Y+102675X0070Y0240     S1      
327m0423            J58   -2          A01X+075435Y+141762X0500Y1350R090 S1      
327m0423            R6252 -1          A01X+080492Y+148435X0198Y0197     S1      
317m0423            VIA   -    MD0100PA00X+080492Y+148925X0200Y         S0      
317m0423            VIA   -    M      A01X+077706Y+160898X0200Y    R180 S2      
017m0423            VIA   -    M      A18X+077706Y+160898X0260Y    R180 S2      
017m0423                  -    MD0100PA00X+077706Y+160898                       
327m0423            Q123  -5          A01X+077850Y+160574X0170Y0240     S1      
327m0423            Q123  -6          A01X+077594Y+160574X0170Y0240     S1      
317m0423            VIA   -    MD0100PA00X+077868Y+141620X0200Y         S0      
327m0424            PR7132-1          A01X+045567Y+104705X0198Y0197R180 S1      
327m0424            VIA   -    M      A01X+046788Y+104236X0300Y         S1      
327m0424            PU6   -25         A01X+047628Y+102675X0070Y0240     S1      
327m0425            VIA   -           A01X+047725Y+100105X0300Y         S1      
327m0425            PU6   -6          A01X+047628Y+100785X0070Y0240     S1      
317m0426            J3    -X9   D0122PA01X+017917Y+146374X0282Y    R180 S3      
327m0426            C3985 -2          A01X+021956Y+145095X0120Y0150R180 S1      
317m0426            VIA   -    MD0100PA01X+021397Y+145085X0200Y    R180 S0      
317m0427            J3    -V9   D0122PA01X+017917Y+147398X0282Y    R180 S3      
317m0427            VIA   -    MD0080PA01X+015443Y+113317X0160Y         S0      
327m0427            PEX0  -AN4        A01X+015630Y+113504X0180Y         S1      
317m0428            J3    -Y9   D0122PA01X+017917Y+145862X0282Y    R180 S3      
327m0428            C3984 -2          A01X+021956Y+144735X0120Y0150R180 S1      
317m0428            VIA   -    MD0100PA01X+021397Y+144745X0200Y    R180 S0      
317m0429            VIA   -    MD0100PA01X+022725Y+146185X0200Y         S0      
327m0429            C3987 -1          A01X+022166Y+146195X0120Y0150R180 S1      
317m0429            VIA   -    MD0080PA01X+016939Y+113691X0160Y         S0      
327m0429            PEX0  -AM8        A01X+017126Y+113878X0180Y         S1      
317m0430            VIA   -    MD0080PA01X+017313Y+113691X0160Y         S0      
327m0430            PEX0  -AM9        A01X+017500Y+113878X0180Y         S1      
327m0430            C3986 -1          A01X+022166Y+145835X0120Y0150R180 S1      
317m0430            VIA   -    MD0100PA01X+022725Y+145845X0200Y         S0      
317m0431            VIA   -    MD0080PA01X+016191Y+113317X0160Y         S0      
327m0431            PEX0  -AN6        A01X+016378Y+113504X0180Y         S1      
317m0431            VIA   -    MD0100PA01X+022725Y+145085X0200Y         S0      
327m0431            C3985 -1          A01X+022166Y+145095X0120Y0150R180 S1      
317m0432            VIA   -    MD0080PA01X+016565Y+113317X0160Y         S0      
327m0432            PEX0  -AN7        A01X+016752Y+113504X0180Y         S1      
327m0432            C3984 -1          A01X+022166Y+144735X0120Y0150R180 S1      
317m0432            VIA   -    MD0100PA01X+022725Y+144745X0200Y         S0      
317m0433            J3    -T10  D0122PA01X+018784Y+148343X0282Y    R180 S3      
317m0433            VIA   -    MD0080PA01X+014321Y+113691X0160Y         S0      
327m0433            PEX0  -AM1        A01X+014508Y+113878X0180Y         S1      
317m0434            J3    -X10  D0122PA01X+018784Y+146295X0282Y    R180 S3      
327m0434            C3986 -2          A01X+021956Y+145835X0120Y0150R180 S1      
317m0434            VIA   -    MD0100PA01X+021397Y+145845X0200Y    R180 S0      
317m0435            J3    -W10  D0122PA01X+018784Y+146807X0282Y    R180 S3      
327m0435            C3987 -2          A01X+021956Y+146195X0120Y0150R180 S1      
317m0435            VIA   -    MD0100PA01X+021397Y+146185X0200Y    R180 S0      
317m0436            J3    -U10  D0122PA01X+018784Y+147831X0282Y    R180 S3      
317m0436            VIA   -    MD0080PA01X+014695Y+113691X0160Y         S0      
327m0436            PEX0  -AM2        A01X+014882Y+113878X0180Y         S1      
317m0437            J3    -U9   D0122PA01X+017917Y+147910X0282Y    R180 S3      
317m0437            VIA   -    MD0080PA01X+015069Y+113317X0160Y         S0      
327m0437            PEX0  -AN3        A01X+015256Y+113504X0180Y         S1      
317TP_DONE          VIA   -           A01X+140219Y+090827X0200Y         S2      
017TP_DONE          VIA   -           A18X+140219Y+090827X0260Y         S2      
017TP_DONE                -     D0100PA00X+140219Y+090827                       
327TP_DONE          U6    -E17        A01X+136572Y+088499X0160Y         S1      
317TP_DONE          VIA   -    MD0100PA00X+136730Y+088656X0180Y         S0      
317TP_INITN         VIA   -           A01X+139489Y+091478X0200Y         S2      
017TP_INITN         VIA   -           A18X+139489Y+091478X0260Y         S2      
017TP_INITN               -     D0100PA00X+139489Y+091478                       
327TP_INITN         U6    -F16        A01X+136257Y+088184X0160Y         S1      
317TP_INITN         VIA   -    MD0100PA00X+136415Y+088341X0180Y         S0      
327BIC_SPI1DQ3      VIA   -    M      A18X+091970Y+082683X0260Y         S2      
317BIC_SPI1DQ3      VIA   -    MD0100PA00X+091916Y+083899X0180Y         S0      
327BIC_SPI1DQ3      U5    -B4         A01X+091759Y+084057X0160Y    R180 S1      
327BIC_SPI1DQ3      R6152 -1          A18X+091740Y+082208X0198Y0197     S2      
327BIC_SPI1DQ2      VIA   -    M      A18X+092192Y+082210X0260Y         S2      
317BIC_SPI1DQ2      VIA   -    MD0100PA00X+091916Y+083584X0180Y         S0      
327BIC_SPI1DQ2      U5    -A4         A01X+091759Y+083742X0160Y    R180 S1      
327BIC_SPI1DQ2      R6151 -1          A18X+091750Y+081798X0198Y0197     S2      
327m0438            VIA   -    M      A18X+100541Y+089279X0260Y         S2      
327m0438            U67   -12         A18X+099305Y+088323X0140Y0610R180 S2      
327m0438            R3480 -2          A18X+100541Y+089742X0198Y0197R090 S2      
327BIC_FWSPIDQ3     U5    -D5         A01X+091444Y+084687X0160Y    R180 S1      
317BIC_FWSPIDQ3     VIA   -    MD0100PA00X+091601Y+084529X0180Y         S0      
327BIC_FWSPIDQ3     R6150 -1          A01X+094961Y+079923X0198Y0197     S1      
317BIC_FWSPIDQ3     VIA   -    M      A01X+095749Y+079855X0200Y         S2      
017BIC_FWSPIDQ3     VIA   -    M      A18X+095749Y+079855X0260Y         S2      
017BIC_FWSPIDQ3           -    MD0100PA00X+095749Y+079855                       
317BIC_FWSPIDQ2     VIA   -    MD0100PA00X+090656Y+084529X0180Y    R270 S0      
317BIC_FWSPIDQ2     VIA   -    M      A01X+095070Y+077971X0200Y         S2      
017BIC_FWSPIDQ2     VIA   -    M      A18X+095070Y+077971X0260Y         S2      
017BIC_FWSPIDQ2           -    MD0100PA00X+095070Y+077971                       
327BIC_FWSPIDQ2     R6149 -1          A01X+094945Y+078247X0198Y0197     S1      
327BIC_FWSPIDQ2     U5    -D8         A01X+090499Y+084687X0160Y    R180 S1      
317BIC_FWSPICS1_N   VIA   -    M      A01X+094697Y+078637X0200Y         S2      
017BIC_FWSPICS1_N   VIA   -    M      A18X+094697Y+078637X0260Y         S2      
017BIC_FWSPICS1_N         -    MD0100PA00X+094697Y+078637                       
327BIC_FWSPICS1_N   R6148 -1          A01X+094938Y+078637X0198Y0197     S1      
327BIC_FWSPICS1_N   U5    -F7         A01X+090814Y+085317X0160Y    R180 S1      
317BIC_FWSPICS1_N   VIA   -    MD0100PA00X+090971Y+085159X0180Y         S0      
317m0439            VIA   -    M      A01X+046329Y+129704X0200Y         S2      
017m0439            VIA   -    M      A18X+046329Y+129704X0260Y         S2      
017m0439                  -    MD0100PA00X+046329Y+129704                       
327m0439            PJ20  -2          A18X+052714Y+129300X0180Y0200R180 S2      
317m0439            VIA   -    MD0100PA00X+046578Y+119347X0200Y         S0      
327m0439            PR79  -2          A18X+046830Y+119347X0198Y0197     S2      
327m0439            PJ6   -1          A01X+045609Y+103572X0280Y0740     S1      
317m0439            VIA   -    MD0100PA00X+045970Y+103572X0200Y         S0      
317m0440            VIA   -    M      A01X+130200Y+091700X0200Y         S2      
017m0440            VIA   -    M      A18X+130200Y+091700X0260Y         S2      
017m0440                  -    MD0100PA00X+130200Y+091700                       
327m0440            R6147 -2          A01X+130200Y+091992X0198Y0197R270 S1      
327m0440            U6    -B3         A01X+132163Y+089444X0160Y         S1      
317m0440            VIA   -    MD0100PA00X+131950Y+090500X0200Y         S0      
317m0441            VIA   -    M      A01X+048563Y+103616X0200Y         S2      
017m0441            VIA   -    M      A18X+048563Y+103616X0260Y         S2      
017m0441                  -    MD0100PA00X+048563Y+103616                       
327m0441            PC49  -2   M      A01X+048221Y+103168X0198Y0197R180 S1      
327m0441            PU6   -22         A01X+048101Y+102675X0070Y0240     S1      
317m0441            VIA   -    MD0100PA00X+046128Y+119747X0200Y         S0      
327m0441            PR78  -1          A18X+045877Y+119747X0198Y0197     S2      
317m0441            VIA   -    MD0100PA00X+040432Y+127589X0200Y         S0      
327m0441            PJ19  -2          A18X+039882Y+127629X0180Y0200     S2      
317m0442            VIA   -    MD0080PA00X+155561Y+113691X0160Y         S0      
327m0442            PEX3  -AM12       A01X+155748Y+113878X0180Y         S1      
327m0442            VIA   -           A18X+155744Y+113504X0260Y         S2      
317m0443            VIA   -    MD0080PA00X+109852Y+113691X0160Y         S0      
327m0443            PEX2  -AM12       A01X+110039Y+113878X0180Y         S1      
327m0443            VIA   -           A18X+110036Y+113504X0260Y         S2      
317m0444            VIA   -    MD0080PA00X+064144Y+113691X0160Y         S0      
327m0444            PEX1  -AM12       A01X+064331Y+113878X0180Y         S1      
327m0444            VIA   -           A18X+064327Y+113504X0260Y         S2      
317m0445            VIA   -    MD0080PA00X+018435Y+113691X0160Y         S0      
327m0445            PEX0  -AM12       A01X+018622Y+113878X0180Y         S1      
327m0445            VIA   -           A18X+018618Y+113504X0260Y         S2      
327m0446            PJ5   -1          A01X+048984Y+103768X0280Y0740R090 S1      
317m0446            VIA   -    MD0100PA00X+048568Y+103988X0200Y         S0      
327m0446            PJ18  -2          A18X+039882Y+127209X0180Y0200     S2      
317m0446            VIA   -    M      A01X+040432Y+127189X0200Y    R180 S2      
017m0446            VIA   -    M      A18X+040432Y+127189X0260Y    R180 S2      
017m0446                  -    MD0100PA00X+040432Y+127189                       
327m0446            PR76  -2          A18X+045877Y+119347X0198Y0197R180 S2      
317m0446            VIA   -    MD0100PA00X+046128Y+119347X0200Y         S0      
327m0447            R6171 -1          A18X+148726Y+089162X0198Y0197R180 S2      
317m0447            VIA   -    M      A01X+148220Y+088581X0200Y         S2      
017m0447            VIA   -    M      A18X+148220Y+088581X0260Y         S2      
017m0447                  -    MD0100PA00X+148220Y+088581                       
327m0447            JPEX3 -3          A01X+146804Y+088030X0200Y0600R090 S1      
327m0447            U321  -3   M      A01X+146804Y+088030X0320Y0750R090 S1      
327m0447            R6172 -1   M      A18X+148711Y+088777X0198Y0197R090 S2      
327m0447            R6173 -1          A18X+149111Y+088777X0198Y0197R090 S2      
327m0448            JPEX2 -3   M      A01X+101063Y+088030X0200Y0600R090 S1      
327m0448            R6169 -1   M      A18X+102954Y+088884X0198Y0197R180 S2      
327m0448            R6170 -1   M      A18X+102954Y+088484X0198Y0197R180 S2      
327m0448            R6168 -1          A18X+102954Y+089284X0198Y0197R180 S2      
317m0448            VIA   -    M      A01X+102491Y+088400X0200Y         S2      
017m0448            VIA   -    M      A18X+102491Y+088400X0260Y         S2      
017m0448                  -    MD0100PA00X+102491Y+088400                       
327m0448            U319  -3   M      A01X+101126Y+088030X0320Y0750R090 S1      
327m0449            R6166 -1   M      A18X+057246Y+088884X0198Y0197R180 S2      
327m0449            R6167 -1   M      A18X+057246Y+088484X0198Y0197R180 S2      
327m0449            R6165 -1          A18X+057246Y+089284X0198Y0197R180 S2      
317m0449            VIA   -    M      A01X+056783Y+088400X0200Y         S2      
017m0449            VIA   -    M      A18X+056783Y+088400X0260Y         S2      
017m0449                  -    MD0100PA00X+056783Y+088400                       
327m0449            U320  -3   M      A01X+055387Y+088030X0320Y0750R090 S1      
327m0449            JPEX1 -3          A01X+055387Y+088030X0200Y0600R090 S1      
317m0450            VIA   -    M      A01X+041060Y+156102X0200Y         S2      
017m0450            VIA   -    M      A18X+041060Y+156102X0260Y         S2      
017m0450                  -    MD0100PA00X+041060Y+156102                       
327m0450            U353  -17         A01X+040896Y+155341X0100Y0290R180 S1      
327m0450            R5456 -1   M      A01X+041346Y+156343X0198Y0197R090 S1      
327m0450            R5446 -2   M      A01X+041746Y+156343X0198Y0197R270 S1      
327m0450            R6181 -2          A01X+042146Y+156343X0198Y0197R270 S1      
327m0450            C3637 -1   M      A01X+040946Y+156343X0198Y0197R090 S1      
317m0451            VIA   -    MD0100PA00X+045929Y+129704X0200Y         S0      
327m0451            PJ21  -2          A18X+052714Y+128880X0180Y0200R180 S2      
317m0451            VIA   -    MD0100PA00X+046578Y+119747X0200Y         S0      
327m0451            PR81  -1          A18X+046830Y+119747X0198Y0197R180 S2      
327m0451            PU6   -31         A01X+046605Y+102439X0070Y0240R090 S1      
327m0451            PC50  -2   M      A01X+046109Y+102784X0198Y0197R090 S1      
317m0451            VIA   -    M      A01X+045970Y+103227X0200Y         S2      
017m0451            VIA   -    M      A18X+045970Y+103227X0260Y         S2      
017m0451                  -    MD0100PA00X+045970Y+103227                       
327m0452            PJ8   -1          A01X+137026Y+103572X0280Y0740     S1      
317m0452            VIA   -    MD0100PA00X+137387Y+103572X0200Y         S0      
317m0452            VIA   -    M      A01X+138905Y+130314X0200Y         S2      
017m0452            VIA   -    M      A18X+138905Y+130314X0260Y         S2      
017m0452                  -    MD0100PA00X+138905Y+130314                       
317m0452            VIA   -    MD0100PA00X+137996Y+119347X0200Y         S0      
327m0452            PR128 -2          A18X+138247Y+119347X0198Y0197     S2      
327m0452            PJ24  -2          A18X+144131Y+129300X0180Y0200R180 S2      
317m0453            VIA   -    MD0100PA00X+138505Y+130314X0200Y         S0      
317m0453            VIA   -    MD0100PA00X+137996Y+119747X0200Y         S0      
327m0453            PR130 -1          A18X+138247Y+119747X0198Y0197R180 S2      
327m0453            PU11  -31         A01X+138022Y+102439X0070Y0240R090 S1      
327m0453            PC130 -2   M      A01X+137526Y+102784X0198Y0197R090 S1      
317m0453            VIA   -    M      A01X+137387Y+103227X0200Y         S2      
017m0453            VIA   -    M      A18X+137387Y+103227X0260Y         S2      
017m0453                  -    MD0100PA00X+137387Y+103227                       
327m0453            PJ25  -2          A18X+144131Y+128880X0180Y0200R180 S2      
317m0454            VIA   -    M      A01X+131829Y+129138X0200Y         S2      
017m0454            VIA   -    M      A18X+131829Y+129138X0260Y         S2      
017m0454                  -    MD0100PA00X+131829Y+129138                       
317m0454            VIA   -    MD0100PA00X+137546Y+119347X0200Y         S0      
327m0454            PR125 -2          A18X+137295Y+119347X0198Y0197R180 S2      
327m0454            PJ22  -2          A18X+131289Y+129111X0180Y0200     S2      
317m0454            VIA   -    MD0100PA00X+139985Y+103978X0200Y         S0      
327m0454            PJ7   -1          A01X+140401Y+103768X0280Y0740R090 S1      
327m0455            PC129 -2   M      A01X+139638Y+103168X0198Y0197R180 S1      
327m0455            PU11  -22         A01X+139518Y+102675X0070Y0240     S1      
317m0455            VIA   -    M      A01X+139981Y+103616X0200Y         S2      
017m0455            VIA   -    M      A18X+139981Y+103616X0260Y         S2      
017m0455                  -    MD0100PA00X+139981Y+103616                       
317m0455            VIA   -    MD0100PA00X+137546Y+119747X0200Y         S0      
327m0455            PR127 -1          A18X+137295Y+119747X0198Y0197     S2      
317m0455            VIA   -    MD0100PA00X+131829Y+129538X0200Y         S0      
327m0455            PJ23  -2          A18X+131289Y+129531X0180Y0200     S2      
317SPI_PEX3_RST_N   VIA   -    MD0080PA00X+153691Y+115561X0160Y         S0      
327SPI_PEX3_RST_N   R6171 -2          A18X+149041Y+089162X0198Y0197R180 S2      
317SPI_PEX3_RST_N   VIA   -    M      A01X+149495Y+089526X0200Y         S2      
017SPI_PEX3_RST_N   VIA   -    M      A18X+149495Y+089526X0260Y         S2      
017SPI_PEX3_RST_N         -    MD0100PA00X+149495Y+089526                       
317SPI_PEX3_RST_N   VIA   -    MD0100PA00X+153207Y+104183X0200Y         S0      
327SPI_PEX3_RST_N   PEX3  -AG7        A01X+153878Y+115748X0180Y         S1      
317SPI_PEX2_RST_N   VIA   -    MD0080PA00X+107982Y+115561X0160Y         S0      
317SPI_PEX2_RST_N   VIA   -    MD0100PA00X+107918Y+103788X0200Y         S0      
317SPI_PEX2_RST_N   VIA   -    M      A01X+103801Y+090256X0200Y         S2      
017SPI_PEX2_RST_N   VIA   -    M      A18X+103801Y+090256X0260Y         S2      
017SPI_PEX2_RST_N         -    MD0100PA00X+103801Y+090256                       
327SPI_PEX2_RST_N   PEX2  -AG7        A01X+108169Y+115748X0180Y         S1      
327SPI_PEX2_RST_N   R6168 -2          A18X+103269Y+089284X0198Y0197R180 S2      
317SPI_PEX1_RST_N   VIA   -    MD0080PA00X+062274Y+115561X0160Y         S0      
327SPI_PEX1_RST_N   R6165 -2          A18X+057561Y+089284X0198Y0197R180 S2      
317SPI_PEX1_RST_N   VIA   -    M      A01X+058033Y+089200X0200Y         S2      
017SPI_PEX1_RST_N   VIA   -    M      A18X+058033Y+089200X0260Y         S2      
017SPI_PEX1_RST_N         -    MD0100PA00X+058033Y+089200                       
317SPI_PEX1_RST_N   VIA   -    MD0100PA00X+061789Y+104396X0200Y         S0      
327SPI_PEX1_RST_N   PEX1  -AG7        A01X+062461Y+115748X0180Y         S1      
327m0456            R6163 -1   M      A18X+011552Y+088884X0198Y0197R180 S2      
317m0456            VIA   -    M      A01X+011089Y+088400X0200Y         S2      
017m0456            VIA   -    M      A18X+011089Y+088400X0260Y         S2      
017m0456                  -    MD0100PA00X+011089Y+088400                       
327m0456            U317  -3   M      A01X+009693Y+088030X0320Y0750R090 S1      
327m0456            JPEX0 -3          A01X+009693Y+088030X0200Y0600R090 S1      
327m0456            R6164 -1   M      A18X+011552Y+088484X0198Y0197R180 S2      
327m0456            R6162 -1          A18X+011552Y+089284X0198Y0197R180 S2      
317SPI_PEX0_RST_N   VIA   -    MD0080PA00X+016565Y+115561X0160Y         S0      
327SPI_PEX0_RST_N   R6162 -2          A18X+011867Y+089284X0198Y0197R180 S2      
317SPI_PEX0_RST_N   VIA   -    M      A01X+012339Y+089200X0200Y         S2      
017SPI_PEX0_RST_N   VIA   -    M      A18X+012339Y+089200X0260Y         S2      
017SPI_PEX0_RST_N         -    MD0100PA00X+012339Y+089200                       
317SPI_PEX0_RST_N   VIA   -    MD0100PA00X+016081Y+104396X0200Y         S0      
327SPI_PEX0_RST_N   PEX0  -AG7        A01X+016752Y+115748X0180Y         S1      
317m0457            VIA   -    M      A01X+084286Y+094915X0200Y    R090 S2      
017m0457            VIA   -    M      A18X+084286Y+094915X0260Y    R090 S2      
017m0457                  -    MD0100PA00X+084286Y+094915                       
327m0457            R6161 -2          A01X+084042Y+095912X0198Y0197R270 S1      
327m0457            U123  -5          A01X+083910Y+095290X0240Y0460R180 S1      
317m0458            VIA   -    M      A01X+180936Y+044211X0200Y    R270 S2      
017m0458            VIA   -    M      A18X+180936Y+044211X0260Y    R270 S2      
017m0458                  -    MD0100PA00X+180936Y+044211                       
327m0458            PR7060-2          A01X+180683Y+044211X0198Y0197R090 S1      
327m0458            PC837 -1          A01X+181186Y+044310X0198Y0197     S1      
327m0459            PU103 -11         A01X+095392Y+061734X0100Y0320R270 S1      
327m0459            PR7029-1          A01X+094816Y+061689X0198Y0197R270 S1      
317m0459            VIA   -           A01X+095067Y+061690X0200Y         S2      
017m0459            VIA   -           A18X+095067Y+061690X0260Y         S2      
017m0459                  -     D0100PA00X+095067Y+061690                       
327m0459            PR7021-1          A01X+094036Y+061689X0198Y0197R270 S1      
327m0459            PR7024-1          A01X+094436Y+061689X0198Y0197R270 S1      
317m0460            VIA   -    M      A01X+180934Y+044712X0200Y    R270 S2      
017m0460            VIA   -    M      A18X+180934Y+044712X0260Y    R270 S2      
017m0460                  -    MD0100PA00X+180934Y+044712                       
327m0460            PU106 -6          A01X+180044Y+044207X0100Y0320R090 S1      
327m0460            PC835 -1          A01X+181186Y+044710X0198Y0197     S1      
327m0461            PC810 -2          A01X+095426Y+060731X0280Y0320R270 S1      
327m0461            PU103 -12         A01X+095549Y+061380X0100Y0320R180 S1      
317m0461            VIA   -           A01X+095454Y+061055X0200Y         S2      
017m0461            VIA   -           A18X+095454Y+061055X0260Y         S2      
017m0461                  -     D0100PA00X+095454Y+061055                       
327m0461            PR7023-1          A01X+095426Y+060181X0280Y0320R090 S1      
327m0461            PR7020-2          A01X+095470Y+059739X0198Y0197R180 S1      
317m0462            VIA   -    M      A01X+142545Y+063347X0200Y         S2      
017m0462            VIA   -    M      A18X+142545Y+063347X0260Y         S2      
017m0462                  -    MD0100PA00X+142545Y+063347                       
327m0462            PU105 -4          A01X+142242Y+062482X0100Y0320R180 S1      
327m0462            PC833 -1          A01X+142545Y+063624X0198Y0197R090 S1      
317m0463            VIA   -    M      A01X+135226Y+045260X0200Y    R270 S2      
017m0463            VIA   -    M      A18X+135226Y+045260X0260Y    R270 S2      
017m0463                  -    MD0100PA00X+135226Y+045260                       
327m0463            PU104 -8          A01X+134336Y+044601X0100Y0320R090 S1      
327m0463            PR7038-1          A01X+135477Y+045260X0198Y0197     S1      
317m0464            VIA   -    M      A01X+140784Y+062771X0200Y         S2      
017m0464            VIA   -    M      A18X+140784Y+062771X0260Y         S2      
017m0464                  -    MD0100PA00X+140784Y+062771                       
327m0464            PU105 -9          A01X+141258Y+062482X0100Y0320R180 S1      
327m0464            PR7052-1          A01X+140453Y+062931X0198Y0197R180 S1      
317m0465            VIA   -    M      A01X+134661Y+044010X0200Y    R270 S2      
017m0465            VIA   -    M      A18X+134661Y+044010X0260Y    R270 S2      
017m0465                  -    MD0100PA00X+134661Y+044010                       
327m0465            PR7037-1          A01X+135477Y+043910X0198Y0197     S1      
327m0465            PU104 -5          A01X+134336Y+044010X0100Y0320R090 S1      
327m0465            PR7034-1   M      A01X+134975Y+043896X0198Y0197R090 S1      
327m0466            PR7055-1          A01X+179251Y+045910X0198Y0197R180 S1      
327m0466            PR7050-1          A01X+179251Y+046310X0198Y0197R180 S1      
327m0466            PU106 -11         A01X+179296Y+044955X0100Y0320R180 S1      
327m0466            PR7059-1          A01X+179251Y+045530X0198Y0197R180 S1      
317m0466            VIA   -           A01X+179253Y+045280X0200Y    R270 S2      
017m0466            VIA   -           A18X+179253Y+045280X0260Y    R270 S2      
017m0466                  -     D0100PA00X+179253Y+045280                       
327m0467            PU106 -12         A01X+178942Y+044798X0100Y0320R090 S1      
327m0467            PR7054-1          A01X+177743Y+044920X0280Y0320     S1      
327m0467            PC832 -2          A01X+178293Y+044920X0280Y0320R180 S1      
317m0467            VIA   -           A01X+178617Y+044893X0200Y    R270 S2      
017m0467            VIA   -           A18X+178617Y+044893X0260Y    R270 S2      
017m0467                  -     D0100PA00X+178617Y+044893                       
327m0467            PR7049-2          A01X+177242Y+044861X0198Y0197R090 S1      
317m0468            VIA   -    M      A01X+134082Y+045299X0200Y    R270 S2      
017m0468            VIA   -    M      A18X+134082Y+045299X0260Y    R270 S2      
017m0468                  -    MD0100PA00X+134082Y+045299                       
327m0468            PU104 -10         A01X+133981Y+044955X0100Y0320R180 S1      
327m0468            R5967 -1          A01X+134385Y+045603X0198Y0197R090 S1      
327m0468            R953  -2   M      A01X+133985Y+045603X0198Y0197R270 S1      
327m0469            PU105 -11         A01X+141100Y+061734X0100Y0320R270 S1      
327m0469            PR7053-1          A01X+140525Y+061689X0198Y0197R270 S1      
327m0469            PR7048-1          A01X+140145Y+061689X0198Y0197R270 S1      
317m0469            VIA   -           A01X+140775Y+061690X0200Y         S2      
017m0469            VIA   -           A18X+140775Y+061690X0260Y         S2      
017m0469                  -     D0100PA00X+140775Y+061690                       
327m0469            PR7045-1          A01X+139745Y+061689X0198Y0197R270 S1      
317m0470            VIA   -    M      A01X+135227Y+044211X0200Y    R270 S2      
017m0470            VIA   -    M      A18X+135227Y+044211X0260Y    R270 S2      
017m0470                  -    MD0100PA00X+135227Y+044211                       
327m0470            PR7034-2          A01X+134975Y+044211X0198Y0197R090 S1      
327m0470            PC817 -1          A01X+135477Y+044310X0198Y0197     S1      
317m0471            VIA   -    M      A01X+180353Y+043111X0200Y    R270 S2      
017m0471            VIA   -    M      A18X+180353Y+043111X0260Y    R270 S2      
017m0471                  -    MD0100PA00X+180353Y+043111                       
327m0471            PU106 -1          A01X+180035Y+043223X0098Y0335R090 S1      
327m0471            R962  -2   M      A01X+181186Y+043160X0198Y0197R180 S1      
327m0471            R961  -2          A01X+181186Y+042460X0198Y0197R180 S1      
327m0471            C982  -2   M      A01X+181186Y+042810X0198Y0197R180 S1      
317m0472            VIA   -    M      A01X+141343Y+063372X0200Y         S2      
017m0472            VIA   -    M      A18X+141343Y+063372X0260Y         S2      
017m0472                  -    MD0100PA00X+141343Y+063372                       
327m0472            PU105 -6          A01X+141848Y+062482X0100Y0320R180 S1      
327m0472            PC831 -1          A01X+141345Y+063624X0198Y0197R090 S1      
317m0473            VIA   -    M      A01X+180370Y+044010X0200Y    R270 S2      
017m0473            VIA   -    M      A18X+180370Y+044010X0260Y    R270 S2      
017m0473                  -    MD0100PA00X+180370Y+044010                       
327m0473            PU106 -5          A01X+180044Y+044010X0100Y0320R090 S1      
327m0473            PR7060-1   M      A01X+180683Y+043896X0198Y0197R090 S1      
327m0473            PR7061-1          A01X+181186Y+043910X0198Y0197     S1      
317m0474            VIA   -    M      A01X+140795Y+063372X0200Y         S2      
017m0474            VIA   -    M      A18X+140795Y+063372X0260Y         S2      
017m0474                  -    MD0100PA00X+140795Y+063372                       
327m0474            PR7057-1          A01X+140795Y+063624X0198Y0197R090 S1      
327m0474            PU105 -8          A01X+141455Y+062482X0100Y0320R180 S1      
327m0475            PU104 -12         A01X+133233Y+044798X0100Y0320R090 S1      
327m0475            PC812 -2          A01X+132585Y+044920X0280Y0320R180 S1      
327m0475            PR7030-1          A01X+132035Y+044920X0280Y0320     S1      
317m0475            VIA   -           A01X+132908Y+044893X0200Y    R270 S2      
017m0475            VIA   -           A18X+132908Y+044893X0260Y    R270 S2      
017m0475                  -     D0100PA00X+132908Y+044893                       
327m0475            PR7025-2          A01X+131534Y+044861X0198Y0197R090 S1      
317m0476            VIA   -    M      A01X+096836Y+063347X0200Y         S2      
017m0476            VIA   -    M      A18X+096836Y+063347X0260Y         S2      
017m0476                  -    MD0100PA00X+096836Y+063347                       
327m0476            PU103 -4          A01X+096533Y+062482X0100Y0320R180 S1      
327m0476            PC813 -1          A01X+096836Y+063624X0198Y0197R090 S1      
317m0477            VIA   -    M      A01X+179791Y+045299X0200Y    R270 S2      
017m0477            VIA   -    M      A18X+179791Y+045299X0260Y    R270 S2      
017m0477                  -    MD0100PA00X+179791Y+045299                       
327m0477            PU106 -10         A01X+179690Y+044955X0100Y0320R180 S1      
327m0477            R5969 -1          A01X+180093Y+045603X0198Y0197R090 S1      
327m0477            R959  -2   M      A01X+179693Y+045603X0198Y0197R270 S1      
317m0478            VIA   -    M      A01X+095634Y+063372X0200Y         S2      
017m0478            VIA   -    M      A18X+095634Y+063372X0260Y         S2      
017m0478                  -    MD0100PA00X+095634Y+063372                       
327m0478            PU103 -6          A01X+096140Y+062482X0100Y0320R180 S1      
327m0478            PC811 -1          A01X+095636Y+063624X0198Y0197R090 S1      
317m0479            VIA   -    M      A01X+140757Y+062228X0200Y         S2      
017m0479            VIA   -    M      A18X+140757Y+062228X0260Y         S2      
017m0479                  -    MD0100PA00X+140757Y+062228                       
327m0479            R5968 -1          A01X+140453Y+062531X0198Y0197R180 S1      
327m0479            R957  -2   M      A01X+140453Y+062131X0198Y0197     S1      
327m0479            PU105 -10         A01X+141100Y+062128X0100Y0320R270 S1      
317m0480            VIA   -    M      A01X+180935Y+045260X0200Y    R270 S2      
017m0480            VIA   -    M      A18X+180935Y+045260X0260Y    R270 S2      
017m0480                  -    MD0100PA00X+180935Y+045260                       
327m0480            PU106 -8          A01X+180044Y+044601X0100Y0320R090 S1      
327m0480            PR7062-1          A01X+181186Y+045260X0198Y0197     S1      
317m0481            VIA   -    M      A01X+134625Y+045272X0200Y    R270 S2      
017m0481            VIA   -    M      A18X+134625Y+045272X0260Y    R270 S2      
017m0481                  -    MD0100PA00X+134625Y+045272                       
327m0481            PU104 -9          A01X+134336Y+044798X0100Y0320R090 S1      
327m0481            PR7035-1          A01X+134785Y+045603X0198Y0197R090 S1      
317m0482            VIA   -    M      A01X+141844Y+063374X0200Y         S2      
017m0482            VIA   -    M      A18X+141844Y+063374X0260Y         S2      
017m0482                  -    MD0100PA00X+141844Y+063374                       
327m0482            PC834 -1          A01X+141745Y+063624X0198Y0197R090 S1      
327m0482            PR7051-2          A01X+141844Y+063121X0198Y0197R180 S1      
317m0483            VIA   -    M      A01X+095075Y+062771X0200Y         S2      
017m0483            VIA   -    M      A18X+095075Y+062771X0260Y         S2      
017m0483                  -    MD0100PA00X+095075Y+062771                       
327m0483            PU103 -9          A01X+095549Y+062482X0100Y0320R180 S1      
327m0483            PR7028-1          A01X+094744Y+062931X0198Y0197R180 S1      
327m0484            PR7031-1          A01X+133542Y+045910X0198Y0197R180 S1      
327m0484            PR7026-1          A01X+133542Y+046310X0198Y0197R180 S1      
327m0484            PU104 -11         A01X+133588Y+044955X0100Y0320R180 S1      
327m0484            PR7036-1          A01X+133542Y+045530X0198Y0197R180 S1      
317m0484            VIA   -           A01X+133544Y+045280X0200Y    R270 S2      
017m0484            VIA   -           A18X+133544Y+045280X0260Y    R270 S2      
017m0484                  -     D0100PA00X+133544Y+045280                       
317m0485            VIA   -    M      A01X+135225Y+044712X0200Y    R270 S2      
017m0485            VIA   -    M      A18X+135225Y+044712X0260Y    R270 S2      
017m0485                  -    MD0100PA00X+135225Y+044712                       
327m0485            PU104 -6          A01X+134336Y+044207X0100Y0320R090 S1      
327m0485            PC816 -1          A01X+135477Y+044710X0198Y0197     S1      
317m0486            VIA   -    M      A01X+095048Y+062228X0200Y         S2      
017m0486            VIA   -    M      A18X+095048Y+062228X0260Y         S2      
017m0486                  -    MD0100PA00X+095048Y+062228                       
327m0486            R5966 -1          A01X+094744Y+062531X0198Y0197R180 S1      
327m0486            R951  -2   M      A01X+094744Y+062131X0198Y0197     S1      
327m0486            PU103 -10         A01X+095392Y+062128X0100Y0320R270 S1      
317m0487            VIA   -    M      A01X+143018Y+062785X0200Y         S2      
017m0487            VIA   -    M      A18X+143018Y+062785X0260Y         S2      
017m0487                  -    MD0100PA00X+143018Y+062785                       
327m0487            R958  -2          A01X+143595Y+063624X0198Y0197R270 S1      
327m0487            C981  -2   M      A01X+143245Y+063624X0198Y0197R270 S1      
327m0487            R960  -2   M      A01X+142895Y+063624X0198Y0197R270 S1      
327m0487            PU105 -1          A01X+142833Y+062472X0098Y0335R180 S1      
317m0488            VIA   -    M      A01X+095086Y+063372X0200Y         S2      
017m0488            VIA   -    M      A18X+095086Y+063372X0260Y         S2      
017m0488                  -    MD0100PA00X+095086Y+063372                       
327m0488            PU103 -8          A01X+095746Y+062482X0100Y0320R180 S1      
327m0488            PR7033-1          A01X+095086Y+063624X0198Y0197R090 S1      
317m0489            VIA   -    M      A01X+135201Y+043510X0200Y    R270 S2      
017m0489            VIA   -    M      A18X+135201Y+043510X0260Y    R270 S2      
017m0489                  -    MD0100PA00X+135201Y+043510                       
327m0489            PU104 -4          A01X+134336Y+043813X0100Y0320R090 S1      
327m0489            PC815 -1          A01X+135477Y+043510X0198Y0197     S1      
317m0490            VIA   -    M      A01X+097235Y+062791X0200Y         S2      
017m0490            VIA   -    M      A18X+097235Y+062791X0260Y         S2      
017m0490                  -    MD0100PA00X+097235Y+062791                       
327m0490            R952  -2          A01X+097886Y+063624X0198Y0197R270 S1      
327m0490            C843  -2   M      A01X+097536Y+063624X0198Y0197R270 S1      
327m0490            R954  -2   M      A01X+097186Y+063624X0198Y0197R270 S1      
327m0490            PU103 -1          A01X+097124Y+062472X0098Y0335R180 S1      
317m0491            VIA   -    M      A01X+180334Y+045272X0200Y    R270 S2      
017m0491            VIA   -    M      A18X+180334Y+045272X0260Y    R270 S2      
017m0491                  -    MD0100PA00X+180334Y+045272                       
327m0491            PU106 -9          A01X+180044Y+044798X0100Y0320R090 S1      
327m0491            PR7058-1          A01X+180493Y+045603X0198Y0197R090 S1      
317m0492            VIA   -    M      A01X+096135Y+063374X0200Y         S2      
017m0492            VIA   -    M      A18X+096135Y+063374X0260Y         S2      
017m0492                  -    MD0100PA00X+096135Y+063374                       
327m0492            PC814 -1          A01X+096036Y+063624X0198Y0197R090 S1      
327m0492            PR7027-2          A01X+096135Y+063121X0198Y0197R180 S1      
317m0493            VIA   -    M      A01X+142045Y+062808X0200Y         S2      
017m0493            VIA   -    M      A18X+142045Y+062808X0260Y         S2      
017m0493                  -    MD0100PA00X+142045Y+062808                       
327m0493            PR7056-1          A01X+142145Y+063624X0198Y0197R090 S1      
327m0493            PU105 -5          A01X+142045Y+062482X0100Y0320R180 S1      
327m0493            PR7051-1   M      A01X+142159Y+063121X0198Y0197R180 S1      
317HSC_TIMER_N      VIA   -    M      A01X+128178Y+082350X0200Y         S2      
017HSC_TIMER_N      VIA   -    M      A18X+128178Y+082350X0260Y         S2      
017HSC_TIMER_N            -    MD0100PA00X+128178Y+082350                       
317HSC_TIMER_N      VIA   -    MD0100PA00X+088513Y+088974X0180Y    R270 S0      
317HSC_TIMER_N      VIA   -    MD0100PA00X+088952Y+072206X0200Y         S0      
327HSC_TIMER_N      U5    -T14        A01X+088609Y+088466X0160Y    R180 S1      
327HSC_TIMER_N      R5910 -1          A01X+128792Y+082350X0198Y0197     S1      
317m0494            VIA   -    M      A01X+096336Y+062808X0200Y         S2      
017m0494            VIA   -    M      A18X+096336Y+062808X0260Y         S2      
017m0494                  -    MD0100PA00X+096336Y+062808                       
327m0494            PR7032-1          A01X+096436Y+063624X0198Y0197R090 S1      
327m0494            PU103 -5          A01X+096336Y+062482X0100Y0320R180 S1      
327m0494            PR7027-1   M      A01X+096450Y+063121X0198Y0197R180 S1      
317m0495            VIA   -    M      A01X+134644Y+043111X0200Y    R270 S2      
017m0495            VIA   -    M      A18X+134644Y+043111X0260Y    R270 S2      
017m0495                  -    MD0100PA00X+134644Y+043111                       
327m0495            PU104 -1          A01X+134326Y+043223X0098Y0335R090 S1      
327m0495            R956  -2   M      A01X+135477Y+043160X0198Y0197R180 S1      
327m0495            R955  -2          A01X+135477Y+042460X0198Y0197R180 S1      
327m0495            C844  -2   M      A01X+135477Y+042810X0198Y0197R180 S1      
317m0496            VIA   -    M      A01X+180910Y+043510X0200Y    R270 S2      
017m0496            VIA   -    M      A18X+180910Y+043510X0260Y    R270 S2      
017m0496                  -    MD0100PA00X+180910Y+043510                       
327m0496            PU106 -4          A01X+180044Y+043813X0100Y0320R090 S1      
327m0496            PC836 -1          A01X+181186Y+043510X0198Y0197     S1      
327m0497            PC830 -2          A01X+141135Y+060731X0280Y0320R270 S1      
327m0497            PU105 -12         A01X+141258Y+061380X0100Y0320R180 S1      
317m0497            VIA   -           A01X+141162Y+061055X0200Y         S2      
017m0497            VIA   -           A18X+141162Y+061055X0260Y         S2      
017m0497                  -     D0100PA00X+141162Y+061055                       
327m0497            PR7044-2          A01X+141178Y+059739X0198Y0197R180 S1      
327m0497            PR7047-1          A01X+141135Y+060181X0280Y0320R090 S1      
317m0498            VIA   -    M      A01X+148457Y+011078X0200Y         S2      
017m0498            VIA   -    M      A18X+148457Y+011078X0260Y         S2      
017m0498                  -    MD0100PA00X+148457Y+011078                       
327m0498            PU132 -4          A01X+148458Y+011368X0100Y0280     S1      
327m0498            PR7126-1          A01X+148284Y+010790X0198Y0197R270 S1      
317m0499            VIA   -    M      A01X+148412Y+012488X0200Y         S2      
017m0499            VIA   -    M      A18X+148412Y+012488X0260Y         S2      
017m0499                  -    MD0100PA00X+148412Y+012488                       
327m0499            PU132 -9          A01X+148458Y+012156X0100Y0280     S1      
327m0499            R6103 -2          A01X+148487Y+012775X0198Y0197R270 S1      
317m0500            VIA   -    M      A01X+159193Y+011078X0200Y         S2      
017m0500            VIA   -    M      A18X+159193Y+011078X0260Y         S2      
017m0500                  -    MD0100PA00X+159193Y+011078                       
327m0500            PU133 -5          A01X+158891Y+011368X0100Y0280     S1      
327m0500            PR7127-1          A01X+158920Y+010790X0198Y0197R270 S1      
327m0500            PC970 -1   M      A01X+159320Y+010790X0198Y0197R270 S1      
317m0501            VIA   -    M      A01X+168929Y+011078X0200Y         S2      
017m0501            VIA   -    M      A18X+168929Y+011078X0260Y         S2      
017m0501                  -    MD0100PA00X+168929Y+011078                       
327m0501            PU134 -4          A01X+168930Y+011368X0100Y0280     S1      
327m0501            PR7130-1          A01X+168757Y+010790X0198Y0197R270 S1      
317m0502            VIA   -    M      A01X+169429Y+011078X0200Y         S2      
017m0502            VIA   -    M      A18X+169429Y+011078X0260Y         S2      
017m0502                  -    MD0100PA00X+169429Y+011078                       
327m0502            PU134 -5          A01X+169127Y+011368X0100Y0280     S1      
327m0502            PR7128-1          A01X+169157Y+010790X0198Y0197R270 S1      
327m0502            PC974 -1   M      A01X+169557Y+010790X0198Y0197R270 S1      
317m0503            VIA   -    M      A01X+123720Y+011078X0200Y         S2      
017m0503            VIA   -    M      A18X+123720Y+011078X0260Y         S2      
017m0503                  -    MD0100PA00X+123720Y+011078                       
327m0503            PR7121-1          A01X+123448Y+010790X0198Y0197R270 S1      
327m0503            PC956 -1   M      A01X+123848Y+010790X0198Y0197R270 S1      
327m0503            PU130 -5          A01X+123418Y+011368X0100Y0280     S1      
317m0504            VIA   -    M      A01X+099421Y+014828X0200Y         S2      
017m0504            VIA   -    M      A18X+099421Y+014828X0260Y         S2      
017m0504                  -    MD0100PA00X+099421Y+014828                       
327m0504            Q225  -2          A01X+099709Y+014941X0160Y0240R270 S1      
327m0504            R6089 -1          A01X+099152Y+015154X0198Y0197R180 S1      
327m0504            R6087 -2   M      A01X+099152Y+014754X0198Y0197     S1      
317m0505            VIA   -    M      A01X+158693Y+011078X0200Y         S2      
017m0505            VIA   -    M      A18X+158693Y+011078X0260Y         S2      
017m0505                  -    MD0100PA00X+158693Y+011078                       
327m0505            PU133 -4          A01X+158694Y+011368X0100Y0280     S1      
327m0505            PR7129-1          A01X+158520Y+010790X0198Y0197R270 S1      
317m0506            VIA   -    M      A01X+089185Y+014828X0200Y         S2      
017m0506            VIA   -    M      A18X+089185Y+014828X0260Y         S2      
017m0506                  -    MD0100PA00X+089185Y+014828                       
327m0506            Q224  -2          A01X+089473Y+014941X0160Y0240R270 S1      
327m0506            R6088 -1          A01X+088916Y+015154X0198Y0197R180 S1      
327m0506            R6086 -2   M      A01X+088916Y+014754X0198Y0197     S1      
317m0507            VIA   -    M      A01X+138176Y+012488X0200Y         S2      
017m0507            VIA   -    M      A18X+138176Y+012488X0260Y         S2      
017m0507                  -    MD0100PA00X+138176Y+012488                       
327m0507            PU131 -9          A01X+138222Y+012156X0100Y0280     S1      
327m0507            R6102 -2          A01X+138250Y+012775X0198Y0197R270 S1      
317m0508            VIA   -    M      A01X+091961Y+012428X0200Y         S2      
017m0508            VIA   -    M      A18X+091961Y+012428X0260Y         S2      
017m0508                  -    MD0100PA00X+091961Y+012428                       
327m0508            PU127 -10         A01X+092316Y+012156X0100Y0280     S1      
327m0508            PC945 -1          A01X+092142Y+012775X0198Y0197R090 S1      
317m0509            VIA   -    M      A01X+145130Y+014828X0200Y         S2      
017m0509            VIA   -    M      A18X+145130Y+014828X0260Y         S2      
017m0509                  -    MD0100PA00X+145130Y+014828                       
327m0509            Q229  -2          A01X+145418Y+014941X0160Y0240R270 S1      
327m0509            R6113 -1          A01X+144861Y+015154X0198Y0197R180 S1      
327m0509            R6111 -2   M      A01X+144861Y+014754X0198Y0197     S1      
317m0510            VIA   -    M      A01X+102704Y+012488X0200Y         S2      
017m0510            VIA   -    M      A18X+102704Y+012488X0260Y         S2      
017m0510                  -    MD0100PA00X+102704Y+012488                       
327m0510            R6079 -2          A01X+102778Y+012775X0198Y0197R270 S1      
327m0510            PU128 -9          A01X+102749Y+012156X0100Y0280     S1      
317m0511            VIA   -    M      A01X+155366Y+014828X0200Y         S2      
017m0511            VIA   -    M      A18X+155366Y+014828X0260Y         S2      
017m0511                  -    MD0100PA00X+155366Y+014828                       
327m0511            R6124 -1          A01X+155097Y+015154X0198Y0197R180 S1      
327m0511            Q230  -2          A01X+155654Y+014941X0160Y0240R270 S1      
327m0511            R6122 -2   M      A01X+155097Y+014754X0198Y0197     S1      
317m0512            VIA   -    M      A01X+134894Y+014828X0200Y         S2      
017m0512            VIA   -    M      A18X+134894Y+014828X0260Y         S2      
017m0512                  -    MD0100PA00X+134894Y+014828                       
327m0512            Q228  -2          A01X+135182Y+014941X0160Y0240R270 S1      
327m0512            R6112 -1          A01X+134625Y+015154X0198Y0197R180 S1      
327m0512            R6110 -2   M      A01X+134625Y+014754X0198Y0197     S1      
317m0513            VIA   -    M      A01X+053713Y+014828X0200Y         S2      
017m0513            VIA   -    M      A18X+053713Y+014828X0260Y         S2      
017m0513                  -    MD0100PA00X+053713Y+014828                       
327m0513            Q221  -2          A01X+054000Y+014941X0160Y0240R270 S1      
327m0513            R6065 -1          A01X+053444Y+015154X0198Y0197R180 S1      
327m0513            R6063 -2   M      A01X+053444Y+014754X0198Y0197     S1      
317m0514            VIA   -    M      A01X+112433Y+012428X0200Y         S2      
017m0514            VIA   -    M      A18X+112433Y+012428X0260Y         S2      
017m0514                  -    MD0100PA00X+112433Y+012428                       
327m0514            PU129 -10         A01X+112788Y+012156X0100Y0280     S1      
327m0514            PC955 -1          A01X+112614Y+012775X0198Y0197R090 S1      
317m0515            VIA   -    M      A01X+168885Y+012488X0200Y         S2      
017m0515            VIA   -    M      A18X+168885Y+012488X0260Y         S2      
017m0515                  -    MD0100PA00X+168885Y+012488                       
327m0515            PU134 -9          A01X+168930Y+012156X0100Y0280     S1      
327m0515            R6115 -2          A01X+168959Y+012775X0198Y0197R270 S1      
317m0516            VIA   -    M      A01X+046803Y+011078X0200Y         S2      
017m0516            VIA   -    M      A18X+046803Y+011078X0260Y         S2      
017m0516                  -    MD0100PA00X+046803Y+011078                       
327m0516            PU123 -4          A01X+046804Y+011368X0100Y0280     S1      
327m0516            PR7108-1          A01X+046631Y+010790X0198Y0197R270 S1      
317m0517            VIA   -    M      A01X+092970Y+012466X0200Y         S2      
017m0517            VIA   -    M      A18X+092970Y+012466X0260Y         S2      
017m0517                  -    MD0100PA00X+092970Y+012466                       
327m0517            PU127 -8          A01X+092710Y+012156X0100Y0280     S1      
327m0517            PC940 -1          A01X+092942Y+012775X0198Y0197R090 S1      
317m0518            VIA   -    M      A01X+137670Y+012428X0200Y         S2      
017m0518            VIA   -    M      A18X+137670Y+012428X0260Y         S2      
017m0518                  -    MD0100PA00X+137670Y+012428                       
327m0518            PU131 -10         A01X+138025Y+012156X0100Y0280     S1      
327m0518            PC963 -1          A01X+137850Y+012775X0198Y0197R090 S1      
317m0519            VIA   -    M      A01X+067231Y+012488X0200Y         S2      
017m0519            VIA   -    M      A18X+067231Y+012488X0260Y         S2      
017m0519                  -    MD0100PA00X+067231Y+012488                       
327m0519            PU125 -9          A01X+067277Y+012156X0100Y0280     S1      
327m0519            R6066 -2          A01X+067306Y+012775X0198Y0197R270 S1      
317m0520            VIA   -    M      A01X+109658Y+014828X0200Y         S2      
017m0520            VIA   -    M      A18X+109658Y+014828X0260Y         S2      
017m0520                  -    MD0100PA00X+109658Y+014828                       
327m0520            Q226  -2          A01X+109945Y+014941X0160Y0240R270 S1      
327m0520            R6100 -1          A01X+109388Y+015154X0198Y0197R180 S1      
327m0520            R6098 -2   M      A01X+109388Y+014754X0198Y0197     S1      
317m0521            VIA   -    M      A01X+147906Y+012428X0200Y         S2      
017m0521            VIA   -    M      A18X+147906Y+012428X0260Y         S2      
017m0521                  -    MD0100PA00X+147906Y+012428                       
327m0521            PU132 -10         A01X+148261Y+012156X0100Y0280     S1      
327m0521            PC967 -1          A01X+147887Y+012775X0198Y0197R090 S1      
317m0522            VIA   -    M      A01X+055190Y+015237X0200Y         S2      
017m0522            VIA   -    M      A18X+055190Y+015237X0260Y         S2      
017m0522                  -    MD0100PA00X+055190Y+015237                       
327m0522            Q221  -6          A01X+054709Y+015237X0240Y0240R270 S1      
327m0522            Q221  -5          A01X+054709Y+014941X0160Y0240R270 S1      
327m0522            R6061 -2   M      A01X+055190Y+014977X0198Y0197R180 S1      
317m0523            VIA   -    M      A01X+138720Y+011078X0200Y         S2      
017m0523            VIA   -    M      A18X+138720Y+011078X0260Y         S2      
017m0523                  -    MD0100PA00X+138720Y+011078                       
327m0523            PU131 -5          A01X+138418Y+011368X0100Y0280     S1      
327m0523            PR7123-1          A01X+138448Y+010790X0198Y0197R270 S1      
327m0523            PC960 -1   M      A01X+138848Y+010790X0198Y0197R270 S1      
317m0524            VIA   -    M      A01X+057539Y+011078X0200Y         S2      
017m0524            VIA   -    M      A18X+057539Y+011078X0260Y         S2      
017m0524                  -    MD0100PA00X+057539Y+011078                       
327m0524            PU124 -5          A01X+057237Y+011368X0100Y0280     S1      
327m0524            PR7109-1          A01X+057267Y+010790X0198Y0197R270 S1      
327m0524            PC926 -1   M      A01X+057667Y+010790X0198Y0197R270 S1      
317m0525            VIA   -    M      A01X+123176Y+012488X0200Y         S2      
017m0525            VIA   -    M      A18X+123176Y+012488X0260Y         S2      
017m0525                  -    MD0100PA00X+123176Y+012488                       
327m0525            PU130 -9          A01X+123221Y+012156X0100Y0280     S1      
327m0525            R6091 -2          A01X+123250Y+012775X0198Y0197R270 S1      
317m0526            VIA   -    M      A01X+136371Y+015237X0200Y         S2      
017m0526            VIA   -    M      A18X+136371Y+015237X0260Y         S2      
017m0526                  -    MD0100PA00X+136371Y+015237                       
327m0526            Q228  -6          A01X+135890Y+015237X0240Y0240R270 S1      
327m0526            Q228  -5          A01X+135890Y+014941X0160Y0240R270 S1      
327m0526            R6108 -2   M      A01X+136371Y+014977X0198Y0197R180 S1      
327m0527            PR7113-1          A01X+077739Y+010790X0198Y0197R270 S1      
327m0527            PU126 -5          A01X+077710Y+011368X0100Y0280     S1      
317m0527            VIA   -    M      A01X+078012Y+011078X0200Y         S2      
017m0527            VIA   -    M      A18X+078012Y+011078X0260Y         S2      
017m0527                  -    MD0100PA00X+078012Y+011078                       
327m0527            PC936 -1   M      A01X+078139Y+010790X0198Y0197R270 S1      
317m0528            VIA   -    M      A01X+092468Y+012488X0200Y         S2      
017m0528            VIA   -    M      A18X+092468Y+012488X0260Y         S2      
017m0528                  -    MD0100PA00X+092468Y+012488                       
327m0528            PU127 -9          A01X+092513Y+012156X0100Y0280     S1      
327m0528            R6078 -2          A01X+092542Y+012775X0198Y0197R270 S1      
317m0529            VIA   -    M      A01X+146607Y+015237X0200Y         S2      
017m0529            VIA   -    M      A18X+146607Y+015237X0260Y         S2      
017m0529                  -    MD0100PA00X+146607Y+015237                       
327m0529            Q229  -5          A01X+146126Y+014941X0160Y0240R270 S1      
327m0529            Q229  -6          A01X+146126Y+015237X0240Y0240R270 S1      
327m0529            R6109 -2   M      A01X+146607Y+014977X0198Y0197R180 S1      
317m0530            VIA   -    M      A01X+067276Y+011078X0200Y         S2      
017m0530            VIA   -    M      A18X+067276Y+011078X0260Y         S2      
017m0530                  -    MD0100PA00X+067276Y+011078                       
327m0530            PU125 -4          A01X+067277Y+011368X0100Y0280     S1      
327m0530            PR7112-1          A01X+067103Y+010790X0198Y0197R270 S1      
317m0531            VIA   -    M      A01X+119894Y+014828X0200Y         S2      
017m0531            VIA   -    M      A18X+119894Y+014828X0260Y         S2      
017m0531                  -    MD0100PA00X+119894Y+014828                       
327m0531            R6101 -1          A01X+119625Y+015154X0198Y0197R180 S1      
327m0531            R6099 -2   M      A01X+119625Y+014754X0198Y0197     S1      
327m0531            Q227  -2          A01X+120182Y+014941X0160Y0240R270 S1      
317m0532            VIA   -    M      A01X+165602Y+014828X0200Y         S2      
017m0532            VIA   -    M      A18X+165602Y+014828X0260Y         S2      
017m0532                  -    MD0100PA00X+165602Y+014828                       
327m0532            Q231  -2          A01X+165890Y+014941X0160Y0240R270 S1      
327m0532            R6125 -1          A01X+165333Y+015154X0198Y0197R180 S1      
327m0532            R6123 -2   M      A01X+165333Y+014754X0198Y0197     S1      
317m0533            VIA   -    M      A01X+043477Y+014828X0200Y         S2      
017m0533            VIA   -    M      A18X+043477Y+014828X0260Y         S2      
017m0533                  -    MD0100PA00X+043477Y+014828                       
327m0533            Q220  -2          A01X+043764Y+014941X0160Y0240R270 S1      
327m0533            R6064 -1          A01X+043208Y+015154X0198Y0197R180 S1      
327m0533            R6062 -2   M      A01X+043208Y+014754X0198Y0197     S1      
317m0534            VIA   -    M      A01X+122670Y+012428X0200Y         S2      
017m0534            VIA   -    M      A18X+122670Y+012428X0260Y         S2      
017m0534                  -    MD0100PA00X+122670Y+012428                       
327m0534            PU130 -10         A01X+123025Y+012156X0100Y0280     S1      
327m0534            PC957 -1          A01X+122650Y+012775X0198Y0197R090 S1      
317m0535            VIA   -    M      A01X+063949Y+014828X0200Y         S2      
017m0535            VIA   -    M      A18X+063949Y+014828X0260Y         S2      
017m0535                  -    MD0100PA00X+063949Y+014828                       
327m0535            Q222  -2          A01X+064237Y+014941X0160Y0240R270 S1      
327m0535            R6076 -1          A01X+063680Y+015154X0198Y0197R180 S1      
327m0535            R6074 -2   M      A01X+063680Y+014754X0198Y0197     S1      
317m0536            VIA   -    M      A01X+103206Y+012466X0200Y         S2      
017m0536            VIA   -    M      A18X+103206Y+012466X0260Y         S2      
017m0536                  -    MD0100PA00X+103206Y+012466                       
327m0536            PU128 -8          A01X+102946Y+012156X0100Y0280     S1      
327m0536            PC942 -1          A01X+103178Y+012775X0198Y0197R090 S1      
317m0537            VIA   -    M      A01X+169387Y+012466X0200Y         S2      
017m0537            VIA   -    M      A18X+169387Y+012466X0260Y         S2      
017m0537                  -    MD0100PA00X+169387Y+012466                       
327m0537            PU134 -8          A01X+169127Y+012156X0100Y0280     S1      
327m0537            PC975 -1          A01X+169359Y+012775X0198Y0197R090 S1      
327m0538            PU126 -9          A01X+077513Y+012156X0100Y0280     S1      
317m0538            VIA   -    M      A01X+077468Y+012488X0200Y         S2      
017m0538            VIA   -    M      A18X+077468Y+012488X0260Y         S2      
017m0538                  -    MD0100PA00X+077468Y+012488                       
327m0538            R6067 -2          A01X+077542Y+012775X0198Y0197R270 S1      
317m0539            VIA   -    M      A01X+113484Y+011078X0200Y         S2      
017m0539            VIA   -    M      A18X+113484Y+011078X0260Y         S2      
017m0539                  -    MD0100PA00X+113484Y+011078                       
327m0539            PU129 -5          A01X+113182Y+011368X0100Y0280     S1      
327m0539            PR7119-1          A01X+113212Y+010790X0198Y0197R270 S1      
327m0539            PC954 -1   M      A01X+113612Y+010790X0198Y0197R270 S1      
317m0540            VIA   -    M      A01X+159151Y+012466X0200Y         S2      
017m0540            VIA   -    M      A18X+159151Y+012466X0260Y         S2      
017m0540                  -    MD0100PA00X+159151Y+012466                       
327m0540            PU133 -8          A01X+158891Y+012156X0100Y0280     S1      
327m0540            PC971 -1          A01X+159123Y+012775X0198Y0197R090 S1      
317m0541            VIA   -    M      A01X+138678Y+012466X0200Y         S2      
017m0541            VIA   -    M      A18X+138678Y+012466X0260Y         S2      
017m0541                  -    MD0100PA00X+138678Y+012466                       
327m0541            PU131 -8          A01X+138418Y+012156X0100Y0280     S1      
327m0541            PC961 -1          A01X+138650Y+012775X0198Y0197R090 S1      
317m0542            VIA   -    M      A01X+090662Y+015237X0200Y         S2      
017m0542            VIA   -    M      A18X+090662Y+015237X0260Y         S2      
017m0542                  -    MD0100PA00X+090662Y+015237                       
327m0542            Q224  -6          A01X+090182Y+015237X0240Y0240R270 S1      
327m0542            Q224  -5          A01X+090182Y+014941X0160Y0240R270 S1      
327m0542            R6084 -2   M      A01X+090662Y+014977X0198Y0197R180 S1      
317m0543            VIA   -    M      A01X+167080Y+015237X0200Y         S2      
017m0543            VIA   -    M      A18X+167080Y+015237X0260Y         S2      
017m0543                  -    MD0100PA00X+167080Y+015237                       
327m0543            Q231  -6          A01X+166599Y+015237X0240Y0240R270 S1      
327m0543            Q231  -5          A01X+166599Y+014941X0160Y0240R270 S1      
327m0543            R6121 -2   M      A01X+167080Y+014977X0198Y0197R180 S1      
317m0544            VIA   -    M      A01X+047261Y+012466X0200Y         S2      
017m0544            VIA   -    M      A18X+047261Y+012466X0260Y         S2      
017m0544                  -    MD0100PA00X+047261Y+012466                       
327m0544            PU123 -8          A01X+047001Y+012156X0100Y0280     S1      
327m0544            PC920 -1          A01X+047233Y+012775X0198Y0197R090 S1      
317m0545            VIA   -    M      A01X+123678Y+012466X0200Y         S2      
017m0545            VIA   -    M      A18X+123678Y+012466X0260Y         S2      
017m0545                  -    MD0100PA00X+123678Y+012466                       
327m0545            PU130 -8          A01X+123418Y+012156X0100Y0280     S1      
327m0545            PC952 -1          A01X+123650Y+012775X0198Y0197R090 S1      
317m0546            VIA   -    M      A01X+158649Y+012488X0200Y         S2      
017m0546            VIA   -    M      A18X+158649Y+012488X0260Y         S2      
017m0546                  -    MD0100PA00X+158649Y+012488                       
327m0546            PU133 -9          A01X+158694Y+012156X0100Y0280     S1      
327m0546            R6114 -2          A01X+158723Y+012775X0198Y0197R270 S1      
317m0547            VIA   -    M      A01X+133297Y+047451X0200Y    R090 S2      
017m0547            VIA   -    M      A18X+133297Y+047451X0260Y    R090 S2      
017m0547                  -    MD0100PA00X+133297Y+047451                       
327m0547            Q217  -5          A01X+133002Y+047156X0160Y0240R270 S1      
327m0547            Q217  -6          A01X+133002Y+047451X0240Y0240R270 S1      
327m0547            R6037 -2   M      A01X+133590Y+047456X0198Y0197R180 S1      
317m0548            VIA   -    M      A01X+057039Y+011078X0200Y         S2      
017m0548            VIA   -    M      A18X+057039Y+011078X0260Y         S2      
017m0548                  -    MD0100PA00X+057039Y+011078                       
327m0548            PU124 -4          A01X+057040Y+011368X0100Y0280     S1      
327m0548            PR7110-1          A01X+056867Y+010790X0198Y0197R270 S1      
317m0549            VIA   -    M      A01X+113442Y+012466X0200Y         S2      
017m0549            VIA   -    M      A18X+113442Y+012466X0260Y         S2      
017m0549                  -    MD0100PA00X+113442Y+012466                       
327m0549            PU129 -8          A01X+113182Y+012156X0100Y0280     S1      
327m0549            PC950 -1          A01X+113414Y+012775X0198Y0197R090 S1      
317m0550            VIA   -    M      A01X+143693Y+046182X0200Y         S2      
017m0550            VIA   -    M      A18X+143693Y+046182X0260Y         S2      
017m0550                  -    MD0100PA00X+143693Y+046182                       
327m0550            PC910 -1          A01X+143548Y+046448X0198Y0197R090 S1      
327m0550            PU121 -8          A01X+143438Y+045643X0100Y0280     S1      
317m0551            VIA   -    M      A01X+056995Y+012488X0200Y         S2      
017m0551            VIA   -    M      A18X+056995Y+012488X0260Y         S2      
017m0551                  -    MD0100PA00X+056995Y+012488                       
327m0551            PU124 -9          A01X+057040Y+012156X0100Y0280     S1      
327m0551            R6055 -2          A01X+057069Y+012775X0198Y0197R270 S1      
317m0552            VIA   -    M      A01X+092512Y+011078X0200Y         S2      
017m0552            VIA   -    M      A18X+092512Y+011078X0260Y         S2      
017m0552                  -    MD0100PA00X+092512Y+011078                       
327m0552            PU127 -4          A01X+092513Y+011368X0100Y0280     S1      
327m0552            PR7116-1          A01X+092339Y+010790X0198Y0197R270 S1      
317m0553            VIA   -    M      A01X+148915Y+012466X0200Y         S2      
017m0553            VIA   -    M      A18X+148915Y+012466X0260Y         S2      
017m0553                  -    MD0100PA00X+148915Y+012466                       
327m0553            PU132 -8          A01X+148654Y+012156X0100Y0280     S1      
327m0553            PC965 -1          A01X+148887Y+012775X0198Y0197R090 S1      
317m0554            VIA   -    M      A01X+142748Y+046200X0200Y         S2      
017m0554            VIA   -    M      A18X+142748Y+046200X0260Y         S2      
017m0554                  -    MD0100PA00X+142748Y+046200                       
327m0554            PC915 -1          A01X+142748Y+046448X0198Y0197R090 S1      
327m0554            PU121 -10         A01X+143045Y+045643X0100Y0280     S1      
317m0555            VIA   -    M      A01X+046759Y+012488X0200Y         S2      
017m0555            VIA   -    M      A18X+046759Y+012488X0260Y         S2      
017m0555                  -    MD0100PA00X+046759Y+012488                       
327m0555            PU123 -9          A01X+046804Y+012156X0100Y0280     S1      
327m0555            R6054 -2          A01X+046833Y+012775X0198Y0197R270 S1      
317m0556            VIA   -    M      A01X+156843Y+015237X0200Y         S2      
017m0556            VIA   -    M      A18X+156843Y+015237X0260Y         S2      
017m0556                  -    MD0100PA00X+156843Y+015237                       
327m0556            Q230  -6          A01X+156363Y+015237X0240Y0240R270 S1      
327m0556            Q230  -5          A01X+156363Y+014941X0160Y0240R270 S1      
327m0556            R6120 -2   M      A01X+156843Y+014977X0198Y0197R180 S1      
327m0557            PR7114-1          A01X+077339Y+010790X0198Y0197R270 S1      
327m0557            PU126 -4          A01X+077513Y+011368X0100Y0280     S1      
317m0557            VIA   -    M      A01X+077512Y+011078X0200Y         S2      
017m0557            VIA   -    M      A18X+077512Y+011078X0260Y         S2      
017m0557                  -    MD0100PA00X+077512Y+011078                       
317m0558            VIA   -    M      A01X+111135Y+015237X0200Y         S2      
017m0558            VIA   -    M      A18X+111135Y+015237X0260Y         S2      
017m0558                  -    MD0100PA00X+111135Y+015237                       
327m0558            Q226  -5          A01X+110654Y+014941X0160Y0240R270 S1      
327m0558            Q226  -6          A01X+110654Y+015237X0240Y0240R270 S1      
327m0558            R6096 -2   M      A01X+111135Y+014977X0198Y0197R180 S1      
317m0559            VIA   -    M      A01X+168378Y+012428X0200Y         S2      
017m0559            VIA   -    M      A18X+168378Y+012428X0260Y         S2      
017m0559                  -    MD0100PA00X+168378Y+012428                       
327m0559            PC977 -1          A01X+168359Y+012775X0198Y0197R090 S1      
327m0559            PU134 -10         A01X+168733Y+012156X0100Y0280     S1      
317m0560            VIA   -    M      A01X+177706Y+047556X0200Y    R090 S2      
017m0560            VIA   -    M      A18X+177706Y+047556X0260Y    R090 S2      
017m0560                  -    MD0100PA00X+177706Y+047556                       
327m0560            Q219  -2          A01X+178002Y+047156X0160Y0240R270 S1      
327m0560            R6053 -1          A01X+177414Y+047956X0198Y0197R180 S1      
327m0560            R6051 -2   M      A01X+177414Y+047556X0198Y0197     S1      
317m0561            VIA   -    M      A01X+067734Y+012466X0200Y         S2      
017m0561            VIA   -    M      A18X+067734Y+012466X0260Y         S2      
017m0561                  -    MD0100PA00X+067734Y+012466                       
327m0561            PU125 -8          A01X+067473Y+012156X0100Y0280     S1      
327m0561            PC930 -1          A01X+067706Y+012775X0198Y0197R090 S1      
317m0562            VIA   -    M      A01X+123220Y+011078X0200Y         S2      
017m0562            VIA   -    M      A18X+123220Y+011078X0260Y         S2      
017m0562                  -    MD0100PA00X+123220Y+011078                       
327m0562            PU130 -4          A01X+123221Y+011368X0100Y0280     S1      
327m0562            PR7122-1          A01X+123048Y+010790X0198Y0197R270 S1      
317m0563            VIA   -    M      A01X+138220Y+011078X0200Y         S2      
017m0563            VIA   -    M      A18X+138220Y+011078X0260Y         S2      
017m0563                  -    MD0100PA00X+138220Y+011078                       
327m0563            PU131 -4          A01X+138222Y+011368X0100Y0280     S1      
327m0563            PR7124-1          A01X+138048Y+010790X0198Y0197R270 S1      
317m0564            VIA   -    M      A01X+051824Y+045937X0200Y         S2      
017m0564            VIA   -    M      A18X+051824Y+045937X0260Y         S2      
017m0564                  -    MD0100PA00X+051824Y+045937                       
327m0564            R5954 -2          A01X+051731Y+046448X0198Y0197R270 S1      
327m0564            PU101 -9          A01X+051824Y+045643X0100Y0280     S1      
317m0565            VIA   -    M      A01X+097733Y+046237X0200Y         S2      
017m0565            VIA   -    M      A18X+097733Y+046237X0260Y         S2      
017m0565                  -    MD0100PA00X+097733Y+046237                       
327m0565            PU119 -9          A01X+097733Y+045943X0100Y0280     S1      
327m0565            R6030 -2          A01X+097640Y+046748X0198Y0197R270 S1      
317m0566            VIA   -    M      A01X+112984Y+011078X0200Y         S2      
017m0566            VIA   -    M      A18X+112984Y+011078X0260Y         S2      
017m0566                  -    MD0100PA00X+112984Y+011078                       
327m0566            PU129 -4          A01X+112985Y+011368X0100Y0280     S1      
327m0566            PR7120-1          A01X+112812Y+010790X0198Y0197R270 S1      
317m0567            VIA   -    M      A01X+158142Y+012428X0200Y         S2      
017m0567            VIA   -    M      A18X+158142Y+012428X0260Y         S2      
017m0567                  -    MD0100PA00X+158142Y+012428                       
327m0567            PU133 -10         A01X+158497Y+012156X0100Y0280     S1      
327m0567            PC973 -1          A01X+158323Y+012775X0198Y0197R090 S1      
327m0568            DE12T_-1          A18X+094994Y-003081X0120Y0200R090 S2      
327m0568            DE12T_-2          A18X+072501Y-003084X0120Y0200R270 S2      
317m0569            VIA   -    M      A01X+173882Y+046103X0200Y    R090 S2      
017m0569            VIA   -    M      A18X+173882Y+046103X0260Y    R090 S2      
017m0569                  -    MD0100PA00X+173882Y+046103                       
327m0569            PU122 -5          A01X+173592Y+045801X0100Y0280R090 S1      
327m0569            PR7105-1          A01X+174171Y+045831X0198Y0197     S1      
327m0569            PC916 -1   M      A01X+174171Y+046231X0198Y0197     S1      
317m0570            VIA   -    M      A01X+066725Y+012428X0200Y         S2      
017m0570            VIA   -    M      A18X+066725Y+012428X0260Y         S2      
017m0570                  -    MD0100PA00X+066725Y+012428                       
327m0570            PU125 -10         A01X+067080Y+012156X0100Y0280     S1      
327m0570            PC935 -1          A01X+066906Y+012775X0198Y0197R090 S1      
317m0571            VIA   -    M      A01X+093012Y+011078X0200Y         S2      
017m0571            VIA   -    M      A18X+093012Y+011078X0260Y         S2      
017m0571                  -    MD0100PA00X+093012Y+011078                       
327m0571            PU127 -5          A01X+092710Y+011368X0100Y0280     S1      
327m0571            PR7115-1          A01X+092739Y+010790X0198Y0197R270 S1      
327m0571            PC944 -1   M      A01X+093139Y+010790X0198Y0197R270 S1      
317m0572            VIA   -    M      A01X+148957Y+011078X0200Y         S2      
017m0572            VIA   -    M      A18X+148957Y+011078X0260Y         S2      
017m0572                  -    MD0100PA00X+148957Y+011078                       
327m0572            PU132 -5          A01X+148654Y+011368X0100Y0280     S1      
327m0572            PR7125-1          A01X+148684Y+010790X0198Y0197R270 S1      
327m0572            PC964 -1   M      A01X+149084Y+010790X0198Y0197R270 S1      
317m0573            VIA   -    MD0100PA18X+151726Y-004376X0200Y         S0      
327m0573            DE16T_-2          A18X+151994Y-004304X0120Y0200R090 S2      
327m0573            DE16T_-1          A18X+129501Y-004294X0120Y0200R270 S2      
317m0573            VIA   -    MD0100PA18X+129769Y-004366X0200Y    R180 S0      
317m0574            VIA   -    M      A01X+046252Y+012428X0200Y         S2      
017m0574            VIA   -    M      A18X+046252Y+012428X0260Y         S2      
017m0574                  -    MD0100PA00X+046252Y+012428                       
327m0574            PU123 -10         A01X+046607Y+012156X0100Y0280     S1      
327m0574            PC925 -1          A01X+046433Y+012775X0198Y0197R090 S1      
317m0575            VIA   -    M      A01X+103248Y+011078X0200Y         S2      
017m0575            VIA   -    M      A18X+103248Y+011078X0260Y         S2      
017m0575                  -    MD0100PA00X+103248Y+011078                       
327m0575            PU128 -5          A01X+102946Y+011368X0100Y0280     S1      
327m0575            PR7117-1          A01X+102976Y+010790X0198Y0197R270 S1      
327m0575            PC946 -1   M      A01X+103376Y+010790X0198Y0197R270 S1      
327m0576            DE15T_-1          A18X+180444Y-004120X0120Y0200R090 S2      
317m0576            VIA   -    MD0100PA18X+180176Y-004049X0200Y         S0      
317m0576            VIA   -    MD0100PA18X+158219Y-004039X0200Y    R180 S0      
327m0576            DE15T_-2          A18X+157951Y-004110X0120Y0200R270 S2      
317m0577            VIA   -    M      A01X+098184Y+046482X0200Y         S2      
017m0577            VIA   -    M      A18X+098184Y+046482X0260Y         S2      
017m0577                  -    MD0100PA00X+098184Y+046482                       
327m0577            PU119 -8          A01X+097930Y+045943X0100Y0280     S1      
327m0577            PC900 -1          A01X+098040Y+046748X0198Y0197R090 S1      
317m0578            VIA   -    M      A01X+056488Y+012428X0200Y         S2      
017m0578            VIA   -    M      A18X+056488Y+012428X0260Y         S2      
017m0578                  -    MD0100PA00X+056488Y+012428                       
327m0578            PU124 -10         A01X+056844Y+012156X0100Y0280     S1      
327m0578            PC927 -1          A01X+056469Y+012775X0198Y0197R090 S1      
317m0579            VIA   -    M      A01X+102748Y+011078X0200Y         S2      
017m0579            VIA   -    M      A18X+102748Y+011078X0260Y         S2      
017m0579                  -    MD0100PA00X+102748Y+011078                       
327m0579            PR7118-1          A01X+102576Y+010790X0198Y0197R270 S1      
327m0579            PU128 -4          A01X+102749Y+011368X0100Y0280     S1      
327m0580            DE02F_-2          A18X+084501Y-007002X0120Y0200R270 S2      
327m0580            DE02F_-1          A18X+097479Y-006999X0120Y0200R090 S2      
317m0581            VIA   -    M      A01X+096382Y+046442X0200Y         S2      
017m0581            VIA   -    M      A18X+096382Y+046442X0260Y         S2      
017m0581                  -    MD0100PA00X+096382Y+046442                       
327m0581            Q216  -2          A01X+095982Y+046146X0160Y0240R180 S1      
327m0581            R6040 -1          A01X+096782Y+046734X0198Y0197R090 S1      
327m0581            R6038 -2   M      A01X+096382Y+046734X0198Y0197R270 S1      
327m0582            PU126 -8          A01X+077710Y+012156X0100Y0280     S1      
317m0582            VIA   -    M      A01X+077970Y+012466X0200Y         S2      
017m0582            VIA   -    M      A18X+077970Y+012466X0260Y         S2      
017m0582                  -    MD0100PA00X+077970Y+012466                       
327m0582            PC932 -1          A01X+077942Y+012775X0198Y0197R090 S1      
317m0583            VIA   -    M      A01X+121371Y+015237X0200Y         S2      
017m0583            VIA   -    M      A18X+121371Y+015237X0260Y         S2      
017m0583                  -    MD0100PA00X+121371Y+015237                       
327m0583            Q227  -6          A01X+120890Y+015237X0240Y0240R270 S1      
327m0583            Q227  -5          A01X+120890Y+014941X0160Y0240R270 S1      
327m0583            R6097 -2   M      A01X+121371Y+014977X0198Y0197R180 S1      
317m0584            VIA   -    MD0100PA18X+123076Y-004023X0200Y         S0      
327m0584            DE16T_-1          A18X+123344Y-004094X0120Y0200R090 S2      
327m0584            DE16T_-2          A18X+100851Y-004084X0120Y0200R270 S2      
317m0584            VIA   -    MD0100PA18X+101119Y-004013X0200Y    R180 S0      
327m0585            R5955 -2          A01X+080769Y+044833X0198Y0197     S1      
317m0585            VIA   -    M      A01X+081041Y+044821X0200Y    R090 S2      
017m0585            VIA   -    M      A18X+081041Y+044821X0260Y    R090 S2      
017m0585                  -    MD0100PA00X+081041Y+044821                       
327m0585            PU102 -9          A01X+081388Y+045004X0100Y0280R090 S1      
317m0586            VIA   -    M      A01X+128174Y+045603X0200Y    R090 S2      
017m0586            VIA   -    M      A18X+128174Y+045603X0260Y    R090 S2      
017m0586                  -    MD0100PA00X+128174Y+045603                       
327m0586            PU120 -4          A01X+127884Y+045604X0100Y0280R090 S1      
327m0586            PR7102-1          A01X+128462Y+045431X0198Y0197     S1      
317m0587            VIA   -    M      A01X+065426Y+015237X0200Y         S2      
017m0587            VIA   -    M      A18X+065426Y+015237X0260Y         S2      
017m0587                  -    MD0100PA00X+065426Y+015237                       
327m0587            Q222  -5          A01X+064945Y+014941X0160Y0240R270 S1      
327m0587            Q222  -6          A01X+064945Y+015237X0240Y0240R270 S1      
327m0587            R6072 -2   M      A01X+065426Y+014977X0198Y0197R180 S1      
317m0588            VIA   -    M      A01X+112940Y+012488X0200Y         S2      
017m0588            VIA   -    M      A18X+112940Y+012488X0260Y         S2      
017m0588                  -    MD0100PA00X+112940Y+012488                       
327m0588            PU129 -9          A01X+112985Y+012156X0100Y0280     S1      
327m0588            R6090 -2          A01X+113014Y+012775X0198Y0197R270 S1      
327m0589            DE15T_-2          A01X+180444Y-003120X0120Y0200R090 S1      
317m0589            VIA   -    MD0100PA01X+180176Y-003049X0200Y         S0      
317m0589            VIA   -    MD0100PA01X+158219Y-003039X0200Y    R180 S0      
327m0589            DE15T_-1          A01X+157951Y-003110X0120Y0200R270 S1      
317m0590            VIA   -    M      A01X+149917Y+025639X0200Y         S2      
017m0590            VIA   -    M      A18X+149917Y+025639X0260Y         S2      
017m0590                  -    MD0100PA00X+149917Y+025639                       
327m0590            Q209  -6          A01X+149917Y+025320X0240Y0240R270 S1      
327m0590            Q209  -5          A01X+149917Y+025024X0160Y0240R270 S1      
327m0590            R6017 -2   M      A01X+150398Y+025060X0198Y0197R180 S1      
317m0591            VIA   -    M      A01X+142712Y+044307X0200Y         S2      
017m0591            VIA   -    M      A18X+142712Y+044307X0260Y         S2      
017m0591                  -    MD0100PA00X+142712Y+044307                       
327m0591            PU121 -4          A01X+143241Y+044856X0100Y0280     S1      
327m0591            PR7104-1          A01X+142702Y+044007X0198Y0197R270 S1      
317m0592            VIA   -    M      A01X+044954Y+015237X0200Y         S2      
017m0592            VIA   -    M      A18X+044954Y+015237X0260Y         S2      
017m0592                  -    MD0100PA00X+044954Y+015237                       
327m0592            Q220  -6          A01X+044473Y+015237X0240Y0240R270 S1      
327m0592            Q220  -5          A01X+044473Y+014941X0160Y0240R270 S1      
327m0592            R6060 -2   M      A01X+044954Y+014977X0198Y0197R180 S1      
317m0593            VIA   -    M      A01X+100898Y+015237X0200Y         S2      
017m0593            VIA   -    M      A18X+100898Y+015237X0260Y         S2      
017m0593                  -    MD0100PA00X+100898Y+015237                       
327m0593            Q225  -6          A01X+100418Y+015237X0240Y0240R270 S1      
327m0593            Q225  -5          A01X+100418Y+014941X0160Y0240R270 S1      
327m0593            R6085 -2   M      A01X+100898Y+014977X0198Y0197R180 S1      
327m0594            DE11T_-2          A01X+094994Y-003081X0120Y0200R090 S1      
327m0594            DE11T_-1          A01X+072501Y-003084X0120Y0200R270 S1      
317m0595            VIA   -    M      A01X+160468Y+025320X0200Y         S2      
017m0595            VIA   -    M      A18X+160468Y+025320X0260Y         S2      
017m0595                  -    MD0100PA00X+160468Y+025320                       
327m0595            Q210  -5          A01X+160153Y+025024X0160Y0240R270 S1      
327m0595            Q210  -6          A01X+160153Y+025320X0240Y0240R270 S1      
327m0595            R6026 -2   M      A01X+160634Y+025060X0198Y0197R180 S1      
317m0596            VIA   -    M      A01X+143241Y+045937X0200Y         S2      
017m0596            VIA   -    M      A18X+143241Y+045937X0260Y         S2      
017m0596                  -    MD0100PA00X+143241Y+045937                       
327m0596            R6042 -2          A01X+143148Y+046448X0198Y0197R270 S1      
327m0596            PU121 -9          A01X+143241Y+045643X0100Y0280     S1      
317m0597            VIA   -    M      A01X+075662Y+015237X0200Y         S2      
017m0597            VIA   -    M      A18X+075662Y+015237X0260Y         S2      
017m0597                  -    MD0100PA00X+075662Y+015237                       
327m0597            Q223  -6          A01X+075182Y+015237X0240Y0240R270 S1      
327m0597            Q223  -5          A01X+075182Y+014941X0160Y0240R270 S1      
327m0597            R6073 -2   M      A01X+075662Y+014977X0198Y0197R180 S1      
317m0598            VIA   -    M      A01X+102197Y+012428X0200Y         S2      
017m0598            VIA   -    M      A18X+102197Y+012428X0260Y         S2      
017m0598                  -    MD0100PA00X+102197Y+012428                       
327m0598            PU128 -10         A01X+102552Y+012156X0100Y0280     S1      
327m0598            PC947 -1          A01X+102178Y+012775X0198Y0197R090 S1      
317m0599            VIA   -    MD0100PA01X+151726Y-003036X0200Y         S0      
327m0599            DE14T_-2          A01X+151994Y-003107X0120Y0200R090 S1      
327m0599            DE14T_-1          A01X+129501Y-003097X0120Y0200R270 S1      
317m0599            VIA   -    MD0100PA01X+129769Y-003026X0200Y    R180 S0      
317m0600            VIA   -    M      A01X+144833Y+028172X0200Y         S2      
017m0600            VIA   -    M      A18X+144833Y+028172X0260Y         S2      
017m0600                  -    MD0100PA00X+144833Y+028172                       
327m0600            PU115 -5          A01X+145030Y+027748X0100Y0280R180 S1      
327m0600            PC880 -1          A01X+144708Y+028491X0198Y0197R090 S1      
327m0600            PR7087-1   M      A01X+145108Y+028491X0198Y0197R090 S1      
317m0601            VIA   -    M      A01X+052276Y+046182X0200Y         S2      
017m0601            VIA   -    M      A18X+052276Y+046182X0260Y         S2      
017m0601                  -    MD0100PA00X+052276Y+046182                       
327m0601            PC790 -1          A01X+052131Y+046448X0198Y0197R090 S1      
327m0601            PU101 -8          A01X+052021Y+045643X0100Y0280     S1      
317m0602            VIA   -    M      A01X+097991Y+044560X0200Y         S2      
017m0602            VIA   -    M      A18X+097991Y+044560X0260Y         S2      
017m0602                  -    MD0100PA00X+097991Y+044560                       
327m0602            PR7099-1          A01X+097593Y+044307X0198Y0197R270 S1      
327m0602            PU119 -5          A01X+097930Y+045156X0100Y0280     S1      
327m0602            PC904 -1   M      A01X+097993Y+044307X0198Y0197R270 S1      
317m0603            VIA   -    M      A01X+067776Y+011078X0200Y         S2      
017m0603            VIA   -    M      A18X+067776Y+011078X0260Y         S2      
017m0603                  -    MD0100PA00X+067776Y+011078                       
327m0603            PU125 -5          A01X+067473Y+011368X0100Y0280     S1      
327m0603            PR7111-1          A01X+067503Y+010790X0198Y0197R270 S1      
327m0603            PC934 -1   M      A01X+067903Y+010790X0198Y0197R270 S1      
327m0604            DE06F_-2          A18X+122809Y-008196X0120Y0200R090 S2      
317m0604            VIA   -    MD0100PA18X+122540Y-008268X0200Y         S0      
317m0604            VIA   -    MD0100PA18X+108119Y-008271X0200Y    R180 S0      
327m0604            DE06F_-1          A18X+107851Y-008199X0120Y0200R270 S2      
317m0605            VIA   -    M      A01X+155070Y+028172X0200Y         S2      
017m0605            VIA   -    M      A18X+155070Y+028172X0260Y         S2      
017m0605                  -    MD0100PA00X+155070Y+028172                       
327m0605            PC885 -1          A01X+154944Y+028491X0198Y0197R090 S1      
327m0605            PR7089-1   M      A01X+155344Y+028491X0198Y0197R090 S1      
327m0605            PU116 -5          A01X+155266Y+027748X0100Y0280R180 S1      
327m0606            PR7014-1          A01X+082754Y+044831X0198Y0197     S1      
327m0606            PU102 -4          A01X+082175Y+045004X0100Y0280R090 S1      
317m0606            VIA   -    M      A01X+082465Y+045003X0200Y    R090 S2      
017m0606            VIA   -    M      A18X+082465Y+045003X0260Y    R090 S2      
017m0606                  -    MD0100PA00X+082465Y+045003                       
317m0607            VIA   -    M      A01X+126784Y+044904X0200Y    R090 S2      
017m0607            VIA   -    M      A18X+126784Y+044904X0260Y    R090 S2      
017m0607                  -    MD0100PA00X+126784Y+044904                       
327m0607            PC907 -1          A01X+126477Y+045033X0198Y0197R180 S1      
327m0607            PU120 -10         A01X+127096Y+045408X0100Y0280R090 S1      
317m0608            VIA   -    M      A01X+074185Y+014828X0200Y         S2      
017m0608            VIA   -    M      A18X+074185Y+014828X0260Y         S2      
017m0608                  -    MD0100PA00X+074185Y+014828                       
327m0608            Q223  -2          A01X+074473Y+014941X0160Y0240R270 S1      
327m0608            R6077 -1          A01X+073916Y+015154X0198Y0197R180 S1      
327m0608            R6075 -2   M      A01X+073916Y+014754X0198Y0197     S1      
317m0609            VIA   -    MD0100PA18X+151726Y-004036X0200Y         S0      
327m0609            DE16T_-1          A18X+151994Y-004107X0120Y0200R090 S2      
327m0609            DE16T_-2          A18X+129501Y-004097X0120Y0200R270 S2      
317m0609            VIA   -    MD0100PA18X+129769Y-004026X0200Y    R180 S0      
317m0610            VIA   -    M      A01X+170390Y+025639X0200Y         S2      
017m0610            VIA   -    M      A18X+170390Y+025639X0260Y         S2      
017m0610                  -    MD0100PA00X+170390Y+025639                       
327m0610            Q211  -6          A01X+170390Y+025320X0240Y0240R270 S1      
327m0610            R6027 -2   M      A01X+170870Y+025060X0198Y0197R180 S1      
327m0610            Q211  -5          A01X+170390Y+025024X0160Y0240R270 S1      
317m0611            VIA   -    M      A01X+141890Y+046142X0200Y         S2      
017m0611            VIA   -    M      A18X+141890Y+046142X0260Y         S2      
017m0611                  -    MD0100PA00X+141890Y+046142                       
327m0611            Q218  -2          A01X+141490Y+045846X0160Y0240R180 S1      
327m0611            R6052 -1          A01X+142290Y+046434X0198Y0197R090 S1      
327m0611            R6050 -2   M      A01X+141890Y+046434X0198Y0197R270 S1      
317m0612            VIA   -    M      A01X+047303Y+011078X0200Y         S2      
017m0612            VIA   -    M      A18X+047303Y+011078X0260Y         S2      
017m0612                  -    MD0100PA00X+047303Y+011078                       
327m0612            PR7107-1          A01X+047031Y+010790X0198Y0197R270 S1      
327m0612            PC924 -1   M      A01X+047431Y+010790X0198Y0197R270 S1      
327m0612            PU123 -5          A01X+047001Y+011368X0100Y0280     S1      
327m0613            DE06F_-1          A18X+122809Y-007999X0120Y0200R090 S2      
317m0613            VIA   -    MD0100PA18X+122540Y-007928X0200Y         S0      
317m0613            VIA   -    MD0100PA18X+108119Y-007931X0200Y    R180 S0      
327m0613            DE06F_-2          A18X+107851Y-008002X0120Y0200R270 S2      
317m0614            VIA   -    M      A01X+145680Y+026611X0200Y         S2      
017m0614            VIA   -    M      A18X+145680Y+026611X0260Y         S2      
017m0614                  -    MD0100PA00X+145680Y+026611                       
327m0614            PU115 -10         A01X+145423Y+026960X0100Y0280R180 S1      
327m0614            PC884 -1          A01X+145603Y+026268X0198Y0197R270 S1      
317m0615            VIA   -    M      A01X+172492Y+044904X0200Y    R090 S2      
017m0615            VIA   -    M      A18X+172492Y+044904X0260Y    R090 S2      
017m0615                  -    MD0100PA00X+172492Y+044904                       
327m0615            PU122 -10         A01X+172805Y+045408X0100Y0280R090 S1      
327m0615            PC917 -1          A01X+172186Y+045033X0198Y0197R180 S1      
317m0616            VIA   -    MD0100PA01X+173640Y-007268X0200Y         S0      
327m0616            DE05F_-1          A01X+173909Y-007196X0120Y0200R090 S1      
317m0616            VIA   -    MD0100PA01X+159219Y-007271X0200Y    R180 S0      
327m0616            DE05F_-2          A01X+158951Y-007199X0120Y0200R270 S1      
317m0617            VIA   -    M      A01X+176389Y+026611X0200Y         S2      
017m0617            VIA   -    M      A18X+176389Y+026611X0260Y         S2      
017m0617                  -    MD0100PA00X+176389Y+026611                       
327m0617            PC897 -1          A01X+176311Y+026268X0198Y0197R270 S1      
327m0617            PU118 -10         A01X+176132Y+026960X0100Y0280R180 S1      
317m0618            VIA   -    M      A01X+052082Y+044260X0200Y         S2      
017m0618            VIA   -    M      A18X+052082Y+044260X0260Y         S2      
017m0618                  -    MD0100PA00X+052082Y+044260                       
327m0618            PU101 -5          A01X+052021Y+044856X0100Y0280     S1      
327m0618            PR7011-1          A01X+051684Y+044007X0198Y0197R270 S1      
327m0618            PC794 -1   M      A01X+052084Y+044007X0198Y0197R270 S1      
317m0619            VIA   -    M      A01X+128174Y+046103X0200Y    R090 S2      
017m0619            VIA   -    M      A18X+128174Y+046103X0260Y    R090 S2      
017m0619                  -    MD0100PA00X+128174Y+046103                       
327m0619            PU120 -5          A01X+127884Y+045801X0100Y0280R090 S1      
327m0619            PR7101-1          A01X+128462Y+045831X0198Y0197     S1      
327m0619            PC906 -1   M      A01X+128462Y+046231X0198Y0197     S1      
327m0620            PU126 -10         A01X+077316Y+012156X0100Y0280     S1      
317m0620            VIA   -    M      A01X+076961Y+012428X0200Y         S2      
017m0620            VIA   -    M      A18X+076961Y+012428X0260Y         S2      
017m0620                  -    MD0100PA00X+076961Y+012428                       
327m0620            PC937 -1          A01X+076942Y+012775X0198Y0197R090 S1      
317m0621            VIA   -    M      A01X+175887Y+026590X0200Y         S2      
017m0621            VIA   -    M      A18X+175887Y+026590X0260Y         S2      
017m0621                  -    MD0100PA00X+175887Y+026590                       
327m0621            PU118 -9          A01X+175935Y+026960X0100Y0280R180 S1      
327m0621            R6021 -2          A01X+175911Y+026268X0198Y0197R090 S1      
317m0622            VIA   -    M      A01X+096277Y+045142X0200Y         S2      
017m0622            VIA   -    M      A18X+096277Y+045142X0260Y         S2      
017m0622                  -    MD0100PA00X+096277Y+045142                       
327m0622            Q216  -5          A01X+095982Y+045438X0160Y0240R180 S1      
327m0622            Q216  -6          A01X+096277Y+045438X0240Y0240R180 S1      
327m0622            R6036 -2   M      A01X+096282Y+044849X0198Y0197R090 S1      
317m0623            VIA   -    M      A01X+057497Y+012466X0200Y         S2      
017m0623            VIA   -    M      A18X+057497Y+012466X0260Y         S2      
017m0623                  -    MD0100PA00X+057497Y+012466                       
327m0623            PU124 -8          A01X+057237Y+012156X0100Y0280     S1      
327m0623            PC922 -1          A01X+057469Y+012775X0198Y0197R090 S1      
327m0624            DE01F_-2          A01X+084501Y-007199X0120Y0200R270 S1      
327m0624            DE01F_-1          A01X+097479Y-007196X0120Y0200R090 S1      
317m0625            VIA   -    M      A01X+141786Y+044842X0200Y         S2      
017m0625            VIA   -    M      A18X+141786Y+044842X0260Y         S2      
017m0625                  -    MD0100PA00X+141786Y+044842                       
327m0625            Q218  -5          A01X+141490Y+045138X0160Y0240R180 S1      
327m0625            Q218  -6          A01X+141786Y+045138X0240Y0240R180 S1      
327m0625            R6048 -2   M      A01X+141790Y+044549X0198Y0197R090 S1      
317m0626            VIA   -    MD0100PA18X+173640Y-008268X0200Y         S0      
327m0626            DE05F_-2          A18X+173909Y-008196X0120Y0200R090 S2      
317m0626            VIA   -    MD0100PA18X+159219Y-008271X0200Y    R180 S0      
327m0626            DE05F_-1          A18X+158951Y-008199X0120Y0200R270 S2      
327m0627            PR7088-1          A01X+145508Y+028491X0198Y0197R090 S1      
317m0627            VIA   -    M      A01X+145427Y+028198X0200Y         S2      
017m0627            VIA   -    M      A18X+145427Y+028198X0260Y         S2      
017m0627                  -    MD0100PA00X+145427Y+028198                       
327m0627            PU115 -4          A01X+145227Y+027748X0100Y0280R180 S1      
317m0628            VIA   -    M      A01X+088295Y+048626X0200Y    R090 S2      
017m0628            VIA   -    M      A18X+088295Y+048626X0260Y    R090 S2      
017m0628                  -    MD0100PA00X+088295Y+048626                       
327m0628            Q215  -5          A01X+088000Y+048330X0160Y0240R270 S1      
327m0628            Q215  -6          A01X+088000Y+048626X0240Y0240R270 S1      
327m0628            R5961 -2   M      A01X+088588Y+048630X0198Y0197R180 S1      
317m0629            VIA   -    M      A01X+097203Y+044607X0200Y         S2      
017m0629            VIA   -    M      A18X+097203Y+044607X0260Y         S2      
017m0629                  -    MD0100PA00X+097203Y+044607                       
327m0629            PU119 -4          A01X+097733Y+045156X0100Y0280     S1      
327m0629            PR7100-1          A01X+097193Y+044307X0198Y0197R270 S1      
317m0630            VIA   -    MD0100PA18X+173640Y-007928X0200Y         S0      
327m0630            DE05F_-1          A18X+173909Y-007999X0120Y0200R090 S2      
317m0630            VIA   -    MD0100PA18X+159219Y-007931X0200Y    R180 S0      
327m0630            DE05F_-2          A18X+158951Y-008002X0120Y0200R270 S2      
327m0631            PR7094-1          A01X+165980Y+028491X0198Y0197R090 S1      
317m0631            VIA   -    M      A01X+165900Y+028198X0200Y         S2      
017m0631            VIA   -    M      A18X+165900Y+028198X0260Y         S2      
017m0631                  -    MD0100PA00X+165900Y+028198                       
327m0631            PU117 -4          A01X+165699Y+027748X0100Y0280R180 S1      
327m0632            PC792 -1          A01X+080769Y+045233X0198Y0197R180 S1      
317m0632            VIA   -    M      A01X+081045Y+045333X0200Y    R090 S2      
017m0632            VIA   -    M      A18X+081045Y+045333X0260Y    R090 S2      
017m0632                  -    MD0100PA00X+081045Y+045333                       
327m0632            PU102 -8          A01X+081388Y+045201X0100Y0280R090 S1      
317m0633            VIA   -    M      A01X+172458Y+045421X0200Y    R090 S2      
017m0633            VIA   -    M      A18X+172458Y+045421X0260Y    R090 S2      
017m0633                  -    MD0100PA00X+172458Y+045421                       
327m0633            PU122 -9          A01X+172805Y+045604X0100Y0280R090 S1      
327m0633            R6043 -2          A01X+172186Y+045433X0198Y0197     S1      
317m0634            VIA   -    MD0100PA18X+123076Y-004363X0200Y         S0      
327m0634            DE16T_-2          A18X+123344Y-004291X0120Y0200R090 S2      
327m0634            DE16T_-1          A18X+100851Y-004281X0120Y0200R270 S2      
317m0634            VIA   -    MD0100PA18X+101119Y-004353X0200Y    R180 S0      
327m0635            PC797 -1          A01X+080769Y+044433X0198Y0197R180 S1      
317m0635            VIA   -    M      A01X+081075Y+044304X0200Y    R090 S2      
017m0635            VIA   -    M      A18X+081075Y+044304X0260Y    R090 S2      
017m0635                  -    MD0100PA00X+081075Y+044304                       
327m0635            PU102 -10         A01X+081388Y+044808X0100Y0280R090 S1      
317m0636            VIA   -    M      A01X+173882Y+045603X0200Y    R090 S2      
017m0636            VIA   -    M      A18X+173882Y+045603X0260Y    R090 S2      
017m0636                  -    MD0100PA00X+173882Y+045603                       
327m0636            PU122 -4          A01X+173592Y+045604X0100Y0280R090 S1      
327m0636            PR7106-1          A01X+174171Y+045431X0198Y0197     S1      
317m0637            VIA   -    MD0100PA18X+148190Y-008268X0200Y         S0      
327m0637            DE06F_-2          A18X+148459Y-008196X0120Y0200R090 S2      
327m0637            DE06F_-1          A18X+133501Y-008199X0120Y0200R270 S2      
317m0637            VIA   -    MD0100PA18X+133769Y-008271X0200Y    R180 S0      
317m0638            VIA   -    M      A01X+144670Y+026570X0200Y         S2      
017m0638            VIA   -    M      A18X+144670Y+026570X0260Y         S2      
017m0638                  -    MD0100PA00X+144670Y+026570                       
327m0638            PU115 -8          A01X+145030Y+026960X0100Y0280R180 S1      
327m0638            PC882 -1          A01X+144803Y+026268X0198Y0197R270 S1      
317m0639            VIA   -    M      A01X+179006Y+047451X0200Y    R090 S2      
017m0639            VIA   -    M      A18X+179006Y+047451X0260Y    R090 S2      
017m0639                  -    MD0100PA00X+179006Y+047451                       
327m0639            R6049 -2   M      A01X+179299Y+047456X0198Y0197R180 S1      
327m0639            Q219  -5          A01X+178710Y+047156X0160Y0240R270 S1      
327m0639            Q219  -6          A01X+178710Y+047451X0240Y0240R270 S1      
317m0640            VIA   -    MD0100PA18X+148190Y-007928X0200Y         S0      
327m0640            DE06F_-1          A18X+148459Y-007999X0120Y0200R090 S2      
327m0640            DE06F_-2          A18X+133501Y-008002X0120Y0200R270 S2      
317m0640            VIA   -    MD0100PA18X+133769Y-007931X0200Y    R180 S0      
317m0641            VIA   -    M      A01X+139681Y+025639X0200Y         S2      
017m0641            VIA   -    M      A18X+139681Y+025639X0260Y         S2      
017m0641                  -    MD0100PA00X+139681Y+025639                       
327m0641            Q208  -5          A01X+139681Y+025024X0160Y0240R270 S1      
327m0641            R6016 -2   M      A01X+140162Y+025060X0198Y0197R180 S1      
327m0641            Q208  -6          A01X+139681Y+025320X0240Y0240R270 S1      
317m0642            VIA   -    M      A01X+051331Y+046200X0200Y         S2      
017m0642            VIA   -    M      A18X+051331Y+046200X0260Y         S2      
017m0642                  -    MD0100PA00X+051331Y+046200                       
327m0642            PC796 -1          A01X+051331Y+046448X0198Y0197R090 S1      
327m0642            PU101 -10         A01X+051627Y+045643X0100Y0280     S1      
327m0643            DE01F_-1          A01X+084501Y-007002X0120Y0200R270 S1      
327m0643            DE01F_-2          A01X+097479Y-006999X0120Y0200R090 S1      
317m0644            VIA   -    M      A01X+138685Y+024911X0200Y         S2      
017m0644            VIA   -    M      A18X+138685Y+024911X0260Y         S2      
017m0644                  -    MD0100PA00X+138685Y+024911                       
327m0644            Q208  -2          A01X+138972Y+025024X0160Y0240R270 S1      
327m0644            PR7091-1          A01X+138416Y+025237X0198Y0197R180 S1      
327m0644            R6018 -2   M      A01X+138416Y+024837X0198Y0197     S1      
317m0645            VIA   -    M      A01X+086995Y+048730X0200Y    R090 S2      
017m0645            VIA   -    M      A18X+086995Y+048730X0260Y    R090 S2      
017m0645                  -    MD0100PA00X+086995Y+048730                       
327m0645            R5965 -1          A01X+086703Y+049130X0198Y0197R180 S1      
327m0645            R5963 -2   M      A01X+086703Y+048730X0198Y0197     S1      
327m0645            Q215  -2          A01X+087291Y+048330X0160Y0240R270 S1      
317m0646            VIA   -    M      A01X+126749Y+045421X0200Y    R090 S2      
017m0646            VIA   -    M      A18X+126749Y+045421X0260Y    R090 S2      
017m0646                  -    MD0100PA00X+126749Y+045421                       
327m0646            PU120 -9          A01X+127096Y+045604X0100Y0280R090 S1      
327m0646            R6031 -2          A01X+126477Y+045433X0198Y0197     S1      
317m0647            VIA   -    MD0100PA01X+151726Y-003376X0200Y         S0      
327m0647            DE14T_-1          A01X+151994Y-003304X0120Y0200R090 S1      
327m0647            DE14T_-2          A01X+129501Y-003294X0120Y0200R270 S1      
317m0647            VIA   -    MD0100PA01X+129769Y-003366X0200Y    R180 S0      
327m0648            PR7096-1          A01X+176216Y+028491X0198Y0197R090 S1      
317m0648            VIA   -    M      A01X+176136Y+028198X0200Y         S2      
017m0648            VIA   -    M      A18X+176136Y+028198X0260Y         S2      
017m0648                  -    MD0100PA00X+176136Y+028198                       
327m0648            PU118 -4          A01X+175935Y+027748X0100Y0280R180 S1      
317m0649            VIA   -    M      A01X+050473Y+046142X0200Y         S2      
017m0649            VIA   -    M      A18X+050473Y+046142X0260Y         S2      
017m0649                  -    MD0100PA00X+050473Y+046142                       
327m0649            Q214  -2          A01X+050073Y+045846X0160Y0240R180 S1      
327m0649            R5964 -1          A01X+050873Y+046434X0198Y0197R090 S1      
327m0649            R5962 -2   M      A01X+050473Y+046434X0198Y0197R270 S1      
317m0650            VIA   -    M      A01X+126754Y+045933X0200Y    R090 S2      
017m0650            VIA   -    M      A18X+126754Y+045933X0260Y    R090 S2      
017m0650                  -    MD0100PA00X+126754Y+045933                       
327m0650            PU120 -8          A01X+127096Y+045801X0100Y0280R090 S1      
327m0650            PC902 -1          A01X+126477Y+045833X0198Y0197R180 S1      
317m0651            VIA   -    MD0100PA01X+148190Y-007268X0200Y         S0      
327m0651            DE04F_-1          A01X+148459Y-007196X0120Y0200R090 S1      
327m0651            DE04F_-2          A01X+133501Y-007199X0120Y0200R270 S1      
317m0651            VIA   -    MD0100PA01X+133769Y-007271X0200Y    R180 S0      
317m0652            VIA   -    M      A01X+169393Y+024911X0200Y         S2      
017m0652            VIA   -    M      A18X+169393Y+024911X0260Y         S2      
017m0652                  -    MD0100PA00X+169393Y+024911                       
327m0652            PR7098-1          A01X+169124Y+025237X0198Y0197R180 S1      
327m0652            R6029 -2   M      A01X+169124Y+024837X0198Y0197     S1      
327m0652            Q211  -2          A01X+169681Y+025024X0160Y0240R270 S1      
317m0653            VIA   -    M      A01X+143500Y+044260X0200Y         S2      
017m0653            VIA   -    M      A18X+143500Y+044260X0260Y         S2      
017m0653                  -    MD0100PA00X+143500Y+044260                       
327m0653            PR7103-1          A01X+143102Y+044007X0198Y0197R270 S1      
327m0653            PU121 -5          A01X+143438Y+044856X0100Y0280     S1      
327m0653            PC914 -1   M      A01X+143502Y+044007X0198Y0197R270 S1      
327m0654            DE03F_-2          A01X+122809Y-006999X0120Y0200R090 S1      
317m0654            VIA   -    MD0100PA01X+122540Y-006928X0200Y         S0      
317m0654            VIA   -    MD0100PA01X+108119Y-006931X0200Y    R180 S0      
327m0654            DE03F_-1          A01X+107851Y-007002X0120Y0200R270 S1      
317m0655            VIA   -    M      A01X+155415Y+026590X0200Y         S2      
017m0655            VIA   -    M      A18X+155415Y+026590X0260Y         S2      
017m0655                  -    MD0100PA00X+155415Y+026590                       
327m0655            PU116 -9          A01X+155463Y+026960X0100Y0280R180 S1      
327m0655            R6011 -2          A01X+155439Y+026268X0198Y0197R090 S1      
317m0656            VIA   -    M      A01X+172463Y+045933X0200Y    R090 S2      
017m0656            VIA   -    M      A18X+172463Y+045933X0260Y    R090 S2      
017m0656                  -    MD0100PA00X+172463Y+045933                       
327m0656            PU122 -8          A01X+172805Y+045801X0100Y0280R090 S1      
327m0656            PC912 -1          A01X+172186Y+045833X0198Y0197R180 S1      
317m0657            VIA   -    MD0100PA01X+123076Y-003023X0200Y         S0      
327m0657            DE13T_-2          A01X+123344Y-003094X0120Y0200R090 S1      
327m0657            DE13T_-1          A01X+100851Y-003084X0120Y0200R270 S1      
317m0657            VIA   -    MD0100PA01X+101119Y-003013X0200Y    R180 S0      
317m0658            VIA   -    M      A01X+165142Y+026570X0200Y         S2      
017m0658            VIA   -    M      A18X+165142Y+026570X0260Y         S2      
017m0658                  -    MD0100PA00X+165142Y+026570                       
327m0658            PU117 -8          A01X+165502Y+026960X0100Y0280R180 S1      
327m0658            PC891 -1          A01X+165275Y+026268X0198Y0197R270 S1      
317m0659            VIA   -    M      A01X+051294Y+044307X0200Y         S2      
017m0659            VIA   -    M      A18X+051294Y+044307X0260Y         S2      
017m0659                  -    MD0100PA00X+051294Y+044307                       
327m0659            PU101 -4          A01X+051824Y+044856X0100Y0280     S1      
327m0659            PR7013-1          A01X+051284Y+044007X0198Y0197R270 S1      
317m0660            VIA   -    M      A01X+131997Y+047556X0200Y    R090 S2      
017m0660            VIA   -    M      A18X+131997Y+047556X0260Y    R090 S2      
017m0660                  -    MD0100PA00X+131997Y+047556                       
327m0660            Q217  -2          A01X+132293Y+047156X0160Y0240R270 S1      
327m0660            R6041 -1          A01X+131705Y+047956X0198Y0197R180 S1      
327m0660            R6039 -2   M      A01X+131705Y+047556X0198Y0197     S1      
327m0661            DE11T_-1          A01X+094994Y-003278X0120Y0200R090 S1      
327m0661            DE11T_-2          A01X+072501Y-003281X0120Y0200R270 S1      
317m0662            VIA   -    M      A01X+175378Y+026570X0200Y         S2      
017m0662            VIA   -    M      A18X+175378Y+026570X0260Y         S2      
017m0662                  -    MD0100PA00X+175378Y+026570                       
327m0662            PC896 -1          A01X+175511Y+026268X0198Y0197R270 S1      
327m0662            PU118 -8          A01X+175738Y+026960X0100Y0280R180 S1      
327m0663            PU102 -5          A01X+082175Y+045201X0100Y0280R090 S1      
317m0663            VIA   -    M      A01X+082465Y+045503X0200Y    R090 S2      
017m0663            VIA   -    M      A18X+082465Y+045503X0260Y    R090 S2      
017m0663                  -    MD0100PA00X+082465Y+045503                       
327m0663            PC795 -1   M      A01X+082754Y+045631X0198Y0197     S1      
327m0663            PR7012-1          A01X+082754Y+045231X0198Y0197     S1      
317m0664            VIA   -    M      A01X+097240Y+046500X0200Y         S2      
017m0664            VIA   -    M      A18X+097240Y+046500X0260Y         S2      
017m0664                  -    MD0100PA00X+097240Y+046500                       
327m0664            PC905 -1          A01X+097240Y+046740X0198Y0197R090 S1      
327m0664            PU119 -10         A01X+097536Y+045943X0100Y0280     S1      
327m0665            DE13T_-1          A01X+123344Y-003291X0120Y0200R090 S1      
317m0665            VIA   -    MD0100PA01X+123076Y-003363X0200Y         S0      
317m0665            VIA   -    MD0100PA01X+101119Y-003353X0200Y    R180 S0      
327m0665            DE13T_-2          A01X+100851Y-003281X0120Y0200R270 S1      
327m0666            PR7090-1          A01X+155744Y+028491X0198Y0197R090 S1      
317m0666            VIA   -    M      A01X+155664Y+028198X0200Y         S2      
017m0666            VIA   -    M      A18X+155664Y+028198X0260Y         S2      
017m0666                  -    MD0100PA00X+155664Y+028198                       
327m0666            PU116 -4          A01X+155463Y+027748X0100Y0280R180 S1      
327m0667            DE12T_-2          A18X+094994Y-003278X0120Y0200R090 S2      
327m0667            DE12T_-1          A18X+072501Y-003281X0120Y0200R270 S2      
317m0668            VIA   -    M      A01X+148921Y+024911X0200Y         S2      
017m0668            VIA   -    M      A18X+148921Y+024911X0260Y         S2      
017m0668                  -    MD0100PA00X+148921Y+024911                       
327m0668            Q209  -2          A01X+149208Y+025024X0160Y0240R270 S1      
327m0668            PR7092-1          A01X+148652Y+025237X0198Y0197R180 S1      
327m0668            R6019 -2   M      A01X+148652Y+024837X0198Y0197     S1      
327m0669            DE02F_-1          A18X+084501Y-007199X0120Y0200R270 S2      
327m0669            DE02F_-2          A18X+097479Y-007196X0120Y0200R090 S2      
317m0670            VIA   -    M      A01X+145178Y+026590X0200Y         S2      
017m0670            VIA   -    M      A18X+145178Y+026590X0260Y         S2      
017m0670                  -    MD0100PA00X+145178Y+026590                       
327m0670            PU115 -9          A01X+145227Y+026960X0100Y0280R180 S1      
327m0670            R6010 -2          A01X+145203Y+026268X0198Y0197R090 S1      
317m0671            VIA   -    M      A01X+050368Y+044842X0200Y         S2      
017m0671            VIA   -    M      A18X+050368Y+044842X0260Y         S2      
017m0671                  -    MD0100PA00X+050368Y+044842                       
327m0671            Q214  -6          A01X+050368Y+045138X0240Y0240R180 S1      
327m0671            R5960 -2   M      A01X+050373Y+044549X0198Y0197R090 S1      
327m0671            Q214  -5          A01X+050073Y+045138X0160Y0240R180 S1      
327m0672            DE03F_-1          A01X+122809Y-007196X0120Y0200R090 S1      
317m0672            VIA   -    MD0100PA01X+122540Y-007268X0200Y         S0      
317m0672            VIA   -    MD0100PA01X+108119Y-007271X0200Y    R180 S0      
327m0672            DE03F_-2          A01X+107851Y-007199X0120Y0200R270 S1      
317m0673            VIA   -    MD0100PA01X+173640Y-006928X0200Y         S0      
327m0673            DE05F_-2          A01X+173909Y-006999X0120Y0200R090 S1      
317m0673            VIA   -    MD0100PA01X+159219Y-006931X0200Y    R180 S0      
327m0673            DE05F_-1          A01X+158951Y-007002X0120Y0200R270 S1      
317m0674            VIA   -    M      A01X+159157Y+024911X0200Y         S2      
017m0674            VIA   -    M      A18X+159157Y+024911X0260Y         S2      
017m0674                  -    MD0100PA00X+159157Y+024911                       
327m0674            Q210  -2          A01X+159445Y+025024X0160Y0240R270 S1      
327m0674            PR7097-1          A01X+158888Y+025237X0198Y0197R180 S1      
327m0674            R6028 -2   M      A01X+158888Y+024837X0198Y0197     S1      
327m0675            DE15T_-2          A18X+180444Y-004317X0120Y0200R090 S2      
317m0675            VIA   -    MD0100PA18X+180176Y-004389X0200Y         S0      
317m0675            VIA   -    MD0100PA18X+158219Y-004379X0200Y    R180 S0      
327m0675            DE15T_-1          A18X+157951Y-004307X0120Y0200R270 S2      
327m0676            DE15T_-1          A01X+180444Y-003317X0120Y0200R090 S1      
317m0676            VIA   -    MD0100PA01X+180176Y-003389X0200Y         S0      
317m0676            VIA   -    MD0100PA01X+158219Y-003379X0200Y    R180 S0      
327m0676            DE15T_-2          A01X+157951Y-003307X0120Y0200R270 S1      
317m0677            VIA   -    M      A01X+175542Y+028172X0200Y         S2      
017m0677            VIA   -    M      A18X+175542Y+028172X0260Y         S2      
017m0677                  -    MD0100PA00X+175542Y+028172                       
327m0677            PU118 -5          A01X+175738Y+027748X0100Y0280R180 S1      
327m0677            PC893 -1          A01X+175416Y+028491X0198Y0197R090 S1      
327m0677            PR7095-1   M      A01X+175816Y+028491X0198Y0197R090 S1      
317m0678            VIA   -    MD0100PA01X+148190Y-006928X0200Y         S0      
327m0678            DE04F_-2          A01X+148459Y-006999X0120Y0200R090 S1      
327m0678            DE04F_-1          A01X+133501Y-007002X0120Y0200R270 S1      
317m0678            VIA   -    MD0100PA01X+133769Y-006931X0200Y    R180 S0      
317m0679            VIA   -    M      A01X+154906Y+026570X0200Y         S2      
017m0679            VIA   -    M      A18X+154906Y+026570X0260Y         S2      
017m0679                  -    MD0100PA00X+154906Y+026570                       
327m0679            PU116 -8          A01X+155266Y+026960X0100Y0280R180 S1      
327m0679            PC881 -1          A01X+155039Y+026268X0198Y0197R270 S1      
317m0680            VIA   -    M      A01X+166152Y+026611X0200Y         S2      
017m0680            VIA   -    M      A18X+166152Y+026611X0260Y         S2      
017m0680                  -    MD0100PA00X+166152Y+026611                       
327m0680            PU117 -10         A01X+165896Y+026960X0100Y0280R180 S1      
327m0680            PC895 -1          A01X+166075Y+026268X0198Y0197R270 S1      
317m0681            VIA   -    M      A01X+155916Y+026611X0200Y         S2      
017m0681            VIA   -    M      A18X+155916Y+026611X0260Y         S2      
017m0681                  -    MD0100PA00X+155916Y+026611                       
327m0681            PU116 -10         A01X+155660Y+026960X0100Y0280R180 S1      
327m0681            PC887 -1          A01X+155839Y+026268X0198Y0197R270 S1      
317m0682            VIA   -    M      A01X+099470Y+026590X0200Y         S2      
017m0682            VIA   -    M      A18X+099470Y+026590X0260Y         S2      
017m0682                  -    MD0100PA00X+099470Y+026590                       
327m0682            PU111 -9          A01X+099518Y+026960X0100Y0280R180 S1      
327m0682            R5990 -2          A01X+099494Y+026268X0198Y0197R090 S1      
317m0683            VIA   -    M      A01X+165651Y+026590X0200Y         S2      
017m0683            VIA   -    M      A18X+165651Y+026590X0260Y         S2      
017m0683                  -    MD0100PA00X+165651Y+026590                       
327m0683            PU117 -9          A01X+165699Y+026960X0100Y0280R180 S1      
327m0683            R6020 -2          A01X+165675Y+026268X0198Y0197R090 S1      
317m0684            VIA   -    M      A01X+165306Y+028172X0200Y         S2      
017m0684            VIA   -    M      A18X+165306Y+028172X0260Y         S2      
017m0684                  -    MD0100PA00X+165306Y+028172                       
327m0684            PU117 -5          A01X+165502Y+027748X0100Y0280R180 S1      
327m0684            PC890 -1          A01X+165180Y+028491X0198Y0197R090 S1      
327m0684            PR7093-1   M      A01X+165580Y+028491X0198Y0197R090 S1      
317m0685            VIA   -    M      A01X+130178Y+026590X0200Y         S2      
017m0685            VIA   -    M      A18X+130178Y+026590X0260Y         S2      
017m0685                  -    MD0100PA00X+130178Y+026590                       
327m0685            PU113 -9          A01X+130226Y+026960X0100Y0280R180 S1      
327m0685            R6001 -2          A01X+130202Y+026268X0198Y0197R090 S1      
317m0686            VIA   -    M      A01X+103212Y+024911X0200Y         S2      
017m0686            VIA   -    M      A18X+103212Y+024911X0260Y         S2      
017m0686                  -    MD0100PA00X+103212Y+024911                       
327m0686            Q205  -2          A01X+103500Y+025024X0160Y0240R270 S1      
327m0686            PR7080-1          A01X+102943Y+025237X0198Y0197R180 S1      
327m0686            R5999 -2   M      A01X+102943Y+024837X0198Y0197     S1      
317m0687            VIA   -    M      A01X+109361Y+028172X0200Y         S2      
017m0687            VIA   -    M      A18X+109361Y+028172X0260Y         S2      
017m0687                  -    MD0100PA00X+109361Y+028172                       
327m0687            PU112 -5          A01X+109557Y+027748X0100Y0280R180 S1      
327m0687            PC862 -1          A01X+109235Y+028491X0198Y0197R090 S1      
327m0687            PR7077-1   M      A01X+109635Y+028491X0198Y0197R090 S1      
317m0688            VIA   -    M      A01X+109706Y+026590X0200Y         S2      
017m0688            VIA   -    M      A18X+109706Y+026590X0260Y         S2      
017m0688                  -    MD0100PA00X+109706Y+026590                       
327m0688            PU112 -9          A01X+109754Y+026960X0100Y0280R180 S1      
327m0688            R5991 -2          A01X+109730Y+026268X0198Y0197R090 S1      
317m0689            VIA   -    M      A01X+119434Y+026570X0200Y         S2      
017m0689            VIA   -    M      A18X+119434Y+026570X0260Y         S2      
017m0689                  -    MD0100PA00X+119434Y+026570                       
327m0689            PC871 -1          A01X+119566Y+026268X0198Y0197R270 S1      
327m0689            PU114 -8          A01X+119794Y+026960X0100Y0280R180 S1      
317m0690            VIA   -    M      A01X+120444Y+026611X0200Y         S2      
017m0690            VIA   -    M      A18X+120444Y+026611X0260Y         S2      
017m0690                  -    MD0100PA00X+120444Y+026611                       
327m0690            PC873 -1          A01X+120366Y+026268X0198Y0197R270 S1      
327m0690            PU114 -10         A01X+120187Y+026960X0100Y0280R180 S1      
317m0691            VIA   -    M      A01X+094425Y+023984X0200Y    R090 S2      
017m0691            VIA   -    M      A18X+094425Y+023984X0260Y    R090 S2      
017m0691                  -    MD0100PA00X+094425Y+023984                       
327m0691            Q204  -2          A01X+094311Y+024272X0160Y0240     S1      
327m0691            PR7079-1          A01X+093812Y+023682X0198Y0197R270 S1      
327m0691            R5998 -2   M      A01X+094257Y+023687X0198Y0197R180 S1      
317m0692            VIA   -    M      A01X+114759Y+025320X0200Y         S2      
017m0692            VIA   -    M      A18X+114759Y+025320X0260Y         S2      
017m0692                  -    MD0100PA00X+114759Y+025320                       
327m0692            Q206  -5          A01X+114445Y+025024X0160Y0240R270 S1      
327m0692            Q206  -6          A01X+114445Y+025320X0240Y0240R270 S1      
327m0692            R6006 -2   M      A01X+114925Y+025060X0198Y0197R180 S1      
317m0693            VIA   -    M      A01X+104208Y+025639X0200Y         S2      
017m0693            VIA   -    M      A18X+104208Y+025639X0260Y         S2      
017m0693                  -    MD0100PA00X+104208Y+025639                       
327m0693            Q205  -5          A01X+104208Y+025024X0160Y0240R270 S1      
327m0693            R5997 -2   M      A01X+104689Y+025060X0198Y0197R180 S1      
327m0693            Q205  -6          A01X+104208Y+025320X0240Y0240R270 S1      
317m0694            VIA   -    M      A01X+110208Y+026611X0200Y         S2      
017m0694            VIA   -    M      A18X+110208Y+026611X0260Y         S2      
017m0694                  -    MD0100PA00X+110208Y+026611                       
327m0694            PC867 -1          A01X+110130Y+026268X0198Y0197R270 S1      
327m0694            PU112 -10         A01X+109951Y+026960X0100Y0280R180 S1      
317m0695            VIA   -    M      A01X+129670Y+026570X0200Y         S2      
017m0695            VIA   -    M      A18X+129670Y+026570X0260Y         S2      
017m0695                  -    MD0100PA00X+129670Y+026570                       
327m0695            PU113 -8          A01X+130030Y+026960X0100Y0280R180 S1      
327m0695            PC875 -1          A01X+129802Y+026268X0198Y0197R270 S1      
317m0696            VIA   -    M      A01X+093696Y+024981X0200Y    R090 S2      
017m0696            VIA   -    M      A18X+093696Y+024981X0260Y    R090 S2      
017m0696                  -    MD0100PA00X+093696Y+024981                       
327m0696            Q204  -5          A01X+094311Y+024981X0160Y0240     S1      
327m0696            Q204  -6          A01X+094016Y+024981X0240Y0240     S1      
327m0696            R5996 -2   M      A01X+094276Y+025461X0198Y0197R270 S1      
317m0697            VIA   -    M      A01X+119597Y+028172X0200Y         S2      
017m0697            VIA   -    M      A18X+119597Y+028172X0260Y         S2      
017m0697                  -    MD0100PA00X+119597Y+028172                       
327m0697            PU114 -5          A01X+119794Y+027748X0100Y0280R180 S1      
327m0697            PC870 -1          A01X+119472Y+028491X0198Y0197R090 S1      
327m0697            PR7081-1   M      A01X+119872Y+028491X0198Y0197R090 S1      
327m0698            PR7078-1          A01X+110035Y+028491X0198Y0197R090 S1      
317m0698            VIA   -    M      A01X+109955Y+028198X0200Y         S2      
017m0698            VIA   -    M      A18X+109955Y+028198X0260Y         S2      
017m0698                  -    MD0100PA00X+109955Y+028198                       
327m0698            PU112 -4          A01X+109754Y+027748X0100Y0280R180 S1      
317m0699            VIA   -    M      A01X+129833Y+028172X0200Y         S2      
017m0699            VIA   -    M      A18X+129833Y+028172X0260Y         S2      
017m0699                  -    MD0100PA00X+129833Y+028172                       
327m0699            PU113 -5          A01X+130030Y+027748X0100Y0280R180 S1      
327m0699            PC874 -1          A01X+129708Y+028491X0198Y0197R090 S1      
327m0699            PR7083-1   M      A01X+130108Y+028491X0198Y0197R090 S1      
327m0700            PR7076-1          A01X+099799Y+028491X0198Y0197R090 S1      
317m0700            VIA   -    M      A01X+099719Y+028198X0200Y         S2      
017m0700            VIA   -    M      A18X+099719Y+028198X0260Y         S2      
017m0700                  -    MD0100PA00X+099719Y+028198                       
327m0700            PU111 -4          A01X+099518Y+027748X0100Y0280R180 S1      
317m0701            VIA   -    M      A01X+099971Y+026611X0200Y         S2      
017m0701            VIA   -    M      A18X+099971Y+026611X0260Y         S2      
017m0701                  -    MD0100PA00X+099971Y+026611                       
327m0701            PU111 -10         A01X+099715Y+026960X0100Y0280R180 S1      
327m0701            PC866 -1          A01X+099894Y+026268X0198Y0197R270 S1      
317m0702            VIA   -    M      A01X+109197Y+026570X0200Y         S2      
017m0702            VIA   -    M      A18X+109197Y+026570X0260Y         S2      
017m0702                  -    MD0100PA00X+109197Y+026570                       
327m0702            PU112 -8          A01X+109557Y+026960X0100Y0280R180 S1      
327m0702            PC863 -1          A01X+109330Y+026268X0198Y0197R270 S1      
317m0703            VIA   -    M      A01X+098961Y+026570X0200Y         S2      
017m0703            VIA   -    M      A18X+098961Y+026570X0260Y         S2      
017m0703                  -    MD0100PA00X+098961Y+026570                       
327m0703            PU111 -8          A01X+099321Y+026960X0100Y0280R180 S1      
327m0703            PC865 -1          A01X+099094Y+026268X0198Y0197R270 S1      
317m0704            VIA   -    M      A01X+155628Y+014374X0200Y         S2      
017m0704            VIA   -    M      A18X+155628Y+014374X0260Y         S2      
017m0704                  -    MD0100PA00X+155628Y+014374                       
327m0704            Q230  -3          A01X+155654Y+014646X0240Y0240R270 S1      
327m0704            R6118 -1          A01X+155877Y+014125X0198Y0197     S1      
327m0704            R6116 -2   M      A01X+155494Y+014125X0198Y0197     S1      
327m0705            PR7084-1          A01X+130508Y+028491X0198Y0197R090 S1      
317m0705            VIA   -    M      A01X+130427Y+028198X0200Y         S2      
017m0705            VIA   -    M      A18X+130427Y+028198X0260Y         S2      
017m0705                  -    MD0100PA00X+130427Y+028198                       
327m0705            PU113 -4          A01X+130226Y+027748X0100Y0280R180 S1      
317m0706            VIA   -    M      A01X+145392Y+014374X0200Y         S2      
017m0706            VIA   -    M      A18X+145392Y+014374X0260Y         S2      
017m0706                  -    MD0100PA00X+145392Y+014374                       
327m0706            Q229  -3          A01X+145418Y+014646X0240Y0240R270 S1      
327m0706            R6107 -1          A01X+145641Y+014125X0198Y0197     S1      
327m0706            R6105 -2   M      A01X+145258Y+014125X0198Y0197     S1      
317m0707            VIA   -    M      A01X+099125Y+028172X0200Y         S2      
017m0707            VIA   -    M      A18X+099125Y+028172X0260Y         S2      
017m0707                  -    MD0100PA00X+099125Y+028172                       
327m0707            PU111 -5          A01X+099321Y+027748X0100Y0280R180 S1      
327m0707            PC860 -1          A01X+098999Y+028491X0198Y0197R090 S1      
327m0707            PR7075-1   M      A01X+099399Y+028491X0198Y0197R090 S1      
317m0708            VIA   -    M      A01X+135156Y+014374X0200Y         S2      
017m0708            VIA   -    M      A18X+135156Y+014374X0260Y         S2      
017m0708                  -    MD0100PA00X+135156Y+014374                       
327m0708            Q228  -3          A01X+135182Y+014646X0240Y0240R270 S1      
327m0708            R6106 -1          A01X+135405Y+014125X0198Y0197     S1      
327m0708            R6104 -2   M      A01X+135022Y+014125X0198Y0197     S1      
317m0709            VIA   -    M      A01X+113448Y+024911X0200Y         S2      
017m0709            VIA   -    M      A18X+113448Y+024911X0260Y         S2      
017m0709                  -    MD0100PA00X+113448Y+024911                       
327m0709            Q206  -2          A01X+113736Y+025024X0160Y0240R270 S1      
327m0709            PR7085-1          A01X+113179Y+025237X0198Y0197R180 S1      
327m0709            R6008 -2   M      A01X+113179Y+024837X0198Y0197     S1      
317m0710            VIA   -    M      A01X+165864Y+014374X0200Y         S2      
017m0710            VIA   -    M      A18X+165864Y+014374X0260Y         S2      
017m0710                  -    MD0100PA00X+165864Y+014374                       
327m0710            Q231  -3          A01X+165890Y+014646X0240Y0240R270 S1      
327m0710            R6119 -1          A01X+166113Y+014125X0198Y0197     S1      
327m0710            R6117 -2   M      A01X+165730Y+014125X0198Y0197     S1      
317m0711            VIA   -    M      A01X+124681Y+025639X0200Y         S2      
017m0711            VIA   -    M      A18X+124681Y+025639X0260Y         S2      
017m0711                  -    MD0100PA00X+124681Y+025639                       
327m0711            Q207  -6          A01X+124681Y+025320X0240Y0240R270 S1      
327m0711            R6007 -2   M      A01X+125162Y+025060X0198Y0197R180 S1      
327m0711            Q207  -5          A01X+124681Y+025024X0160Y0240R270 S1      
317m0712            VIA   -    M      A01X+109920Y+014374X0200Y         S2      
017m0712            VIA   -    M      A18X+109920Y+014374X0260Y         S2      
017m0712                  -    MD0100PA00X+109920Y+014374                       
327m0712            Q226  -3          A01X+109945Y+014646X0240Y0240R270 S1      
327m0712            R6094 -1          A01X+110168Y+014125X0198Y0197     S1      
327m0712            R6092 -2   M      A01X+109786Y+014125X0198Y0197     S1      
317m0713            VIA   -    M      A01X+123684Y+024911X0200Y         S2      
017m0713            VIA   -    M      A18X+123684Y+024911X0260Y         S2      
017m0713                  -    MD0100PA00X+123684Y+024911                       
327m0713            Q207  -2          A01X+123972Y+025024X0160Y0240R270 S1      
327m0713            PR7086-1          A01X+123415Y+025237X0198Y0197R180 S1      
327m0713            R6009 -2   M      A01X+123415Y+024837X0198Y0197     S1      
317m0714            VIA   -    M      A01X+089447Y+014374X0200Y         S2      
017m0714            VIA   -    M      A18X+089447Y+014374X0260Y         S2      
017m0714                  -    MD0100PA00X+089447Y+014374                       
327m0714            Q224  -3          A01X+089473Y+014646X0240Y0240R270 S1      
327m0714            R6082 -1          A01X+089696Y+014125X0198Y0197     S1      
327m0714            R6080 -2   M      A01X+089313Y+014125X0198Y0197     S1      
317m0715            VIA   -    M      A01X+119942Y+026590X0200Y         S2      
017m0715            VIA   -    M      A18X+119942Y+026590X0260Y         S2      
017m0715                  -    MD0100PA00X+119942Y+026590                       
327m0715            PU114 -9          A01X+119990Y+026960X0100Y0280R180 S1      
327m0715            R6000 -2          A01X+119966Y+026268X0198Y0197R090 S1      
317m0716            VIA   -    M      A01X+099683Y+014374X0200Y         S2      
017m0716            VIA   -    M      A18X+099683Y+014374X0260Y         S2      
017m0716                  -    MD0100PA00X+099683Y+014374                       
327m0716            Q225  -3          A01X+099709Y+014646X0240Y0240R270 S1      
327m0716            R6083 -1          A01X+099932Y+014125X0198Y0197     S1      
327m0716            R6081 -2   M      A01X+099549Y+014125X0198Y0197     S1      
317m0717            VIA   -    M      A01X+130680Y+026611X0200Y         S2      
017m0717            VIA   -    M      A18X+130680Y+026611X0260Y         S2      
017m0717                  -    MD0100PA00X+130680Y+026611                       
327m0717            PU113 -10         A01X+130423Y+026960X0100Y0280R180 S1      
327m0717            PC877 -1          A01X+130602Y+026268X0198Y0197R270 S1      
317m0718            VIA   -    M      A01X+120156Y+014374X0200Y         S2      
017m0718            VIA   -    M      A18X+120156Y+014374X0260Y         S2      
017m0718                  -    MD0100PA00X+120156Y+014374                       
327m0718            Q227  -3          A01X+120182Y+014646X0240Y0240R270 S1      
327m0718            R6095 -1          A01X+120405Y+014125X0198Y0197     S1      
327m0718            R6093 -2   M      A01X+120022Y+014125X0198Y0197     S1      
317m0719            VIA   -    M      A01X+058500Y+025639X0200Y         S2      
017m0719            VIA   -    M      A18X+058500Y+025639X0260Y         S2      
017m0719                  -    MD0100PA00X+058500Y+025639                       
327m0719            Q201  -6          A01X+058500Y+025320X0240Y0240R270 S1      
327m0719            Q201  -5          A01X+058500Y+025024X0160Y0240R270 S1      
327m0719            R5977 -2   M      A01X+058980Y+025060X0198Y0197R180 S1      
327m0720            PR7082-1          A01X+120272Y+028491X0198Y0197R090 S1      
317m0720            VIA   -    M      A01X+120191Y+028198X0200Y         S2      
017m0720            VIA   -    M      A18X+120191Y+028198X0260Y         S2      
017m0720                  -    MD0100PA00X+120191Y+028198                       
327m0720            PU114 -4          A01X+119990Y+027748X0100Y0280R180 S1      
317m0721            VIA   -    M      A01X+053975Y+014374X0200Y         S2      
017m0721            VIA   -    M      A18X+053975Y+014374X0260Y         S2      
017m0721                  -    MD0100PA00X+053975Y+014374                       
327m0721            Q221  -3          A01X+054000Y+014646X0240Y0240R270 S1      
327m0721            R6059 -1          A01X+054224Y+014125X0198Y0197     S1      
327m0721            R6057 -2   M      A01X+053841Y+014125X0198Y0197     S1      
317m0722            VIA   -    M      A01X+063652Y+028172X0200Y         S2      
017m0722            VIA   -    M      A18X+063652Y+028172X0260Y         S2      
017m0722                  -    MD0100PA00X+063652Y+028172                       
327m0722            PU108 -5          A01X+063849Y+027748X0100Y0280R180 S1      
327m0722            PC842 -1          A01X+063527Y+028491X0198Y0197R090 S1      
327m0722            PR7065-1   M      A01X+063927Y+028491X0198Y0197R090 S1      
317m0723            VIA   -    M      A01X+064211Y+014374X0200Y         S2      
017m0723            VIA   -    M      A18X+064211Y+014374X0260Y         S2      
017m0723                  -    MD0100PA00X+064211Y+014374                       
327m0723            R6070 -1          A01X+064460Y+014125X0198Y0197     S1      
327m0723            Q222  -3          A01X+064237Y+014646X0240Y0240R270 S1      
327m0723            R6068 -2   M      A01X+064077Y+014125X0198Y0197     S1      
317m0724            VIA   -    M      A01X+043739Y+014374X0200Y         S2      
017m0724            VIA   -    M      A18X+043739Y+014374X0260Y         S2      
017m0724                  -    MD0100PA00X+043739Y+014374                       
327m0724            Q220  -3          A01X+043764Y+014646X0240Y0240R270 S1      
327m0724            R6056 -2          A01X+043604Y+014125X0198Y0197     S1      
327m0724            R6058 -1          A01X+043987Y+014125X0198Y0197     S1      
317m0725            VIA   -    M      A01X+053761Y+026590X0200Y         S2      
017m0725            VIA   -    M      A18X+053761Y+026590X0260Y         S2      
017m0725                  -    MD0100PA00X+053761Y+026590                       
327m0725            PU107 -9          A01X+053809Y+026960X0100Y0280R180 S1      
327m0725            R5970 -2          A01X+053785Y+026268X0198Y0197R090 S1      
317m0726            VIA   -    M      A01X+074447Y+014374X0200Y         S2      
017m0726            VIA   -    M      A18X+074447Y+014374X0260Y         S2      
017m0726                  -    MD0100PA00X+074447Y+014374                       
327m0726            Q223  -3          A01X+074473Y+014646X0240Y0240R270 S1      
327m0726            R6071 -1          A01X+074696Y+014125X0198Y0197     S1      
327m0726            R6069 -2   M      A01X+074313Y+014125X0198Y0197     S1      
317m0727            VIA   -    M      A01X+074234Y+026590X0200Y         S2      
017m0727            VIA   -    M      A18X+074234Y+026590X0260Y         S2      
017m0727                  -    MD0100PA00X+074234Y+026590                       
327m0727            PU109 -9          A01X+074282Y+026960X0100Y0280R180 S1      
327m0727            R5980 -2          A01X+074258Y+026268X0198Y0197R090 S1      
317m0728            VIA   -    M      A01X+047267Y+024911X0200Y         S2      
017m0728            VIA   -    M      A18X+047267Y+024911X0260Y         S2      
017m0728                  -    MD0100PA00X+047267Y+024911                       
327m0728            PR7067-1          A01X+046998Y+025237X0198Y0197R180 S1      
327m0728            R5978 -2   M      A01X+046998Y+024837X0198Y0197     S1      
327m0728            Q200  -2          A01X+047555Y+025024X0160Y0240R270 S1      
317m0729            VIA   -    M      A01X+063489Y+026570X0200Y         S2      
017m0729            VIA   -    M      A18X+063489Y+026570X0260Y         S2      
017m0729                  -    MD0100PA00X+063489Y+026570                       
327m0729            PU108 -8          A01X+063849Y+026960X0100Y0280R180 S1      
327m0729            PC843 -1          A01X+063622Y+026268X0198Y0197R270 S1      
327m0730            PR7072-1          A01X+084799Y+028491X0198Y0197R090 S1      
317m0730            VIA   -    M      A01X+084719Y+028198X0200Y         S2      
017m0730            VIA   -    M      A18X+084719Y+028198X0260Y         S2      
017m0730                  -    MD0100PA00X+084719Y+028198                       
327m0730            PU110 -4          A01X+084518Y+027748X0100Y0280R180 S1      
317m0731            VIA   -    M      A01X+064499Y+026611X0200Y         S2      
017m0731            VIA   -    M      A18X+064499Y+026611X0260Y         S2      
017m0731                  -    MD0100PA00X+064499Y+026611                       
327m0731            PC847 -1          A01X+064422Y+026268X0198Y0197R270 S1      
327m0731            PU108 -10         A01X+064242Y+026960X0100Y0280R180 S1      
317m0732            VIA   -    M      A01X+141090Y+046192X0200Y         S2      
017m0732            VIA   -    M      A18X+141090Y+046192X0260Y         S2      
017m0732                  -    MD0100PA00X+141090Y+046192                       
327m0732            Q218  -3          A01X+141195Y+045846X0240Y0240R180 S1      
327m0732            R6044 -2          A01X+141490Y+046434X0198Y0197R270 S1      
327m0732            R6046 -1   M      A01X+141090Y+046434X0198Y0197R090 S1      
317m0733            VIA   -    M      A01X+131947Y+046756X0200Y    R090 S2      
017m0733            VIA   -    M      A18X+131947Y+046756X0260Y    R090 S2      
017m0733                  -    MD0100PA00X+131947Y+046756                       
327m0733            Q217  -3          A01X+132293Y+046861X0240Y0240R270 S1      
327m0733            R6033 -2          A01X+131705Y+047156X0198Y0197     S1      
327m0733            R6035 -1   M      A01X+131705Y+046756X0198Y0197R180 S1      
317m0734            VIA   -    M      A01X+084971Y+026611X0200Y         S2      
017m0734            VIA   -    M      A18X+084971Y+026611X0260Y         S2      
017m0734                  -    MD0100PA00X+084971Y+026611                       
327m0734            PU110 -10         A01X+084715Y+026960X0100Y0280R180 S1      
327m0734            PC857 -1          A01X+084894Y+026268X0198Y0197R270 S1      
327m0735            R6045 -2   M      A01X+177414Y+046756X0198Y0197     S1      
327m0735            R6047 -1          A01X+177414Y+047156X0198Y0197R180 S1      
317m0735            VIA   -    M      A01X+177656Y+046756X0200Y    R090 S2      
017m0735            VIA   -    M      A18X+177656Y+046756X0260Y    R090 S2      
017m0735                  -    MD0100PA00X+177656Y+046756                       
327m0735            Q219  -3          A01X+178002Y+046861X0240Y0240R270 S1      
317m0736            VIA   -    M      A01X+053252Y+026570X0200Y         S2      
017m0736            VIA   -    M      A18X+053252Y+026570X0260Y         S2      
017m0736                  -    MD0100PA00X+053252Y+026570                       
327m0736            PU107 -8          A01X+053612Y+026960X0100Y0280R180 S1      
327m0736            PC840 -1          A01X+053385Y+026268X0198Y0197R270 S1      
317m0737            VIA   -    M      A01X+095582Y+046492X0200Y         S2      
017m0737            VIA   -    M      A18X+095582Y+046492X0260Y         S2      
017m0737                  -    MD0100PA00X+095582Y+046492                       
327m0737            Q216  -3          A01X+095686Y+046146X0240Y0240R180 S1      
327m0737            R6032 -2          A01X+095982Y+046734X0198Y0197R270 S1      
327m0737            R6034 -1   M      A01X+095582Y+046734X0198Y0197R090 S1      
317m0738            VIA   -    M      A01X+074735Y+026611X0200Y         S2      
017m0738            VIA   -    M      A18X+074735Y+026611X0260Y         S2      
017m0738                  -    MD0100PA00X+074735Y+026611                       
327m0738            PU109 -10         A01X+074478Y+026960X0100Y0280R180 S1      
327m0738            PC850 -1          A01X+074658Y+026268X0198Y0197R270 S1      
327m0739            R5856 -2          A01X+004564Y+046734X0198Y0197R270 S1      
327m0739            R5858 -1   M      A01X+004164Y+046734X0198Y0197R090 S1      
327m0739            Q212  -3          A01X+004269Y+046146X0240Y0240R180 S1      
317m0739            VIA   -    M      A01X+004164Y+046492X0200Y         S2      
017m0739            VIA   -    M      A18X+004164Y+046492X0260Y         S2      
017m0739                  -    MD0100PA00X+004164Y+046492                       
317m0740            VIA   -    M      A01X+057504Y+024911X0200Y         S2      
017m0740            VIA   -    M      A18X+057504Y+024911X0260Y         S2      
017m0740                  -    MD0100PA00X+057504Y+024911                       
327m0740            Q201  -2          A01X+057791Y+025024X0160Y0240R270 S1      
327m0740            PR7068-1          A01X+057234Y+025237X0198Y0197R180 S1      
327m0740            R5979 -2   M      A01X+057234Y+024837X0198Y0197     S1      
317m0741            VIA   -    M      A01X+049673Y+046192X0200Y         S2      
017m0741            VIA   -    M      A18X+049673Y+046192X0260Y         S2      
017m0741                  -    MD0100PA00X+049673Y+046192                       
327m0741            Q214  -3          A01X+049778Y+045846X0240Y0240R180 S1      
327m0741            R5956 -2          A01X+050073Y+046434X0198Y0197R270 S1      
327m0741            R5958 -1   M      A01X+049673Y+046434X0198Y0197R090 S1      
317m0742            VIA   -    M      A01X+078972Y+025639X0200Y         S2      
017m0742            VIA   -    M      A18X+078972Y+025639X0260Y         S2      
017m0742                  -    MD0100PA00X+078972Y+025639                       
327m0742            Q203  -6          A01X+078972Y+025320X0240Y0240R270 S1      
327m0742            Q203  -5          A01X+078972Y+025024X0160Y0240R270 S1      
327m0742            R5987 -2   M      A01X+079453Y+025060X0198Y0197R180 S1      
317m0743            VIA   -    M      A01X+040530Y+046756X0200Y    R090 S2      
017m0743            VIA   -    M      A18X+040530Y+046756X0260Y    R090 S2      
017m0743                  -    MD0100PA00X+040530Y+046756                       
327m0743            Q213  -3          A01X+040876Y+046861X0240Y0240R270 S1      
327m0743            R5857 -2          A01X+040288Y+047156X0198Y0197     S1      
327m0743            R5859 -1   M      A01X+040288Y+046756X0198Y0197R180 S1      
317m0744            VIA   -    M      A01X+063997Y+026590X0200Y         S2      
017m0744            VIA   -    M      A18X+063997Y+026590X0260Y         S2      
017m0744                  -    MD0100PA00X+063997Y+026590                       
327m0744            R5971 -2          A01X+064022Y+026268X0198Y0197R090 S1      
327m0744            PU108 -9          A01X+064046Y+026960X0100Y0280R180 S1      
317m0745            VIA   -    M      A01X+086945Y+047930X0200Y    R090 S2      
017m0745            VIA   -    M      A18X+086945Y+047930X0260Y    R090 S2      
017m0745                  -    MD0100PA00X+086945Y+047930                       
327m0745            Q215  -3          A01X+087291Y+048035X0240Y0240R270 S1      
327m0745            R5957 -2          A01X+086703Y+048330X0198Y0197     S1      
327m0745            R5959 -1   M      A01X+086703Y+047930X0198Y0197R180 S1      
317m0746            VIA   -    M      A01X+073888Y+028172X0200Y         S2      
017m0746            VIA   -    M      A18X+073888Y+028172X0260Y         S2      
017m0746                  -    MD0100PA00X+073888Y+028172                       
327m0746            PU109 -5          A01X+074085Y+027748X0100Y0280R180 S1      
327m0746            PC852 -1          A01X+073763Y+028491X0198Y0197R090 S1      
327m0746            PR7070-1   M      A01X+074163Y+028491X0198Y0197R090 S1      
317m0747            VIA   -    M      A01X+138947Y+024457X0200Y         S2      
017m0747            VIA   -    M      A18X+138947Y+024457X0260Y         S2      
017m0747                  -    MD0100PA00X+138947Y+024457                       
327m0747            Q208  -3          A01X+138972Y+024729X0240Y0240R270 S1      
327m0747            R6012 -2          A01X+139195Y+024208X0198Y0197R180 S1      
327m0747            R6014 -1   M      A01X+138812Y+024208X0198Y0197R180 S1      
327m0748            PR7064-1          A01X+054091Y+028491X0198Y0197R090 S1      
317m0748            VIA   -    M      A01X+054010Y+028198X0200Y         S2      
017m0748            VIA   -    M      A18X+054010Y+028198X0260Y         S2      
017m0748                  -    MD0100PA00X+054010Y+028198                       
327m0748            PU107 -4          A01X+053809Y+027748X0100Y0280R180 S1      
317m0749            VIA   -    M      A01X+149183Y+024457X0200Y         S2      
017m0749            VIA   -    M      A18X+149183Y+024457X0260Y         S2      
017m0749                  -    MD0100PA00X+149183Y+024457                       
327m0749            R6013 -2          A01X+149432Y+024208X0198Y0197R180 S1      
327m0749            Q209  -3          A01X+149208Y+024729X0240Y0240R270 S1      
327m0749            R6015 -1   M      A01X+149049Y+024208X0198Y0197R180 S1      
317m0750            VIA   -    M      A01X+083961Y+026570X0200Y         S2      
017m0750            VIA   -    M      A18X+083961Y+026570X0260Y         S2      
017m0750                  -    MD0100PA00X+083961Y+026570                       
327m0750            PC851 -1          A01X+084094Y+026268X0198Y0197R270 S1      
327m0750            PU110 -8          A01X+084321Y+026960X0100Y0280R180 S1      
317m0751            VIA   -    M      A01X+159419Y+024457X0200Y         S2      
017m0751            VIA   -    M      A18X+159419Y+024457X0260Y         S2      
017m0751                  -    MD0100PA00X+159419Y+024457                       
327m0751            Q210  -3          A01X+159445Y+024729X0240Y0240R270 S1      
327m0751            R6022 -2          A01X+159668Y+024208X0198Y0197R180 S1      
327m0751            R6024 -1   M      A01X+159285Y+024208X0198Y0197R180 S1      
317m0752            VIA   -    M      A01X+053416Y+028172X0200Y         S2      
017m0752            VIA   -    M      A18X+053416Y+028172X0260Y         S2      
017m0752                  -    MD0100PA00X+053416Y+028172                       
327m0752            PU107 -5          A01X+053612Y+027748X0100Y0280R180 S1      
327m0752            PC845 -1          A01X+053291Y+028491X0198Y0197R090 S1      
327m0752            PR7063-1   M      A01X+053691Y+028491X0198Y0197R090 S1      
317m0753            VIA   -    M      A01X+169655Y+024457X0200Y         S2      
017m0753            VIA   -    M      A18X+169655Y+024457X0260Y         S2      
017m0753                  -    MD0100PA00X+169655Y+024457                       
327m0753            Q211  -3          A01X+169681Y+024729X0240Y0240R270 S1      
327m0753            R6023 -2          A01X+169904Y+024208X0198Y0197R180 S1      
327m0753            R6025 -1   M      A01X+169521Y+024208X0198Y0197R180 S1      
317m0754            VIA   -    M      A01X+077976Y+024911X0200Y         S2      
017m0754            VIA   -    M      A18X+077976Y+024911X0260Y         S2      
017m0754                  -    MD0100PA00X+077976Y+024911                       
327m0754            Q203  -2          A01X+078264Y+025024X0160Y0240R270 S1      
327m0754            PR7074-1          A01X+077707Y+025237X0198Y0197R180 S1      
327m0754            R5989 -2   M      A01X+077707Y+024837X0198Y0197     S1      
317m0755            VIA   -    M      A01X+103474Y+024457X0200Y         S2      
017m0755            VIA   -    M      A18X+103474Y+024457X0260Y         S2      
017m0755                  -    MD0100PA00X+103474Y+024457                       
327m0755            Q205  -3          A01X+103500Y+024729X0240Y0240R270 S1      
327m0755            R5993 -2          A01X+103723Y+024208X0198Y0197R180 S1      
327m0755            R5995 -1   M      A01X+103340Y+024208X0198Y0197R180 S1      
317m0756            VIA   -    M      A01X+094878Y+024246X0200Y    R090 S2      
017m0756            VIA   -    M      A18X+094878Y+024246X0260Y    R090 S2      
017m0756                  -    MD0100PA00X+094878Y+024246                       
327m0756            Q204  -3          A01X+094606Y+024272X0240Y0240     S1      
327m0756            R5992 -2          A01X+095128Y+024495X0198Y0197R270 S1      
327m0756            R5994 -1   M      A01X+095128Y+024112X0198Y0197R270 S1      
317m0757            VIA   -    M      A01X+084125Y+028172X0200Y         S2      
017m0757            VIA   -    M      A18X+084125Y+028172X0260Y         S2      
017m0757                  -    MD0100PA00X+084125Y+028172                       
327m0757            PC855 -1          A01X+083999Y+028491X0198Y0197R090 S1      
327m0757            PR7069-1   M      A01X+084399Y+028491X0198Y0197R090 S1      
327m0757            PU110 -5          A01X+084321Y+027748X0100Y0280R180 S1      
317m0758            VIA   -    M      A01X+123946Y+024457X0200Y         S2      
017m0758            VIA   -    M      A18X+123946Y+024457X0260Y         S2      
017m0758                  -    MD0100PA00X+123946Y+024457                       
327m0758            Q207  -3          A01X+123972Y+024729X0240Y0240R270 S1      
327m0758            R6003 -2          A01X+124195Y+024208X0198Y0197R180 S1      
327m0758            R6005 -1   M      A01X+123812Y+024208X0198Y0197R180 S1      
317m0759            VIA   -    M      A01X+084470Y+026590X0200Y         S2      
017m0759            VIA   -    M      A18X+084470Y+026590X0260Y         S2      
017m0759                  -    MD0100PA00X+084470Y+026590                       
327m0759            R5981 -2          A01X+084494Y+026268X0198Y0197R090 S1      
327m0759            PU110 -9          A01X+084518Y+026960X0100Y0280R180 S1      
317m0760            VIA   -    M      A01X+113710Y+024457X0200Y         S2      
017m0760            VIA   -    M      A18X+113710Y+024457X0260Y         S2      
017m0760                  -    MD0100PA00X+113710Y+024457                       
327m0760            Q206  -3          A01X+113736Y+024729X0240Y0240R270 S1      
327m0760            R6002 -2          A01X+113959Y+024208X0198Y0197R180 S1      
327m0760            R6004 -1   M      A01X+113576Y+024208X0198Y0197R180 S1      
317m0761            VIA   -    M      A01X+073725Y+026570X0200Y         S2      
017m0761            VIA   -    M      A18X+073725Y+026570X0260Y         S2      
017m0761                  -    MD0100PA00X+073725Y+026570                       
327m0761            PU109 -8          A01X+074085Y+026960X0100Y0280R180 S1      
327m0761            PC853 -1          A01X+073858Y+026268X0198Y0197R270 S1      
317m0762            VIA   -    M      A01X+047529Y+024457X0200Y         S2      
017m0762            VIA   -    M      A18X+047529Y+024457X0260Y         S2      
017m0762                  -    MD0100PA00X+047529Y+024457                       
327m0762            Q200  -3          A01X+047555Y+024729X0240Y0240R270 S1      
327m0762            R5972 -2          A01X+047778Y+024208X0198Y0197R180 S1      
327m0762            R5974 -1   M      A01X+047395Y+024208X0198Y0197R180 S1      
327m0763            PR7071-1          A01X+074563Y+028491X0198Y0197R090 S1      
317m0763            VIA   -    M      A01X+074482Y+028198X0200Y         S2      
017m0763            VIA   -    M      A18X+074482Y+028198X0260Y         S2      
017m0763                  -    MD0100PA00X+074482Y+028198                       
327m0763            PU109 -4          A01X+074282Y+027748X0100Y0280R180 S1      
317m0764            VIA   -    M      A01X+057766Y+024457X0200Y         S2      
017m0764            VIA   -    M      A18X+057766Y+024457X0260Y         S2      
017m0764                  -    MD0100PA00X+057766Y+024457                       
327m0764            R5973 -2          A01X+058014Y+024208X0198Y0197R180 S1      
327m0764            R5975 -1   M      A01X+057631Y+024208X0198Y0197R180 S1      
327m0764            Q201  -3          A01X+057791Y+024729X0240Y0240R270 S1      
317m0765            VIA   -    M      A01X+069050Y+025320X0200Y         S2      
017m0765            VIA   -    M      A18X+069050Y+025320X0260Y         S2      
017m0765                  -    MD0100PA00X+069050Y+025320                       
327m0765            Q202  -5          A01X+068736Y+025024X0160Y0240R270 S1      
327m0765            Q202  -6          A01X+068736Y+025320X0240Y0240R270 S1      
327m0765            R5986 -2   M      A01X+069217Y+025060X0198Y0197R180 S1      
317m0766            VIA   -    M      A01X+068002Y+024457X0200Y         S2      
017m0766            VIA   -    M      A18X+068002Y+024457X0260Y         S2      
017m0766                  -    MD0100PA00X+068002Y+024457                       
327m0766            Q202  -3          A01X+068027Y+024729X0240Y0240R270 S1      
327m0766            R5982 -2          A01X+068250Y+024208X0198Y0197R180 S1      
327m0766            R5984 -1   M      A01X+067868Y+024208X0198Y0197R180 S1      
327m0767            PR7066-1          A01X+064327Y+028491X0198Y0197R090 S1      
317m0767            VIA   -    M      A01X+064246Y+028198X0200Y         S2      
017m0767            VIA   -    M      A18X+064246Y+028198X0260Y         S2      
017m0767                  -    MD0100PA00X+064246Y+028198                       
327m0767            PU108 -4          A01X+064046Y+027748X0100Y0280R180 S1      
317m0768            VIA   -    M      A01X+078238Y+024457X0200Y         S2      
017m0768            VIA   -    M      A18X+078238Y+024457X0260Y         S2      
017m0768                  -    MD0100PA00X+078238Y+024457                       
327m0768            Q203  -3          A01X+078264Y+024729X0240Y0240R270 S1      
327m0768            R5983 -2          A01X+078487Y+024208X0198Y0197R180 S1      
327m0768            R5985 -1   M      A01X+078104Y+024208X0198Y0197R180 S1      
317m0769            VIA   -    M      A01X+048264Y+025639X0200Y         S2      
017m0769            VIA   -    M      A18X+048264Y+025639X0260Y         S2      
017m0769                  -    MD0100PA00X+048264Y+025639                       
327m0769            Q200  -6          A01X+048264Y+025320X0240Y0240R270 S1      
327m0769            Q200  -5          A01X+048264Y+025024X0160Y0240R270 S1      
327m0769            R5976 -2   M      A01X+048744Y+025060X0198Y0197R180 S1      
317m0770            VIA   -    M      A01X+067740Y+024911X0200Y         S2      
017m0770            VIA   -    M      A18X+067740Y+024911X0260Y         S2      
017m0770                  -    MD0100PA00X+067740Y+024911                       
327m0770            PR7073-1          A01X+067471Y+025237X0198Y0197R180 S1      
327m0770            Q202  -2          A01X+068027Y+025024X0160Y0240R270 S1      
327m0770            R5988 -2   M      A01X+067471Y+024837X0198Y0197     S1      
317m0771            VIA   -    M      A01X+054263Y+026611X0200Y         S2      
017m0771            VIA   -    M      A18X+054263Y+026611X0260Y         S2      
017m0771                  -    MD0100PA00X+054263Y+026611                       
327m0771            PU107 -10         A01X+054006Y+026960X0100Y0280R180 S1      
327m0771            PC846 -1          A01X+054185Y+026268X0198Y0197R270 S1      
317SSD15_ADC_A0     VIA   -    MD0100PA00X+176720Y+019230X0200Y         S0      
327SSD15_ADC_A0     R5909 -1          A01X+177277Y+019662X0198Y0197     S1      
317SSD15_ADC_A0     VIA   -    M      A01X+177711Y+017856X0200Y         S2      
017SSD15_ADC_A0     VIA   -    M      A18X+177711Y+017856X0260Y         S2      
017SSD15_ADC_A0           -    MD0100PA00X+177711Y+017856                       
327SSD15_ADC_A0     R672  -1          A01X+178009Y+017666X0198Y0197     S1      
327SSD15_ADC_A0     R675  -1   M      A01X+178009Y+018066X0198Y0197     S1      
327SSD15_ADC_A0     U78   -2          A01X+177380Y+018187X0090Y0240R090 S1      
317SSD12_ADC_A1     VIA   -    M      A01X+147009Y+017266X0200Y         S2      
017SSD12_ADC_A1     VIA   -    M      A18X+147009Y+017266X0260Y         S2      
017SSD12_ADC_A1           -    MD0100PA00X+147009Y+017266                       
327SSD12_ADC_A1     R640  -1   M      A01X+147301Y+017266X0198Y0197     S1      
327SSD12_ADC_A1     R5904 -1          A01X+146778Y+016871X0198Y0197R180 S1      
327SSD12_ADC_A1     R637  -1   M      A01X+147301Y+016866X0198Y0197     S1      
327SSD12_ADC_A1     U75   -1          A01X+146672Y+017990X0090Y0240R090 S1      
317SSD14_ADC_A0     VIA   -    MD0100PA00X+166484Y+019230X0200Y         S0      
327SSD14_ADC_A0     R5907 -1          A01X+168088Y+019666X0198Y0197R180 S1      
317SSD14_ADC_A0     VIA   -    M      A01X+167475Y+017856X0200Y         S2      
017SSD14_ADC_A0     VIA   -    M      A18X+167475Y+017856X0260Y         S2      
017SSD14_ADC_A0           -    MD0100PA00X+167475Y+017856                       
327SSD14_ADC_A0     U77   -2          A01X+167144Y+018187X0090Y0240R090 S1      
327SSD14_ADC_A0     R660  -1          A01X+167773Y+017666X0198Y0197     S1      
327SSD14_ADC_A0     R664  -1   M      A01X+167773Y+018066X0198Y0197     S1      
317SSD15_ADC_A1     VIA   -    M      A01X+177717Y+017266X0200Y         S2      
017SSD15_ADC_A1     VIA   -    M      A18X+177717Y+017266X0260Y         S2      
017SSD15_ADC_A1           -    MD0100PA00X+177717Y+017266                       
327SSD15_ADC_A1     R673  -1   M      A01X+178009Y+017266X0198Y0197     S1      
327SSD15_ADC_A1     R5908 -1          A01X+177486Y+016871X0198Y0197R180 S1      
327SSD15_ADC_A1     R671  -1   M      A01X+178009Y+016866X0198Y0197     S1      
327SSD15_ADC_A1     U78   -1          A01X+177380Y+017990X0090Y0240R090 S1      
317SSD13_ADC_A1     VIA   -    M      A01X+157245Y+017266X0200Y         S2      
017SSD13_ADC_A1     VIA   -    M      A18X+157245Y+017266X0260Y         S2      
017SSD13_ADC_A1           -    MD0100PA00X+157245Y+017266                       
327SSD13_ADC_A1     U76   -1          A01X+156908Y+017990X0090Y0240R090 S1      
327SSD13_ADC_A1     R651  -1   M      A01X+157537Y+017266X0198Y0197     S1      
327SSD13_ADC_A1     R5905 -1          A01X+157014Y+016871X0198Y0197R180 S1      
327SSD13_ADC_A1     R648  -1   M      A01X+157537Y+016866X0198Y0197     S1      
317SSD14_ADC_A1     VIA   -    M      A01X+167481Y+017266X0200Y         S2      
017SSD14_ADC_A1     VIA   -    M      A18X+167481Y+017266X0260Y         S2      
017SSD14_ADC_A1           -    MD0100PA00X+167481Y+017266                       
327SSD14_ADC_A1     R5906 -1          A01X+167250Y+016871X0198Y0197R180 S1      
327SSD14_ADC_A1     R659  -1   M      A01X+167773Y+016866X0198Y0197     S1      
327SSD14_ADC_A1     R663  -1   M      A01X+167773Y+017266X0198Y0197     S1      
327SSD14_ADC_A1     U77   -1          A01X+167144Y+017990X0090Y0240R090 S1      
317SSD8_ADC_A1      VIA   -    M      A01X+101300Y+017266X0200Y         S2      
017SSD8_ADC_A1      VIA   -    M      A18X+101300Y+017266X0260Y         S2      
017SSD8_ADC_A1            -    MD0100PA00X+101300Y+017266                       
327SSD8_ADC_A1      U71   -1          A01X+100963Y+017990X0090Y0240R090 S1      
327SSD8_ADC_A1      R594  -1          A01X+101592Y+016866X0198Y0197     S1      
327SSD8_ADC_A1      R597  -1   M      A01X+101592Y+017266X0198Y0197     S1      
317SSD8_ADC_A1      VIA   -    MD0100PA00X+102171Y+019266X0200Y         S0      
327SSD8_ADC_A1      R5898 -1          A01X+101907Y+019266X0198Y0197R180 S1      
317m0772            VIA   -    MD0100PA00X+106077Y+105346X0200Y         S0      
317m0772            VIA   -    M      A01X+097399Y+091004X0200Y         S2      
017m0772            VIA   -    M      A18X+097399Y+091004X0260Y         S2      
017m0772                  -    MD0100PA00X+097399Y+091004                       
327m0772            R3482 -1          A18X+097441Y+090550X0198Y0197     S2      
327m0772            R3473 -1          A18X+107055Y+116065X0198Y0197R180 S2      
327SPI_PEX2_CLK_R   R3471 -1          A18X+107030Y+114853X0198Y0197R180 S2      
317SPI_PEX2_CLK_R   VIA   -    M      A01X+106787Y+105104X0200Y         S2      
017SPI_PEX2_CLK_R   VIA   -    M      A18X+106787Y+105104X0260Y         S2      
017SPI_PEX2_CLK_R         -    MD0100PA00X+106787Y+105104                       
327SPI_PEX2_CLK_R   U67   -5          A18X+099305Y+090483X0140Y0610R180 S2      
317SPI_PEX2_CLK_R   VIA   -    MD0100PA00X+099030Y+089750X0200Y         S0      
317m0773            VIA   -    M      A01X+107658Y+104133X0200Y         S2      
017m0773            VIA   -    M      A18X+107658Y+104133X0260Y         S2      
017m0773                  -    MD0100PA00X+107658Y+104133                       
327m0773            R3479 -1          A18X+100899Y+087139X0198Y0197R090 S2      
317m0773            VIA   -    MD0100PA00X+100471Y+087139X0200Y         S0      
327m0773            R3472 -1          A18X+107047Y+113533X0198Y0197R270 S2      
317SSD9_ADC_A1      VIA   -    M      A01X+111536Y+017266X0200Y         S2      
017SSD9_ADC_A1      VIA   -    M      A18X+111536Y+017266X0260Y         S2      
017SSD9_ADC_A1            -    MD0100PA00X+111536Y+017266                       
327SSD9_ADC_A1      U72   -1          A01X+111199Y+017990X0090Y0240R090 S1      
327SSD9_ADC_A1      R5899 -1          A01X+111305Y+016871X0198Y0197R180 S1      
327SSD9_ADC_A1      R604  -1   M      A01X+111828Y+016866X0198Y0197     S1      
327SSD9_ADC_A1      R608  -1   M      A01X+111828Y+017266X0198Y0197     S1      
317m0774            VIA   -    MD0100PA00X+107423Y+105584X0200Y         S0      
327m0774            VIA   -    M      A18X+098555Y+091343X0260Y         S2      
327m0774            U67   -2          A18X+098555Y+090483X0140Y0610R180 S2      
317m0774            VIA   -    MD0100PA00X+098931Y+092036X0200Y         S0      
327m0774            R3470 -1          A18X+107421Y+113533X0198Y0197R270 S2      
317m0775            VIA   -    M      A01X+105721Y+104036X0200Y         S2      
017m0775            VIA   -    M      A18X+105721Y+104036X0260Y         S2      
017m0775                  -    MD0100PA00X+105721Y+104036                       
327m0775            R3474 -1          A18X+107076Y+116910X0198Y0197R180 S2      
317m0775            VIA   -    MD0100PA00X+098805Y+088828X0200Y         S0      
327m0775            U67   -14         A18X+098805Y+088323X0140Y0610R180 S2      
317m0776            VIA   -    M      A01X+106508Y+103692X0200Y         S2      
017m0776            VIA   -    M      A18X+106508Y+103692X0260Y         S2      
017m0776                  -    MD0100PA00X+106508Y+103692                       
327m0776            U67   -11         A18X+099555Y+088323X0140Y0610R180 S2      
317m0776            VIA   -    MD0100PA00X+099831Y+088830X0200Y         S0      
327m0776            R3475 -1          A18X+107076Y+116456X0198Y0197R180 S2      
317m0777            VIA   -    MD0100PA00X+133108Y+090050X0200Y         S0      
327m0777            U6    -A6         A01X+133108Y+089759X0160Y         S1      
327m0777            J55   -2          A01X+139253Y+096447X0500Y1350R090 S1      
317m0777            VIA   -    M      A01X+140206Y+096591X0200Y         S2      
017m0777            VIA   -    M      A18X+140206Y+096591X0260Y         S2      
017m0777                  -    MD0100PA00X+140206Y+096591                       
327m0777            R5893 -2          A18X+140206Y+096118X0198Y0197     S2      
317SSD10_ADC_A0     VIA   -    MD0100PA00X+120775Y+019230X0200Y         S0      
327SSD10_ADC_A0     R5901 -1          A01X+122379Y+019666X0198Y0197R180 S1      
317SSD10_ADC_A0     VIA   -    M      A01X+121766Y+017856X0200Y         S2      
017SSD10_ADC_A0     VIA   -    M      A18X+121766Y+017856X0260Y         S2      
017SSD10_ADC_A0           -    MD0100PA00X+121766Y+017856                       
327SSD10_ADC_A0     R617  -1          A01X+122064Y+017666X0198Y0197     S1      
327SSD10_ADC_A0     R620  -1   M      A01X+122064Y+018066X0198Y0197     S1      
327SSD10_ADC_A0     U73   -2          A01X+121435Y+018187X0090Y0240R090 S1      
317SSD11_ADC_A0     VIA   -    MD0100PA00X+131012Y+019230X0200Y         S0      
327SSD11_ADC_A0     R5903 -1          A01X+131568Y+019662X0198Y0197     S1      
327SSD11_ADC_A0     U74   -2          A01X+131672Y+018187X0090Y0240R090 S1      
327SSD11_ADC_A0     R628  -1          A01X+132301Y+017666X0198Y0197     S1      
327SSD11_ADC_A0     R631  -1   M      A01X+132301Y+018066X0198Y0197     S1      
317SSD11_ADC_A0     VIA   -    M      A01X+132002Y+017856X0200Y         S2      
017SSD11_ADC_A0     VIA   -    M      A18X+132002Y+017856X0260Y         S2      
017SSD11_ADC_A0           -    MD0100PA00X+132002Y+017856                       
317SSD11_ADC_A1     VIA   -    M      A01X+132008Y+017266X0200Y         S2      
017SSD11_ADC_A1     VIA   -    M      A18X+132008Y+017266X0260Y         S2      
017SSD11_ADC_A1           -    MD0100PA00X+132008Y+017266                       
327SSD11_ADC_A1     U74   -1          A01X+131672Y+017990X0090Y0240R090 S1      
327SSD11_ADC_A1     R5902 -1          A01X+131778Y+016871X0198Y0197R180 S1      
327SSD11_ADC_A1     R627  -1   M      A01X+132301Y+016866X0198Y0197     S1      
327SSD11_ADC_A1     R630  -1   M      A01X+132301Y+017266X0198Y0197     S1      
317SSD10_ADC_A1     VIA   -    M      A01X+121772Y+017266X0200Y         S2      
017SSD10_ADC_A1     VIA   -    M      A18X+121772Y+017266X0260Y         S2      
017SSD10_ADC_A1           -    MD0100PA00X+121772Y+017266                       
327SSD10_ADC_A1     U73   -1          A01X+121435Y+017990X0090Y0240R090 S1      
327SSD10_ADC_A1     R5900 -1          A01X+121542Y+016871X0198Y0197R180 S1      
327SSD10_ADC_A1     R616  -1   M      A01X+122064Y+016866X0198Y0197     S1      
327SSD10_ADC_A1     R619  -1   M      A01X+122064Y+017266X0198Y0197     S1      
317FPGA_DEBUG_LED   VIA   -    M      A01X+127059Y+090532X0200Y         S2      
017FPGA_DEBUG_LED   VIA   -    M      A18X+127059Y+090532X0260Y         S2      
017FPGA_DEBUG_LED         -    MD0100PA00X+127059Y+090532                       
327FPGA_DEBUG_LED   Q113  -2          A01X+126779Y+090532X0160Y0240R270 S1      
327FPGA_DEBUG_LED   R5892 -2          A18X+127614Y+090517X0198Y0197     S2      
317JP_FPGA_LED      VIA   -    M      A01X+143084Y+096555X0200Y         S2      
017JP_FPGA_LED      VIA   -    M      A18X+143084Y+096555X0260Y         S2      
017JP_FPGA_LED            -    MD0100PA00X+143084Y+096555                       
327JP_FPGA_LED      R5891 -1          A01X+143588Y+095190X0198Y0197     S1      
317JP_FPGA_LED      VIA   -    MD0100PA00X+133265Y+088656X0180Y         S0      
327JP_FPGA_LED      U6    -E7         A01X+133423Y+088499X0160Y         S1      
317P3V3_LED         VIA   -    MD0100PA00X+105030Y+089110X0200Y         S0      
317P3V3_LED         VIA   -    MD0100PA00X+092387Y+079827X0200Y    R090 S0      
317P3V3_LED         VIA   -    MD0100PA00X+101178Y+101659X0200Y         S0      
317P3V3_LED         VIA   -    MD0100PA00X+101284Y+091068X0200Y         S0      
327P3V3_LED         R1396 -1          A01X+101178Y+101397X0198Y0197R270 S1      
317P3V3_LED         VIA   -    MD0100PA00X+100703Y+079297X0200Y         S0      
327P3V3_LED         R4857 -1          A01X+092763Y+079827X0198Y0197     S1      
317P3V3_LED         VIA   -    MD0100PA00X+055224Y+095910X0200Y         S0      
317P3V3_LED         VIA   -    M      A01X+055470Y+101847X0200Y         S2      
017P3V3_LED         VIA   -    M      A18X+055470Y+101847X0260Y         S2      
017P3V3_LED               -    MD0100PA00X+055470Y+101847                       
327P3V3_LED         R1327 -1          A01X+055470Y+101397X0198Y0197R270 S1      
317P3V3_LED         VIA   -    MD0100PA00X+009761Y+101847X0200Y         S0      
327P3V3_LED         R1260 -1          A01X+009761Y+101397X0198Y0197R270 S1      
327P3V3_LED         R5891 -2          A01X+143903Y+095190X0198Y0197     S1      
327P3V3_LED         J57   -2          A01X+143017Y+097608X0500Y1350R090 S1      
317P3V3_LED         VIA   -    MD0100PA00X+143903Y+095768X0200Y         S2      
327P3V3_LED         R1463 -1          A01X+146887Y+101397X0198Y0197R270 S1      
317P3V3_LED         VIA   -    MD0100PA00X+146887Y+101847X0200Y         S2      
317P3V3_LED         VIA   -    MD0100PA00X+129785Y+101448X0200Y         S0      
327P3V3_LED         R3006 -1          A01X+128004Y+090522X0198Y0197R270 S1      
327P3V3_LED         R5892 -1          A18X+127929Y+090517X0198Y0197     S2      
317P3V3_LED         VIA   -    MD0100PA00X+128349Y+090718X0200Y         S0      
317SSD6_ADC_A0      VIA   -    MD0100PA00X+075067Y+019230X0200Y         S0      
327SSD6_ADC_A0      R5896 -1          A01X+076671Y+019666X0198Y0197R180 S1      
317SSD6_ADC_A0      VIA   -    M      A01X+076057Y+017856X0200Y         S2      
017SSD6_ADC_A0      VIA   -    M      A18X+076057Y+017856X0260Y         S2      
017SSD6_ADC_A0            -    MD0100PA00X+076057Y+017856                       
327SSD6_ADC_A0      U61   -2          A01X+075727Y+018187X0090Y0240R090 S1      
327SSD6_ADC_A0      R572  -1          A01X+076356Y+017666X0198Y0197     S1      
327SSD6_ADC_A0      R575  -1   M      A01X+076356Y+018066X0198Y0197     S1      
327m0778            VIA   -    M      A18X+085699Y+082905X0260Y         S2      
317m0778            VIA   -    MD0100PA00X+088767Y+084214X0180Y         S0      
327m0778            R5890 -1          A18X+084992Y+082742X0198Y0197     S2      
327m0778            U5    -C13        A01X+088924Y+084372X0160Y    R180 S1      
317SSD7_ADC_A0      VIA   -    MD0100PA00X+085303Y+019230X0200Y         S0      
327SSD7_ADC_A0      R5897 -1          A01X+085860Y+019662X0198Y0197     S1      
327SSD7_ADC_A0      U62   -2          A01X+085963Y+018187X0090Y0240R090 S1      
327SSD7_ADC_A0      R584  -1          A01X+086592Y+017666X0198Y0197     S1      
327SSD7_ADC_A0      R586  -1   M      A01X+086592Y+018066X0198Y0197     S1      
317SSD7_ADC_A0      VIA   -    M      A01X+086294Y+017856X0200Y         S2      
017SSD7_ADC_A0      VIA   -    M      A18X+086294Y+017856X0260Y         S2      
017SSD7_ADC_A0            -    MD0100PA00X+086294Y+017856                       
317SSD2_ADC_A0      VIA   -    M      A01X+030349Y+017856X0200Y         S2      
017SSD2_ADC_A0      VIA   -    M      A18X+030349Y+017856X0260Y         S2      
017SSD2_ADC_A0            -    MD0100PA00X+030349Y+017856                       
327SSD2_ADC_A0      R529  -1          A01X+030647Y+017666X0198Y0197     S1      
327SSD2_ADC_A0      R532  -1   M      A01X+030647Y+018066X0198Y0197     S1      
327SSD2_ADC_A0      U55   -2          A01X+030018Y+018187X0090Y0240R090 S1      
317SSD2_ADC_A0      VIA   -    MD0100PA00X+030081Y+019286X0200Y         S0      
327SSD2_ADC_A0      R5894 -1          A01X+029952Y+019629X0198Y0197     S1      
317SSD3_ADC_A0      VIA   -    MD0100PA00X+039594Y+019230X0200Y         S0      
327SSD3_ADC_A0      R5895 -1          A01X+040151Y+019662X0198Y0197     S1      
327SSD3_ADC_A0      R540  -1          A01X+040883Y+017666X0198Y0197     S1      
327SSD3_ADC_A0      R543  -1   M      A01X+040883Y+018066X0198Y0197     S1      
327SSD3_ADC_A0      U56   -2          A01X+040254Y+018187X0090Y0240R090 S1      
317SSD3_ADC_A0      VIA   -    M      A01X+040585Y+017856X0200Y         S2      
017SSD3_ADC_A0      VIA   -    M      A18X+040585Y+017856X0260Y         S2      
017SSD3_ADC_A0            -    MD0100PA00X+040585Y+017856                       
317P3V3_CO_MODE     VIA   -    M      A01X+047366Y+047551X0200Y    R090 S2      
017P3V3_CO_MODE     VIA   -    M      A18X+047366Y+047551X0260Y    R090 S2      
017P3V3_CO_MODE           -    MD0100PA00X+047366Y+047551                       
327P3V3_CO_MODE     PU70  -5          A01X+047076Y+047249X0100Y0280R090 S1      
327P3V3_CO_MODE     PC596 -1   M      A01X+047654Y+047678X0198Y0197     S1      
327P3V3_CO_MODE     PR6853-1          A01X+047654Y+047278X0198Y0197     S1      
317P3V3_PG_G1       VIA   -    M      A01X+048948Y+043142X0200Y         S2      
017P3V3_PG_G1       VIA   -    M      A18X+048948Y+043142X0260Y         S2      
017P3V3_PG_G1             -    MD0100PA00X+048948Y+043142                       
327P3V3_PG_G1       Q126  -2          A01X+048548Y+042846X0160Y0240R180 S1      
327P3V3_PG_G1       R5829 -1          A01X+049348Y+043434X0198Y0197R090 S1      
327P3V3_PG_G1       R5828 -2   M      A01X+048948Y+043434X0198Y0197R270 S1      
327P3V3_CO_GATE     PC594 -1          A01X+045669Y+047281X0198Y0197R180 S1      
317P3V3_CO_GATE     VIA   -    M      A01X+045946Y+047380X0200Y    R090 S2      
017P3V3_CO_GATE     VIA   -    M      A18X+045946Y+047380X0260Y    R090 S2      
017P3V3_CO_GATE           -    MD0100PA00X+045946Y+047380                       
327P3V3_CO_GATE     PU70  -8          A01X+046288Y+047249X0100Y0280R090 S1      
327P3V3_CO_ILIMIT   PR6854-1          A01X+047654Y+046878X0198Y0197     S1      
317P3V3_CO_ILIMIT   VIA   -    M      A01X+047366Y+047051X0200Y    R090 S2      
017P3V3_CO_ILIMIT   VIA   -    M      A18X+047366Y+047051X0260Y    R090 S2      
017P3V3_CO_ILIMIT         -    MD0100PA00X+047366Y+047051                       
327P3V3_CO_ILIMIT   PU70  -4          A01X+047076Y+047052X0100Y0280R090 S1      
317PWRGD_P3V3_D     VIA   -    M      A01X+048148Y+043192X0200Y         S2      
017PWRGD_P3V3_D     VIA   -    M      A18X+048148Y+043192X0260Y         S2      
017PWRGD_P3V3_D           -    MD0100PA00X+048148Y+043192                       
327PWRGD_P3V3_D     Q126  -3          A01X+048253Y+042846X0240Y0240R180 S1      
327PWRGD_P3V3_D     R5825 -2          A01X+048548Y+043434X0198Y0197R270 S1      
327PWRGD_P3V3_D     R5826 -1   M      A01X+048148Y+043434X0198Y0197R090 S1      
327P3V3_CO_DV_DT    PC597 -1          A01X+045669Y+046481X0198Y0197R180 S1      
317P3V3_CO_DV_DT    VIA   -    M      A01X+045976Y+046352X0200Y    R090 S2      
017P3V3_CO_DV_DT    VIA   -    M      A18X+045976Y+046352X0260Y    R090 S2      
017P3V3_CO_DV_DT          -    MD0100PA00X+045976Y+046352                       
327P3V3_CO_DV_DT    PU70  -10         A01X+046288Y+046855X0100Y0280R090 S1      
327P3V3_CO_EN       R5824 -2          A01X+045669Y+046881X0198Y0197     S1      
317P3V3_CO_EN       VIA   -    M      A01X+045941Y+046869X0200Y    R090 S2      
017P3V3_CO_EN       VIA   -    M      A18X+045941Y+046869X0260Y    R090 S2      
017P3V3_CO_EN             -    MD0100PA00X+045941Y+046869                       
327P3V3_CO_EN       PU70  -9          A01X+046288Y+047052X0100Y0280R090 S1      
317P3V3_PG_G2       VIA   -    M      A01X+048844Y+041842X0200Y         S2      
017P3V3_PG_G2       VIA   -    M      A18X+048844Y+041842X0260Y         S2      
017P3V3_PG_G2             -    MD0100PA00X+048844Y+041842                       
327P3V3_PG_G2       Q126  -6          A01X+048844Y+042137X0240Y0240R180 S1      
327P3V3_PG_G2       R5827 -2   M      A01X+048848Y+041549X0198Y0197R090 S1      
327P3V3_PG_G2       Q126  -5          A01X+048548Y+042137X0160Y0240R180 S1      
317m0779            VIA   -    M      A01X+026253Y+045111X0200Y         S2      
017m0779            VIA   -    M      A18X+026253Y+045111X0260Y         S2      
017m0779                  -    MD0100PA00X+026253Y+045111                       
327m0779            R88   -1          A01X+025228Y+045387X0198Y0197R180 S1      
327m0779            J21   -A9         A01X+027030Y+044896X0140Y0480R090 S1      
317m0780            VIA   -    M      A01X+022293Y+024457X0200Y         S2      
017m0780            VIA   -    M      A18X+022293Y+024457X0260Y         S2      
017m0780                  -    MD0100PA00X+022293Y+024457                       
327m0780            Q129  -3          A01X+022319Y+024729X0240Y0240R270 S1      
327m0780            R5846 -2          A01X+022542Y+024208X0198Y0197R180 S1      
327m0780            R5848 -1   M      A01X+022159Y+024208X0198Y0197R180 S1      
327m0781            PR6912-1          A01X+039090Y+028491X0198Y0197R090 S1      
317m0781            VIA   -    M      A01X+039010Y+028198X0200Y         S2      
017m0781            VIA   -    M      A18X+039010Y+028198X0260Y         S2      
017m0781                  -    MD0100PA00X+039010Y+028198                       
327m0781            PU77  -4          A01X+038809Y+027748X0100Y0280R180 S1      
317m0782            VIA   -    M      A01X+008052Y+026590X0200Y         S2      
017m0782            VIA   -    M      A18X+008052Y+026590X0260Y         S2      
017m0782                  -    MD0100PA00X+008052Y+026590                       
327m0782            PU76  -9          A01X+008101Y+026960X0100Y0280R180 S1      
327m0782            R5835 -2          A01X+008077Y+026268X0198Y0197R090 S1      
317m0783            VIA   -    M      A01X+028525Y+026590X0200Y         S2      
017m0783            VIA   -    M      A18X+028525Y+026590X0260Y         S2      
017m0783                  -    MD0100PA00X+028525Y+026590                       
327m0783            PU78  -9          A01X+028573Y+026960X0100Y0280R180 S1      
327m0783            R5844 -2          A01X+028549Y+026268X0198Y0197R090 S1      
327PU_FPGA_SN       VIA   -    M      A01X+138409Y+081738X0300Y         S1      
327PU_FPGA_SN       U6    -AB21       A01X+137832Y+083144X0160Y         S1      
327PU_FPGA_SN       R5803 -2          A01X+139454Y+080925X0198Y0197R090 S1      
317m0784            VIA   -    M      A01X+023342Y+025320X0200Y         S2      
017m0784            VIA   -    M      A18X+023342Y+025320X0260Y         S2      
017m0784                  -    MD0100PA00X+023342Y+025320                       
327m0784            Q129  -5          A01X+023027Y+025024X0160Y0240R270 S1      
327m0784            Q129  -6          A01X+023027Y+025320X0240Y0240R270 S1      
327m0784            R5850 -2   M      A01X+023508Y+025060X0198Y0197R180 S1      
317m0785            VIA   -    M      A01X+018289Y+026590X0200Y         S2      
017m0785            VIA   -    M      A18X+018289Y+026590X0260Y         S2      
017m0785                  -    MD0100PA00X+018289Y+026590                       
327m0785            PU75  -9          A01X+018337Y+026960X0100Y0280R180 S1      
327m0785            R5834 -2          A01X+018313Y+026268X0198Y0197R090 S1      
327m0786            R5478 -2          A18X+082755Y+084899X0198Y0197     S2      
327m0786            VIA   -    M      A18X+082884Y+085492X0260Y         S2      
327m0786            C2145 -2   M      A18X+083130Y+085948X0198Y0197R180 S2      
317m0786            VIA   -    MD0100PA00X+083333Y+085556X0200Y         S0      
317m0786            VIA   -    MD0100PA00X+088137Y+085159X0180Y         S0      
327m0786            U5    -F15        A01X+088294Y+085317X0160Y    R180 S1      
317m0787            VIA   -    M      A01X+002555Y+025639X0200Y         S2      
017m0787            VIA   -    M      A18X+002555Y+025639X0260Y         S2      
017m0787                  -    MD0100PA00X+002555Y+025639                       
327m0787            Q127  -6          A01X+002555Y+025320X0240Y0240R270 S1      
327m0787            R5840 -2   M      A01X+003036Y+025060X0198Y0197R180 S1      
327m0787            Q127  -5          A01X+002555Y+025024X0160Y0240R270 S1      
317m0788            VIA   -    M      A01X+012057Y+024457X0200Y         S2      
017m0788            VIA   -    M      A18X+012057Y+024457X0260Y         S2      
017m0788                  -    MD0100PA00X+012057Y+024457                       
327m0788            Q128  -3          A01X+012082Y+024729X0240Y0240R270 S1      
327m0788            R5837 -2          A01X+012306Y+024208X0198Y0197R180 S1      
327m0788            R5839 -1   M      A01X+011923Y+024208X0198Y0197R180 S1      
317m0789            VIA   -    M      A01X+038416Y+028172X0200Y         S2      
017m0789            VIA   -    M      A18X+038416Y+028172X0260Y         S2      
017m0789                  -    MD0100PA00X+038416Y+028172                       
327m0789            PU77  -5          A01X+038612Y+027748X0100Y0280R180 S1      
327m0789            PC653 -1          A01X+038290Y+028491X0198Y0197R090 S1      
327m0789            PR6911-1   M      A01X+038690Y+028491X0198Y0197R090 S1      
317m0790            VIA   -    M      A01X+022031Y+024911X0200Y         S2      
017m0790            VIA   -    M      A18X+022031Y+024911X0260Y         S2      
017m0790                  -    MD0100PA00X+022031Y+024911                       
327m0790            Q129  -2          A01X+022319Y+025024X0160Y0240R270 S1      
327m0790            PR6913-1          A01X+021762Y+025237X0198Y0197R180 S1      
327m0790            R5852 -2   M      A01X+021762Y+024837X0198Y0197     S1      
317m0791            VIA   -    M      A01X+017780Y+026570X0200Y         S2      
017m0791            VIA   -    M      A18X+017780Y+026570X0260Y         S2      
017m0791                  -    MD0100PA00X+017780Y+026570                       
327m0791            PU75  -8          A01X+018140Y+026960X0100Y0280R180 S1      
327m0791            PC640 -1          A01X+017913Y+026268X0198Y0197R270 S1      
317m0792            VIA   -    M      A01X+012791Y+025639X0200Y         S2      
017m0792            VIA   -    M      A18X+012791Y+025639X0260Y         S2      
017m0792                  -    MD0100PA00X+012791Y+025639                       
327m0792            Q128  -6          A01X+012791Y+025320X0240Y0240R270 S1      
327m0792            R5841 -2   M      A01X+013272Y+025060X0198Y0197R180 S1      
327m0792            Q128  -5          A01X+012791Y+025024X0160Y0240R270 S1      
317m0793            VIA   -    M      A01X+039263Y+026611X0200Y         S2      
017m0793            VIA   -    M      A18X+039263Y+026611X0260Y         S2      
017m0793                  -    MD0100PA00X+039263Y+026611                       
327m0793            PU77  -10         A01X+039006Y+026960X0100Y0280R180 S1      
327m0793            PC657 -1          A01X+039185Y+026268X0198Y0197R270 S1      
317m0794            VIA   -    M      A01X+038252Y+026570X0200Y         S2      
017m0794            VIA   -    M      A18X+038252Y+026570X0260Y         S2      
017m0794                  -    MD0100PA00X+038252Y+026570                       
327m0794            PU77  -8          A01X+038612Y+026960X0100Y0280R180 S1      
327m0794            PC654 -1          A01X+038385Y+026268X0198Y0197R270 S1      
317m0795            VIA   -    M      A01X+033264Y+025639X0200Y         S2      
017m0795            VIA   -    M      A18X+033264Y+025639X0260Y         S2      
017m0795                  -    MD0100PA00X+033264Y+025639                       
327m0795            Q130  -6          A01X+033264Y+025320X0240Y0240R270 S1      
327m0795            Q130  -5          A01X+033264Y+025024X0160Y0240R270 S1      
327m0795            R5851 -2   M      A01X+033744Y+025060X0198Y0197R180 S1      
317m0796            VIA   -    M      A01X+007707Y+028172X0200Y         S2      
017m0796            VIA   -    M      A18X+007707Y+028172X0260Y         S2      
017m0796                  -    MD0100PA00X+007707Y+028172                       
327m0796            PU76  -5          A01X+007904Y+027748X0100Y0280R180 S1      
327m0796            PC641 -1          A01X+007582Y+028491X0198Y0197R090 S1      
327m0796            PR6904-1   M      A01X+007982Y+028491X0198Y0197R090 S1      
327m0797            PR6910-1          A01X+028854Y+028491X0198Y0197R090 S1      
317m0797            VIA   -    M      A01X+028774Y+028198X0200Y         S2      
017m0797            VIA   -    M      A18X+028774Y+028198X0260Y         S2      
017m0797                  -    MD0100PA00X+028774Y+028198                       
327m0797            PU78  -4          A01X+028573Y+027748X0100Y0280R180 S1      
317m0798            VIA   -    M      A01X+028180Y+028172X0200Y         S2      
017m0798            VIA   -    M      A18X+028180Y+028172X0260Y         S2      
017m0798                  -    MD0100PA00X+028180Y+028172                       
327m0798            PU78  -5          A01X+028376Y+027748X0100Y0280R180 S1      
327m0798            PC651 -1          A01X+028054Y+028491X0198Y0197R090 S1      
327m0798            PR6909-1   M      A01X+028454Y+028491X0198Y0197R090 S1      
317m0799            VIA   -    M      A01X+001559Y+024911X0200Y         S2      
017m0799            VIA   -    M      A18X+001559Y+024911X0260Y         S2      
017m0799                  -    MD0100PA00X+001559Y+024911                       
327m0799            Q127  -2          A01X+001846Y+025024X0160Y0240R270 S1      
327m0799            R5842 -2          A01X+001290Y+025237X0198Y0197     S1      
327m0799            PR6907-1   M      A01X+001290Y+024837X0198Y0197R180 S1      
317m0800            VIA   -    M      A01X+032529Y+024457X0200Y         S2      
017m0800            VIA   -    M      A18X+032529Y+024457X0260Y         S2      
017m0800                  -    MD0100PA00X+032529Y+024457                       
327m0800            Q130  -3          A01X+032555Y+024729X0240Y0240R270 S1      
327m0800            R5847 -2          A01X+032778Y+024208X0198Y0197R180 S1      
327m0800            R5849 -1   M      A01X+032395Y+024208X0198Y0197R180 S1      
327m0801            PR6905-1          A01X+008382Y+028491X0198Y0197R090 S1      
317m0801            VIA   -    M      A01X+008301Y+028198X0200Y         S2      
017m0801            VIA   -    M      A18X+008301Y+028198X0260Y         S2      
017m0801                  -    MD0100PA00X+008301Y+028198                       
327m0801            PU76  -4          A01X+008101Y+027748X0100Y0280R180 S1      
317m0802            VIA   -    M      A01X+029026Y+026611X0200Y         S2      
017m0802            VIA   -    M      A18X+029026Y+026611X0260Y         S2      
017m0802                  -    MD0100PA00X+029026Y+026611                       
327m0802            PU78  -10         A01X+028770Y+026960X0100Y0280R180 S1      
327m0802            PC656 -1          A01X+028949Y+026268X0198Y0197R270 S1      
317m0803            VIA   -    M      A01X+008554Y+026611X0200Y         S2      
017m0803            VIA   -    M      A18X+008554Y+026611X0260Y         S2      
017m0803                  -    MD0100PA00X+008554Y+026611                       
327m0803            PU76  -10         A01X+008297Y+026960X0100Y0280R180 S1      
327m0803            PC646 -1          A01X+008477Y+026268X0198Y0197R270 S1      
317m0804            VIA   -    M      A01X+017944Y+028172X0200Y         S2      
017m0804            VIA   -    M      A18X+017944Y+028172X0260Y         S2      
017m0804                  -    MD0100PA00X+017944Y+028172                       
327m0804            PU75  -5          A01X+018140Y+027748X0100Y0280R180 S1      
327m0804            PC644 -1          A01X+017818Y+028491X0198Y0197R090 S1      
327m0804            PR6903-1   M      A01X+018218Y+028491X0198Y0197R090 S1      
317m0805            VIA   -    M      A01X+018790Y+026611X0200Y         S2      
017m0805            VIA   -    M      A18X+018790Y+026611X0260Y         S2      
017m0805                  -    MD0100PA00X+018790Y+026611                       
327m0805            PU75  -10         A01X+018534Y+026960X0100Y0280R180 S1      
327m0805            PC647 -1          A01X+018713Y+026268X0198Y0197R270 S1      
327m0806            PR6906-1          A01X+018618Y+028491X0198Y0197R090 S1      
317m0806            VIA   -    M      A01X+018538Y+028198X0200Y         S2      
017m0806            VIA   -    M      A18X+018538Y+028198X0260Y         S2      
017m0806                  -    MD0100PA00X+018538Y+028198                       
327m0806            PU75  -4          A01X+018337Y+027748X0100Y0280R180 S1      
317m0807            VIA   -    M      A01X+038761Y+026590X0200Y         S2      
017m0807            VIA   -    M      A18X+038761Y+026590X0260Y         S2      
017m0807                  -    MD0100PA00X+038761Y+026590                       
327m0807            PU77  -9          A01X+038809Y+026960X0100Y0280R180 S1      
327m0807            R5845 -2          A01X+038785Y+026268X0198Y0197R090 S1      
317m0808            VIA   -    M      A01X+032267Y+024911X0200Y         S2      
017m0808            VIA   -    M      A18X+032267Y+024911X0260Y         S2      
017m0808                  -    MD0100PA00X+032267Y+024911                       
327m0808            Q130  -2          A01X+032555Y+025024X0160Y0240R270 S1      
327m0808            PR6914-1          A01X+031998Y+025237X0198Y0197R180 S1      
327m0808            R5853 -2   M      A01X+031998Y+024837X0198Y0197     S1      
317m0809            VIA   -    M      A01X+001821Y+024457X0200Y         S2      
017m0809            VIA   -    M      A18X+001821Y+024457X0260Y         S2      
017m0809                  -    MD0100PA00X+001821Y+024457                       
327m0809            Q127  -3          A01X+001846Y+024729X0240Y0240R270 S1      
327m0809            R5836 -2          A01X+002069Y+024208X0198Y0197R180 S1      
327m0809            R5838 -1   M      A01X+001686Y+024208X0198Y0197R180 S1      
317m0810            VIA   -    MD0100PA00X+132950Y+087396X0180Y         S0      
327m0810            U6    -J6         A01X+133108Y+087239X0160Y         S1      
327m0810            R5802 -2          A01X+146232Y+102838X0198Y0197R090 S1      
317m0810            VIA   -    M      A01X+145968Y+102838X0200Y         S2      
017m0810            VIA   -    M      A18X+145968Y+102838X0260Y         S2      
017m0810                  -    MD0100PA00X+145968Y+102838                       
317m0811            VIA   -    M      A01X+011795Y+024911X0200Y         S2      
017m0811            VIA   -    M      A18X+011795Y+024911X0260Y         S2      
017m0811                  -    MD0100PA00X+011795Y+024911                       
327m0811            Q128  -2          A01X+012082Y+025024X0160Y0240R270 S1      
327m0811            PR6908-1          A01X+011526Y+025237X0198Y0197R180 S1      
327m0811            R5843 -2   M      A01X+011526Y+024837X0198Y0197     S1      
317m0812            VIA   -    M      A01X+003658Y+062771X0200Y         S2      
017m0812            VIA   -    M      A18X+003658Y+062771X0260Y         S2      
017m0812                  -    MD0100PA00X+003658Y+062771                       
327m0812            PR6870-1          A01X+003327Y+062931X0198Y0197R180 S1      
327m0812            PU71  -9          A01X+004132Y+062482X0100Y0320R180 S1      
317m0813            VIA   -    M      A01X+007544Y+026570X0200Y         S2      
017m0813            VIA   -    M      A18X+007544Y+026570X0260Y         S2      
017m0813                  -    MD0100PA00X+007544Y+026570                       
327m0813            PU76  -8          A01X+007904Y+026960X0100Y0280R180 S1      
327m0813            PC642 -1          A01X+007677Y+026268X0198Y0197R270 S1      
317m0814            VIA   -    MD0100PA00X+098327Y+085388X0200Y         S0      
327m0814            R5801 -2          A01X+100523Y+102838X0198Y0197R090 S1      
317m0814            VIA   -    M      A01X+101332Y+078593X0200Y         S2      
017m0814            VIA   -    M      A18X+101332Y+078593X0260Y         S2      
017m0814                  -    MD0100PA00X+101332Y+078593                       
317m0814            VIA   -    MD0100PA00X+133265Y+087396X0180Y         S0      
327m0814            U6    -J7         A01X+133423Y+087239X0160Y         S1      
327m0815            PC611 -2          A01X+041167Y+044920X0280Y0320R180 S1      
327m0815            PU72  -12         A01X+041816Y+044798X0100Y0320R090 S1      
317m0815            VIA   -           A01X+041491Y+044893X0200Y    R270 S2      
017m0815            VIA   -           A18X+041491Y+044893X0260Y    R270 S2      
017m0815                  -     D0100PA00X+041491Y+044893                       
327m0815            PR6863-2          A01X+040116Y+044861X0198Y0197R090 S1      
327m0815            PR6867-1          A01X+040617Y+044920X0280Y0320     S1      
317m0816            VIA   -    M      A01X+028016Y+026570X0200Y         S2      
017m0816            VIA   -    M      A18X+028016Y+026570X0260Y         S2      
017m0816                  -    MD0100PA00X+028016Y+026570                       
327m0816            PU78  -8          A01X+028376Y+026960X0100Y0280R180 S1      
327m0816            PC652 -1          A01X+028149Y+026268X0198Y0197R270 S1      
327m0817            PR6888-1          A01X+091657Y+047944X0198Y0197R180 S1      
327m0817            PR6892-1          A01X+091657Y+047544X0198Y0197R180 S1      
327m0817            PU74  -11         A01X+091703Y+046589X0100Y0320R180 S1      
327m0817            PR6898-1          A01X+091657Y+047164X0198Y0197R180 S1      
317m0817            VIA   -           A01X+091659Y+046914X0200Y    R270 S2      
017m0817            VIA   -           A18X+091659Y+046914X0260Y    R270 S2      
017m0817                  -     D0100PA00X+091659Y+046914                       
317m0818            VIA   -    M      A01X+050628Y+062808X0200Y         S2      
017m0818            VIA   -    M      A18X+050628Y+062808X0260Y         S2      
017m0818                  -    MD0100PA00X+050628Y+062808                       
327m0818            PU73  -5          A01X+050628Y+062482X0100Y0320R180 S1      
327m0818            PR6895-1   M      A01X+050742Y+063121X0198Y0197R180 S1      
327m0818            PR6899-1          A01X+050728Y+063624X0198Y0197R090 S1      
317m0819            VIA   -    M      A01X+043808Y+044712X0200Y    R270 S2      
017m0819            VIA   -    M      A18X+043808Y+044712X0260Y    R270 S2      
017m0819                  -    MD0100PA00X+043808Y+044712                       
327m0819            PU72  -6          A01X+042918Y+044207X0100Y0320R090 S1      
327m0819            PC613 -1          A01X+044060Y+044710X0198Y0197     S1      
327m0820            PU73  -11         A01X+049683Y+061734X0100Y0320R270 S1      
327m0820            PR6894-1          A01X+049108Y+061689X0198Y0197R270 S1      
327m0820            PR6886-1          A01X+048328Y+061689X0198Y0197R270 S1      
327m0820            PR6890-1          A01X+048728Y+061689X0198Y0197R270 S1      
317m0820            VIA   -           A01X+049358Y+061690X0200Y         S2      
017m0820            VIA   -           A18X+049358Y+061690X0260Y         S2      
017m0820                  -     D0100PA00X+049358Y+061690                       
317m0821            VIA   -    M      A01X+004718Y+063374X0200Y         S2      
017m0821            VIA   -    M      A18X+004718Y+063374X0260Y         S2      
017m0821                  -    MD0100PA00X+004718Y+063374                       
327m0821            PR6869-2          A01X+004718Y+063121X0198Y0197R180 S1      
327m0821            PC615 -1          A01X+004619Y+063624X0198Y0197R090 S1      
317m0822            VIA   -    M      A01X+049378Y+063372X0200Y         S2      
017m0822            VIA   -    M      A18X+049378Y+063372X0260Y         S2      
017m0822                  -    MD0100PA00X+049378Y+063372                       
327m0822            PU73  -8          A01X+050037Y+062482X0100Y0320R180 S1      
327m0822            PR6901-1          A01X+049378Y+063624X0198Y0197R090 S1      
327m0823            PU71  -12         A01X+004132Y+061380X0100Y0320R180 S1      
327m0823            PC610 -2          A01X+004009Y+060731X0280Y0320R270 S1      
317m0823            VIA   -           A01X+004036Y+061055X0200Y         S2      
017m0823            VIA   -           A18X+004036Y+061055X0260Y         S2      
017m0823                  -     D0100PA00X+004036Y+061055                       
327m0823            PR6861-2          A01X+004052Y+059739X0198Y0197R180 S1      
327m0823            PR6865-1          A01X+004009Y+060181X0280Y0320R090 S1      
317m0824            VIA   -    M      A01X+093341Y+046894X0200Y    R270 S2      
017m0824            VIA   -    M      A18X+093341Y+046894X0260Y    R270 S2      
017m0824                  -    MD0100PA00X+093341Y+046894                       
327m0824            PU74  -8          A01X+092451Y+046235X0100Y0320R090 S1      
327m0824            PR6902-1          A01X+093592Y+046894X0198Y0197     S1      
317m0825            VIA   -    M      A01X+049926Y+063372X0200Y         S2      
017m0825            VIA   -    M      A18X+049926Y+063372X0260Y         S2      
017m0825                  -    MD0100PA00X+049926Y+063372                       
327m0825            PC632 -1          A01X+049928Y+063624X0198Y0197R090 S1      
327m0825            PU73  -6          A01X+050431Y+062482X0100Y0320R180 S1      
327m0826            PU73  -12         A01X+049840Y+061380X0100Y0320R180 S1      
327m0826            PC630 -2          A01X+049718Y+060731X0280Y0320R270 S1      
317m0826            VIA   -           A01X+049745Y+061055X0200Y         S2      
017m0826            VIA   -           A18X+049745Y+061055X0260Y         S2      
017m0826                  -     D0100PA00X+049745Y+061055                       
327m0826            PR6885-2          A01X+049761Y+059739X0198Y0197R180 S1      
327m0826            PR6889-1          A01X+049718Y+060181X0280Y0320R090 S1      
317m0827            VIA   -    M      A01X+050426Y+063374X0200Y         S2      
017m0827            VIA   -    M      A18X+050426Y+063374X0260Y         S2      
017m0827                  -    MD0100PA00X+050426Y+063374                       
327m0827            PC635 -1          A01X+050328Y+063624X0198Y0197R090 S1      
327m0827            PR6895-2          A01X+050426Y+063121X0198Y0197R180 S1      
317m0828            VIA   -    M      A01X+093316Y+045144X0200Y    R270 S2      
017m0828            VIA   -    M      A18X+093316Y+045144X0260Y    R270 S2      
017m0828                  -    MD0100PA00X+093316Y+045144                       
327m0828            PU74  -4          A01X+092451Y+045447X0100Y0320R090 S1      
327m0828            PC636 -1          A01X+093592Y+045144X0198Y0197     S1      
317m0829            VIA   -    M      A01X+003631Y+062228X0200Y         S2      
017m0829            VIA   -    M      A18X+003631Y+062228X0260Y         S2      
017m0829                  -    MD0100PA00X+003631Y+062228                       
327m0829            R5830 -1          A01X+003327Y+062531X0198Y0197R180 S1      
327m0829            R902  -2   M      A01X+003327Y+062131X0198Y0197     S1      
327m0829            PU71  -10         A01X+003974Y+062128X0100Y0320R270 S1      
317m0830            VIA   -    M      A01X+093340Y+046346X0200Y    R270 S2      
017m0830            VIA   -    M      A18X+093340Y+046346X0260Y    R270 S2      
017m0830                  -    MD0100PA00X+093340Y+046346                       
327m0830            PU74  -6          A01X+092451Y+045841X0100Y0320R090 S1      
327m0830            PC633 -1          A01X+093592Y+046344X0198Y0197     S1      
317m0831            VIA   -    MD0100PA00X+130574Y+087753X0200Y         S0      
327m0831            U6    -H1         A01X+131533Y+087554X0160Y         S1      
317m0831            VIA   -    M      A01X+050966Y+082451X0200Y         S2      
017m0831            VIA   -    M      A18X+050966Y+082451X0260Y         S2      
017m0831                  -    MD0100PA00X+050966Y+082451                       
327m0831            R5800 -2          A01X+054814Y+102838X0198Y0197R090 S1      
317m0831            VIA   -    MD0100PA00X+051950Y+102838X0200Y         S0      
317m0832            VIA   -    M      A01X+093342Y+045846X0200Y    R270 S2      
017m0832            VIA   -    M      A18X+093342Y+045846X0260Y    R270 S2      
017m0832                  -    MD0100PA00X+093342Y+045846                       
327m0832            PR6897-2          A01X+093090Y+045846X0198Y0197R090 S1      
327m0832            PC637 -1          A01X+093592Y+045944X0198Y0197     S1      
317m0833            VIA   -    M      A01X+043244Y+044010X0200Y    R270 S2      
017m0833            VIA   -    M      A18X+043244Y+044010X0260Y    R270 S2      
017m0833                  -    MD0100PA00X+043244Y+044010                       
327m0833            PR6876-1          A01X+044060Y+043910X0198Y0197     S1      
327m0833            PU72  -5          A01X+042918Y+044010X0100Y0320R090 S1      
327m0833            PR6872-1   M      A01X+043557Y+043896X0198Y0197R090 S1      
317m0834            VIA   -    M      A01X+004919Y+062808X0200Y         S2      
017m0834            VIA   -    M      A18X+004919Y+062808X0260Y         S2      
017m0834                  -    MD0100PA00X+004919Y+062808                       
327m0834            PR6875-1          A01X+005019Y+063624X0198Y0197R090 S1      
327m0834            PU71  -5          A01X+004919Y+062482X0100Y0320R180 S1      
327m0834            PR6869-1   M      A01X+005033Y+063121X0198Y0197R180 S1      
317m0835            VIA   -    M      A01X+043227Y+043111X0200Y    R270 S2      
017m0835            VIA   -    M      A18X+043227Y+043111X0260Y    R270 S2      
017m0835                  -    MD0100PA00X+043227Y+043111                       
327m0835            PU72  -1          A01X+042909Y+043223X0098Y0335R090 S1      
327m0835            R944  -2   M      A01X+044060Y+043160X0198Y0197R180 S1      
327m0835            R906  -2          A01X+044060Y+042460X0198Y0197R180 S1      
327m0835            C840  -2   M      A01X+044060Y+042810X0198Y0197R180 S1      
327m0836            PR6868-1          A01X+042125Y+045910X0198Y0197R180 S1      
327m0836            PR6864-1          A01X+042125Y+046310X0198Y0197R180 S1      
327m0836            PU72  -11         A01X+042170Y+044955X0100Y0320R180 S1      
327m0836            PR6874-1          A01X+042125Y+045530X0198Y0197R180 S1      
317m0836            VIA   -           A01X+042127Y+045280X0200Y    R270 S2      
017m0836            VIA   -           A18X+042127Y+045280X0260Y    R270 S2      
017m0836                  -     D0100PA00X+042127Y+045280                       
317m0837            VIA   -    M      A01X+043784Y+043510X0200Y    R270 S2      
017m0837            VIA   -    M      A18X+043784Y+043510X0260Y    R270 S2      
017m0837                  -    MD0100PA00X+043784Y+043510                       
327m0837            PU72  -4          A01X+042918Y+043813X0100Y0320R090 S1      
327m0837            PC616 -1          A01X+044060Y+043510X0198Y0197     S1      
317m0838            VIA   -    M      A01X+043809Y+045260X0200Y    R270 S2      
017m0838            VIA   -    M      A18X+043809Y+045260X0260Y    R270 S2      
017m0838                  -    MD0100PA00X+043809Y+045260                       
327m0838            PU72  -8          A01X+042918Y+044601X0100Y0320R090 S1      
327m0838            PR6878-1          A01X+044060Y+045260X0198Y0197     S1      
317m0839            VIA   -    M      A01X+005818Y+062791X0200Y         S2      
017m0839            VIA   -    M      A18X+005818Y+062791X0260Y         S2      
017m0839                  -    MD0100PA00X+005818Y+062791                       
327m0839            R903  -2          A01X+006469Y+063624X0198Y0197R270 S1      
327m0839            C839  -2   M      A01X+006119Y+063624X0198Y0197R270 S1      
327m0839            R905  -2   M      A01X+005769Y+063624X0198Y0197R270 S1      
327m0839            PU71  -1          A01X+005707Y+062472X0098Y0335R180 S1      
327m0840            PC6619-1          A18X+141936Y+108589X0400Y0500     S2      
327m0840            PC6620-1          A18X+141950Y+109309X0400Y0500     S2      
327m0840            PC6621-1          A18X+138495Y+109307X0400Y0500R180 S2      
327m0840            PC6622-1          A01X+141936Y+108589X0400Y0500R180 S1      
327m0840            PL14  -1          A01X+141327Y+107868X0420Y0990R270 S1      
327m0840            PC177 -1          A01X+138542Y+108033X0630Y1380R180 S1      
327m0840            PC192 -1          A18X+142298Y+110990X0400Y0500R270 S2      
327m0840            PC193 -1          A18X+142512Y+111775X0400Y0500R090 S2      
327m0840            PC176 -1          A18X+141712Y+111775X0400Y0500R090 S2      
327m0840            PC174 -1          A18X+139086Y+110990X0400Y0500R270 S2      
327m0840            PC191 -1          A18X+139299Y+111775X0400Y0500R090 S2      
327m0840            PC173 -1          A18X+138499Y+111775X0400Y0500R090 S2      
327m0840            PU15  -30         A01X+142099Y+111023X0090Y0240R180 S1      
317m0840            VIA   -    MD0100PA00X+141967Y+111365X0200Y         S0      
317m0840            VIA   -    MD0100PA00X+142397Y+111365X0200Y         S0      
317m0840            VIA   -    MD0100PA00X+142647Y+111365X0200Y         S0      
317m0840            VIA   -    MD0100PA00X+142112Y+111880X0200Y         S0      
317m0840            VIA   -    MD0100PA00X+142112Y+111610X0200Y         S0      
327m0840            PU15  -25_2M      A01X+142300Y+111661X0810Y0910R090 S1      
317m0840            VIA   -    MD0100PA00X+141888Y+111060X0200Y         S0      
327m0840            PC189 -1          A01X+141505Y+111982X0198Y0197R090 S1      
317m0840            VIA   -    MD0100PA00X+141668Y+110940X0200Y         S0      
317m0840            VIA   -    MD0100PA00X+141458Y+111090X0200Y         S0      
317m0840            VIA   -    MD0100PA00X+141678Y+111240X0200Y         S0      
317m0840            VIA   -    MD0100PA00X+141458Y+111380X0200Y         S0      
327m0840            PU14  -30         A01X+138886Y+111023X0090Y0240R180 S1      
317m0840            VIA   -    MD0100PA00X+139184Y+111365X0200Y         S0      
317m0840            VIA   -    MD0100PA00X+138754Y+111365X0200Y         S0      
317m0840            VIA   -    MD0100PA00X+138899Y+111610X0200Y         S0      
317m0840            VIA   -    MD0100PA00X+138899Y+111880X0200Y         S0      
317m0840            VIA   -    MD0100PA00X+139434Y+111365X0200Y         S0      
327m0840            PU14  -25_2M      A01X+139087Y+111661X0810Y0910R090 S1      
317m0840            VIA   -    MD0100PA00X+138676Y+111060X0200Y         S0      
327m0840            PC172 -1          A01X+138292Y+111982X0198Y0197R090 S1      
317m0840            VIA   -    MD0100PA00X+138456Y+110940X0200Y         S0      
317m0840            VIA   -    MD0100PA00X+138246Y+111380X0200Y         S0      
317m0840            VIA   -    MD0100PA00X+138246Y+111090X0200Y         S0      
317m0840            VIA   -    MD0100PA00X+138466Y+111240X0200Y         S0      
327m0840            PC188 -1          A01X+142100Y+109883X0198Y0197     S1      
317m0840            VIA   -    MD0100PA00X+141878Y+110800X0200Y         S0      
317m0840            VIA   -    MD0100PA00X+141458Y+110800X0200Y         S0      
317m0840            VIA   -    MD0100PA00X+141600Y+109309X0200Y         S0      
327m0840            PC171 -1          A01X+138888Y+109883X0198Y0197     S1      
317m0840            VIA   -    MD0100PA00X+138666Y+110800X0200Y         S0      
317m0840            VIA   -    MD0100PA00X+138845Y+109305X0200Y         S0      
317m0840            VIA   -    MD0100PA00X+138246Y+110800X0200Y         S0      
327m0840            PC175 -1          A01X+141950Y+109309X0400Y0500R180 S1      
317m0840            VIA   -    MD0100PA00X+141600Y+109029X0200Y         S0      
317m0840            VIA   -    MD0100PA00X+140568Y+108430X0200Y         S0      
317m0840            VIA   -    MD0100PA00X+140818Y+108430X0200Y         S0      
317m0840            VIA   -    MD0100PA00X+141068Y+108430X0200Y         S0      
317m0840            VIA   -    MD0100PA00X+141318Y+108430X0200Y         S0      
317m0840            VIA   -    MD0100PA00X+141568Y+108430X0200Y         S0      
317m0840            VIA   -    MD0100PA00X+141568Y+108680X0200Y         S0      
317m0840            VIA   -    MD0100PA00X+141318Y+108680X0200Y         S0      
317m0840            VIA   -    MD0100PA00X+141068Y+108680X0200Y         S0      
317m0840            VIA   -    MD0100PA00X+140818Y+108680X0200Y         S0      
317m0840            VIA   -    MD0100PA00X+140568Y+108680X0200Y         S0      
317m0840            VIA   -    MD0100PA00X+139019Y+108672X0200Y         S0      
317m0840            VIA   -    MD0100PA00X+139019Y+108422X0200Y         S0      
317m0840            VIA   -    MD0100PA00X+139019Y+108172X0200Y         S0      
317m0840            VIA   -    MD0100PA00X+139269Y+108172X0200Y         S0      
317m0840            VIA   -    MD0100PA00X+139269Y+108422X0200Y         S0      
317m0840            VIA   -    MD0100PA00X+139269Y+108672X0200Y         S0      
317m0840            VIA   -    M      A01X+139209Y+109274X0200Y         S2      
017m0840            VIA   -    M      A18X+139209Y+109274X0260Y         S2      
017m0840                  -    MD0100PA00X+139209Y+109274                       
317m0840            VIA   -    MD0100PA00X+139269Y+108922X0200Y         S0      
317m0840            VIA   -    MD0100PA00X+138852Y+109009X0200Y         S0      
327m0840            PC190 -1          A01X+138495Y+109307X0400Y0500     S1      
317m0841            VIA   -    M      A01X+051128Y+063347X0200Y         S2      
017m0841            VIA   -    M      A18X+051128Y+063347X0260Y         S2      
017m0841                  -    MD0100PA00X+051128Y+063347                       
327m0841            PU73  -4          A01X+050825Y+062482X0100Y0320R180 S1      
327m0841            PC634 -1          A01X+051128Y+063624X0198Y0197R090 S1      
317m0842            VIA   -    M      A01X+042665Y+045299X0200Y    R270 S2      
017m0842            VIA   -    M      A18X+042665Y+045299X0260Y    R270 S2      
017m0842                  -    MD0100PA00X+042665Y+045299                       
327m0842            R5831 -1          A01X+042967Y+045603X0198Y0197R090 S1      
327m0842            PU72  -10         A01X+042564Y+044955X0100Y0320R180 S1      
327m0842            R904  -2   M      A01X+042567Y+045603X0198Y0197R270 S1      
317m0843            VIA   -    M      A01X+092740Y+046906X0200Y    R270 S2      
017m0843            VIA   -    M      A18X+092740Y+046906X0260Y    R270 S2      
017m0843                  -    MD0100PA00X+092740Y+046906                       
327m0843            PU74  -9          A01X+092451Y+046432X0100Y0320R090 S1      
327m0843            PR6896-1          A01X+092900Y+047237X0198Y0197R090 S1      
317m0844            VIA   -    M      A01X+051527Y+062791X0200Y         S2      
017m0844            VIA   -    M      A18X+051527Y+062791X0260Y         S2      
017m0844                  -    MD0100PA00X+051527Y+062791                       
327m0844            R946  -2          A01X+052178Y+063624X0198Y0197R270 S1      
327m0844            C841  -2   M      A01X+051828Y+063624X0198Y0197R270 S1      
327m0844            R948  -2   M      A01X+051478Y+063624X0198Y0197R270 S1      
327m0844            PU73  -1          A01X+051415Y+062472X0098Y0335R180 S1      
327m0845            PU74  -12         A01X+091349Y+046432X0100Y0320R090 S1      
327m0845            PR6891-1          A01X+090150Y+046554X0280Y0320     S1      
327m0845            PC631 -2          A01X+090700Y+046554X0280Y0320R180 S1      
317m0845            VIA   -           A01X+091024Y+046527X0200Y    R270 S2      
017m0845            VIA   -           A18X+091024Y+046527X0260Y    R270 S2      
017m0845                  -     D0100PA00X+091024Y+046527                       
327m0845            PR6887-2          A01X+089649Y+046495X0198Y0197R090 S1      
317m0846            VIA   -    M      A01X+092197Y+046933X0200Y    R270 S2      
017m0846            VIA   -    M      A18X+092197Y+046933X0260Y    R270 S2      
017m0846                  -    MD0100PA00X+092197Y+046933                       
327m0846            R5833 -1          A01X+092500Y+047237X0198Y0197R090 S1      
327m0846            R947  -2   M      A01X+092100Y+047237X0198Y0197R270 S1      
327m0846            PU74  -10         A01X+092097Y+046589X0100Y0320R180 S1      
317m0847            VIA   -    M      A01X+004217Y+063372X0200Y         S2      
017m0847            VIA   -    M      A18X+004217Y+063372X0260Y         S2      
017m0847                  -    MD0100PA00X+004217Y+063372                       
327m0847            PC612 -1          A01X+004219Y+063624X0198Y0197R090 S1      
327m0847            PU71  -6          A01X+004722Y+062482X0100Y0320R180 S1      
317m0848            VIA   -    M      A01X+049339Y+062228X0200Y         S2      
017m0848            VIA   -    M      A18X+049339Y+062228X0260Y         S2      
017m0848                  -    MD0100PA00X+049339Y+062228                       
327m0848            R5832 -1          A01X+049035Y+062531X0198Y0197R180 S1      
327m0848            R945  -2   M      A01X+049035Y+062131X0198Y0197     S1      
327m0848            PU73  -10         A01X+049683Y+062128X0100Y0320R270 S1      
317m0849            VIA   -    M      A01X+043810Y+044211X0200Y    R270 S2      
017m0849            VIA   -    M      A18X+043810Y+044211X0260Y    R270 S2      
017m0849                  -    MD0100PA00X+043810Y+044211                       
327m0849            PR6872-2          A01X+043557Y+044211X0198Y0197R090 S1      
327m0849            PC617 -1          A01X+044060Y+044310X0198Y0197     S1      
317m0850            VIA   -    M      A01X+092760Y+044745X0200Y    R270 S2      
017m0850            VIA   -    M      A18X+092760Y+044745X0260Y    R270 S2      
017m0850                  -    MD0100PA00X+092760Y+044745                       
327m0850            R950  -2   M      A01X+093592Y+044794X0198Y0197R180 S1      
327m0850            R949  -2          A01X+093592Y+044094X0198Y0197R180 S1      
327m0850            C842  -2   M      A01X+093592Y+044444X0198Y0197R180 S1      
327m0850            PU74  -1          A01X+092441Y+044857X0098Y0335R090 S1      
317m0851            VIA   -    M      A01X+092777Y+045644X0200Y    R270 S2      
017m0851            VIA   -    M      A18X+092777Y+045644X0260Y    R270 S2      
017m0851                  -    MD0100PA00X+092777Y+045644                       
327m0851            PU74  -5          A01X+092451Y+045644X0100Y0320R090 S1      
327m0851            PR6897-1   M      A01X+093090Y+045530X0198Y0197R090 S1      
327m0851            PR6900-1          A01X+093592Y+045544X0198Y0197     S1      
327m0852            PU71  -11         A01X+003974Y+061734X0100Y0320R270 S1      
327m0852            PR6862-1          A01X+002619Y+061689X0198Y0197R270 S1      
327m0852            PR6866-1          A01X+003019Y+061689X0198Y0197R270 S1      
327m0852            PR6871-1          A01X+003399Y+061689X0198Y0197R270 S1      
317m0852            VIA   -           A01X+003649Y+061690X0200Y         S2      
017m0852            VIA   -           A18X+003649Y+061690X0260Y         S2      
017m0852                  -     D0100PA00X+003649Y+061690                       
317m0853            VIA   -    M      A01X+043208Y+045272X0200Y    R270 S2      
017m0853            VIA   -    M      A18X+043208Y+045272X0260Y    R270 S2      
017m0853                  -    MD0100PA00X+043208Y+045272                       
327m0853            PU72  -9          A01X+042918Y+044798X0100Y0320R090 S1      
327m0853            PR6873-1          A01X+043367Y+045603X0198Y0197R090 S1      
317m0854            VIA   -    M      A01X+003669Y+063372X0200Y         S2      
017m0854            VIA   -    M      A18X+003669Y+063372X0260Y         S2      
017m0854                  -    MD0100PA00X+003669Y+063372                       
327m0854            PU71  -8          A01X+004329Y+062482X0100Y0320R180 S1      
327m0854            PR6877-1          A01X+003669Y+063624X0198Y0197R090 S1      
317m0855            VIA   -    M      A01X+049366Y+062771X0200Y         S2      
017m0855            VIA   -    M      A18X+049366Y+062771X0260Y         S2      
017m0855                  -    MD0100PA00X+049366Y+062771                       
327m0855            PR6893-1          A01X+049035Y+062931X0198Y0197R180 S1      
327m0855            PU73  -9          A01X+049840Y+062482X0100Y0320R180 S1      
317m0856            VIA   -    M      A01X+005419Y+063347X0200Y         S2      
017m0856            VIA   -    M      A18X+005419Y+063347X0260Y         S2      
017m0856                  -    MD0100PA00X+005419Y+063347                       
327m0856            PU71  -4          A01X+005116Y+062482X0100Y0320R180 S1      
327m0856            PC614 -1          A01X+005419Y+063624X0198Y0197R090 S1      
317m0857            VIA   -    M      A01X+031759Y+012488X0200Y         S2      
017m0857            VIA   -    M      A18X+031759Y+012488X0260Y         S2      
017m0857                  -    MD0100PA00X+031759Y+012488                       
327m0857            PU84  -9          A01X+031804Y+012156X0100Y0280     S1      
327m0857            R5879 -2          A01X+031822Y+012764X0198Y0197R270 S1      
317m0858            VIA   -    M      A01X+028476Y+014828X0200Y         S2      
017m0858            VIA   -    M      A18X+028476Y+014828X0260Y         S2      
017m0858                  -    MD0100PA00X+028476Y+014828                       
327m0858            Q136  -2          A01X+028764Y+014941X0160Y0240R270 S1      
327m0858            R5889 -1          A01X+028207Y+015154X0198Y0197R180 S1      
327m0858            R5887 -2   M      A01X+028207Y+014754X0198Y0197     S1      
317m0859            VIA   -    M      A01X+032303Y+011078X0200Y         S2      
017m0859            VIA   -    M      A18X+032303Y+011078X0260Y         S2      
017m0859                  -    MD0100PA00X+032303Y+011078                       
327m0859            PU84  -5          A01X+032001Y+011368X0100Y0280     S1      
327m0859            PR6925-1          A01X+032031Y+010790X0198Y0197R270 S1      
327m0859            PC686 -1   M      A01X+032431Y+010790X0198Y0197R270 S1      
317m0860            VIA   -    M      A01X+021523Y+012488X0200Y         S2      
017m0860            VIA   -    M      A18X+021523Y+012488X0260Y         S2      
017m0860                  -    MD0100PA00X+021523Y+012488                       
327m0860            PU83  -9          A01X+021568Y+012156X0100Y0280     S1      
327m0860            R5878 -2          A01X+021597Y+012775X0198Y0197R270 S1      
317m0861            VIA   -    M      A01X+002234Y+016672X0200Y         S2      
017m0861            VIA   -    M      A18X+002234Y+016672X0260Y         S2      
017m0861                  -    MD0100PA00X+002234Y+016672                       
327m0861            PU81  -8          A01X+001889Y+016404X0100Y0280     S1      
327m0861            PC670 -1          A01X+002071Y+017023X0198Y0197R090 S1      
317m0862            VIA   -    M      A01X+031252Y+012428X0200Y         S2      
017m0862            VIA   -    M      A18X+031252Y+012428X0260Y         S2      
017m0862                  -    MD0100PA00X+031252Y+012428                       
327m0862            PU84  -10         A01X+031607Y+012156X0100Y0280     S1      
327m0862            PC687 -1          A01X+031233Y+012775X0198Y0197R090 S1      
317m0863            VIA   -    M      A01X+040580Y+047556X0200Y    R090 S2      
017m0863            VIA   -    M      A18X+040580Y+047556X0260Y    R090 S2      
017m0863                  -    MD0100PA00X+040580Y+047556                       
327m0863            Q213  -2          A01X+040876Y+047156X0160Y0240R270 S1      
327m0863            R5865 -1          A01X+040288Y+047956X0198Y0197R180 S1      
327m0863            R5863 -2   M      A01X+040288Y+047556X0198Y0197     S1      
317m0864            VIA   -    M      A01X+021567Y+011078X0200Y         S2      
017m0864            VIA   -    M      A18X+021567Y+011078X0260Y         S2      
017m0864                  -    MD0100PA00X+021567Y+011078                       
327m0864            PR6924-1          A01X+021394Y+010790X0198Y0197R270 S1      
327m0864            PU83  -4          A01X+021568Y+011368X0100Y0280     S1      
317m0865            VIA   -    M      A01X+021016Y+012428X0200Y         S2      
017m0865            VIA   -    M      A18X+021016Y+012428X0260Y         S2      
017m0865                  -    MD0100PA00X+021016Y+012428                       
327m0865            PU83  -10         A01X+021371Y+012156X0100Y0280     S1      
327m0865            PC685 -1          A01X+021197Y+012775X0198Y0197R090 S1      
327m0866            PU79  -8          A01X+035679Y+045801X0100Y0280R090 S1      
317m0866            VIA   -    M      A01X+035337Y+045933X0200Y    R090 S2      
017m0866            VIA   -    M      A18X+035337Y+045933X0260Y    R090 S2      
017m0866                  -    MD0100PA00X+035337Y+045933                       
327m0866            PC662 -1          A01X+035060Y+045833X0198Y0197R180 S1      
327m0867            PU82  -10         A01X+011135Y+012156X0100Y0280     S1      
317m0867            VIA   -    M      A01X+010780Y+012428X0200Y         S2      
017m0867            VIA   -    M      A18X+010780Y+012428X0260Y         S2      
017m0867                  -    MD0100PA00X+010780Y+012428                       
327m0867            PC677 -1          A01X+010761Y+012775X0198Y0197R090 S1      
327m0868            PR6916-1          A01X+005776Y+044307X0198Y0197R270 S1      
327m0868            PU80  -4          A01X+006315Y+045156X0100Y0280     S1      
317m0868            VIA   -    M      A01X+005786Y+044607X0200Y         S2      
017m0868            VIA   -    M      A18X+005786Y+044607X0260Y         S2      
017m0868                  -    MD0100PA00X+005786Y+044607                       
317m0869            VIA   -    M      A01X+002191Y+015326X0200Y         S2      
017m0869            VIA   -    M      A18X+002191Y+015326X0260Y         S2      
017m0869                  -    MD0100PA00X+002191Y+015326                       
327m0869            PU81  -5          A01X+001889Y+015616X0100Y0280     S1      
327m0869            PR6919-1          A01X+001918Y+015038X0198Y0197R270 S1      
327m0869            PC674 -1   M      A01X+002318Y+015038X0198Y0197R270 S1      
317SMB_LM75_2_SDA   VIA   -    M      A01X+028963Y+002828X0200Y    R090 S2      
017SMB_LM75_2_SDA   VIA   -    M      A18X+028963Y+002828X0260Y    R090 S2      
017SMB_LM75_2_SDA         -    MD0100PA00X+028963Y+002828                       
327SMB_LM75_2_SDA   U416  -1          A01X+029496Y+002941X0240Y0520R270 S1      
327SMB_LM75_2_SDA   R5808 -2          A01X+028694Y+002716X0198Y0197     S1      
327m0870            PU80  -5          A01X+006512Y+045156X0100Y0280     S1      
317m0870            VIA   -    M      A01X+006574Y+044560X0200Y         S2      
017m0870            VIA   -    M      A18X+006574Y+044560X0260Y         S2      
017m0870                  -    MD0100PA00X+006574Y+044560                       
327m0870            PR6915-1          A01X+006176Y+044307X0198Y0197R270 S1      
327m0870            PC664 -1   M      A01X+006576Y+044307X0198Y0197R270 S1      
317m0871            VIA   -    M      A01X+001559Y+026911X0200Y         S2      
017m0871            VIA   -    M      A18X+001559Y+026911X0260Y         S2      
017m0871                  -    MD0100PA00X+001559Y+026911                       
327m0871            R5874 -2          A01X+001290Y+027237X0198Y0197     S1      
327m0871            Q133  -2          A01X+001846Y+027024X0160Y0240R270 S1      
327m0871            R5876 -1   M      A01X+001290Y+026837X0198Y0197R180 S1      
327m0872            PU79  -5          A01X+036466Y+045801X0100Y0280R090 S1      
317m0872            VIA   -    M      A01X+036756Y+046103X0200Y    R090 S2      
017m0872            VIA   -    M      A18X+036756Y+046103X0260Y    R090 S2      
017m0872                  -    MD0100PA00X+036756Y+046103                       
327m0872            PR6917-1          A01X+037045Y+045831X0198Y0197     S1      
327m0872            PC666 -1   M      A01X+037045Y+046231X0198Y0197     S1      
317m0873            VIA   -    M      A01X+019717Y+015237X0200Y         S2      
017m0873            VIA   -    M      A18X+019717Y+015237X0260Y         S2      
017m0873                  -    MD0100PA00X+019717Y+015237                       
327m0873            Q135  -5          A01X+019237Y+014941X0160Y0240R270 S1      
327m0873            Q135  -6          A01X+019237Y+015237X0240Y0240R270 S1      
327m0873            R5884 -2   M      A01X+019717Y+014977X0198Y0197R180 S1      
317LM75_2_A2        VIA   -    M      A01X+032184Y+001441X0200Y    R090 S2      
017LM75_2_A2        VIA   -    M      A18X+032184Y+001441X0260Y    R090 S2      
017LM75_2_A2              -    MD0100PA00X+032184Y+001441                       
327LM75_2_A2        U416  -5          A01X+031582Y+001441X0240Y0520R270 S1      
327LM75_2_A2        R5813 -1          A01X+032533Y+001181X0198Y0197     S1      
327LM75_2_A2        R5807 -1   M      A01X+032533Y+001581X0198Y0197     S1      
317m0874            VIA   -    M      A01X+041880Y+047451X0200Y    R090 S2      
017m0874            VIA   -    M      A18X+041880Y+047451X0260Y    R090 S2      
017m0874                  -    MD0100PA00X+041880Y+047451                       
327m0874            Q213  -5          A01X+041584Y+047156X0160Y0240R270 S1      
327m0874            Q213  -6          A01X+041584Y+047451X0240Y0240R270 S1      
327m0874            R5861 -2   M      A01X+042173Y+047456X0198Y0197R180 S1      
317m0875            VIA   -    M      A01X+018240Y+014828X0200Y         S2      
017m0875            VIA   -    M      A18X+018240Y+014828X0260Y         S2      
017m0875                  -    MD0100PA00X+018240Y+014828                       
327m0875            Q135  -2          A01X+018528Y+014941X0160Y0240R270 S1      
327m0875            R5888 -1          A01X+017971Y+015154X0198Y0197R180 S1      
327m0875            R5886 -2   M      A01X+017971Y+014754X0198Y0197     S1      
317SMB_LM75_3_SCL   VIA   -    M      A01X+145783Y+002642X0200Y    R090 S2      
017SMB_LM75_3_SCL   VIA   -    M      A18X+145783Y+002642X0260Y    R090 S2      
017SMB_LM75_3_SCL         -    MD0100PA00X+145783Y+002642                       
327SMB_LM75_3_SCL   U417  -2          A01X+146268Y+002764X0240Y0520R270 S1      
327SMB_LM75_3_SCL   R5819 -2          A01X+145466Y+002639X0198Y0197     S1      
327m0876            PU79  -10         A01X+035679Y+045408X0100Y0280R090 S1      
317m0876            VIA   -    M      A01X+035366Y+044904X0200Y    R090 S2      
017m0876            VIA   -    M      A18X+035366Y+044904X0260Y    R090 S2      
017m0876                  -    MD0100PA00X+035366Y+044904                       
327m0876            PC667 -1          A01X+035060Y+045033X0198Y0197R180 S1      
327m0877            PU82  -4          A01X+011332Y+011368X0100Y0280     S1      
317m0877            VIA   -    M      A01X+011331Y+011078X0200Y         S2      
017m0877            VIA   -    M      A18X+011331Y+011078X0260Y         S2      
017m0877                  -    MD0100PA00X+011331Y+011078                       
327m0877            PR6922-1          A01X+011158Y+010790X0198Y0197R270 S1      
317LM75_3_A2        VIA   -    M      A01X+148956Y+001764X0200Y    R090 S2      
017LM75_3_A2        VIA   -    M      A18X+148956Y+001764X0260Y    R090 S2      
017LM75_3_A2              -    MD0100PA00X+148956Y+001764                       
327LM75_3_A2        R5823 -1          A01X+149305Y+001504X0198Y0197     S1      
327LM75_3_A2        R5817 -1   M      A01X+149305Y+001904X0198Y0197     S1      
327LM75_3_A2        U417  -5          A01X+148354Y+001764X0240Y0520R270 S1      
327m0878            PU80  -9          A01X+006315Y+045943X0100Y0280     S1      
327m0878            R5855 -2          A01X+006222Y+046748X0198Y0197R270 S1      
317m0878            VIA   -    M      A01X+006315Y+046237X0200Y         S2      
017m0878            VIA   -    M      A18X+006315Y+046237X0260Y         S2      
017m0878                  -    MD0100PA00X+006315Y+046237                       
317m0879            VIA   -    M      A01X+032261Y+012466X0200Y         S2      
017m0879            VIA   -    M      A18X+032261Y+012466X0260Y         S2      
017m0879                  -    MD0100PA00X+032261Y+012466                       
327m0879            PU84  -8          A01X+032001Y+012156X0100Y0280     S1      
327m0879            PC682 -1          A01X+032233Y+012775X0198Y0197R090 S1      
317LM75_3_A1        VIA   -    M      A01X+149056Y+002304X0200Y    R090 S2      
017LM75_3_A1        VIA   -    M      A18X+149056Y+002304X0260Y    R090 S2      
017LM75_3_A1              -    MD0100PA00X+149056Y+002304                       
327LM75_3_A1        R5822 -1          A01X+149305Y+002704X0198Y0197     S1      
327LM75_3_A1        U417  -6          A01X+148354Y+002264X0240Y0520R270 S1      
327LM75_3_A1        R5816 -1   M      A01X+149305Y+002304X0198Y0197     S1      
327m0880            R5864 -1          A01X+005364Y+046734X0198Y0197R090 S1      
327m0880            R5862 -2   M      A01X+004964Y+046734X0198Y0197R270 S1      
327m0880            Q212  -2          A01X+004564Y+046146X0160Y0240R180 S1      
317m0880            VIA   -    M      A01X+004964Y+046442X0200Y         S2      
017m0880            VIA   -    M      A18X+004964Y+046442X0260Y         S2      
017m0880                  -    MD0100PA00X+004964Y+046442                       
327m0881            PU82  -9          A01X+011332Y+012156X0100Y0280     S1      
317m0881            VIA   -    M      A01X+011286Y+012488X0200Y         S2      
017m0881            VIA   -    M      A18X+011286Y+012488X0260Y         S2      
017m0881                  -    MD0100PA00X+011286Y+012488                       
327m0881            R5867 -2          A01X+011361Y+012775X0198Y0197R270 S1      
327m0882            PU80  -10         A01X+006119Y+045943X0100Y0280     S1      
327m0882            PC665 -1          A01X+005822Y+046748X0198Y0197R090 S1      
317m0882            VIA   -    M      A01X+005822Y+046500X0200Y         S2      
017m0882            VIA   -    M      A18X+005822Y+046500X0260Y         S2      
017m0882                  -    MD0100PA00X+005822Y+046500                       
317m0883            VIA   -    M      A01X+031803Y+011078X0200Y         S2      
017m0883            VIA   -    M      A18X+031803Y+011078X0260Y         S2      
017m0883                  -    MD0100PA00X+031803Y+011078                       
327m0883            PU84  -4          A01X+031804Y+011368X0100Y0280     S1      
327m0883            PR6926-1          A01X+031631Y+010790X0198Y0197R270 S1      
317LM75_2_A1        VIA   -    M      A01X+032285Y+001981X0200Y    R090 S2      
017LM75_2_A1        VIA   -    M      A18X+032285Y+001981X0260Y    R090 S2      
017LM75_2_A1              -    MD0100PA00X+032285Y+001981                       
327LM75_2_A1        R5812 -1          A01X+032533Y+002381X0198Y0197     S1      
327LM75_2_A1        R5806 -1   M      A01X+032533Y+001981X0198Y0197     S1      
327LM75_2_A1        U416  -6          A01X+031582Y+001941X0240Y0520R270 S1      
327m0884            PU79  -4          A01X+036466Y+045604X0100Y0280R090 S1      
317m0884            VIA   -    M      A01X+036756Y+045603X0200Y    R090 S2      
017m0884            VIA   -    M      A18X+036756Y+045603X0260Y    R090 S2      
017m0884                  -    MD0100PA00X+036756Y+045603                       
327m0884            PR6918-1          A01X+037045Y+045431X0198Y0197     S1      
327m0885            PU82  -8          A01X+011528Y+012156X0100Y0280     S1      
317m0885            VIA   -    M      A01X+011789Y+012466X0200Y         S2      
017m0885            VIA   -    M      A18X+011789Y+012466X0260Y         S2      
017m0885                  -    MD0100PA00X+011789Y+012466                       
327m0885            PC672 -1          A01X+011761Y+012775X0198Y0197R090 S1      
327SMB_LM75_2_SCL   R5809 -2          A01X+145438Y+003919X0198Y0197     S1      
317SMB_LM75_2_SCL   VIA   -    MD0100PA00X+028467Y+003407X0200Y         S0      
317SMB_LM75_2_SCL   VIA   -    MD0100PA00X+145501Y+004313X0200Y         S0      
317SMB_LM75_2_SCL   VIA   -    M      A01X+029011Y+002319X0200Y    R090 S2      
017SMB_LM75_2_SCL   VIA   -    M      A18X+029011Y+002319X0260Y    R090 S2      
017SMB_LM75_2_SCL         -    MD0100PA00X+029011Y+002319                       
327SMB_LM75_2_SCL   U416  -2          A01X+029496Y+002441X0240Y0520R270 S1      
327m0886            PU79  -9          A01X+035679Y+045604X0100Y0280R090 S1      
317m0886            VIA   -    M      A01X+035332Y+045421X0200Y    R090 S2      
017m0886            VIA   -    M      A18X+035332Y+045421X0260Y    R090 S2      
017m0886                  -    MD0100PA00X+035332Y+045421                       
327m0886            R5854 -2          A01X+035060Y+045433X0198Y0197     S1      
327m0887            PU82  -5          A01X+011528Y+011368X0100Y0280     S1      
317m0887            VIA   -    M      A01X+011831Y+011078X0200Y         S2      
017m0887            VIA   -    M      A18X+011831Y+011078X0260Y         S2      
017m0887                  -    MD0100PA00X+011831Y+011078                       
327m0887            PR6921-1          A01X+011558Y+010790X0198Y0197R270 S1      
327m0887            PC676 -1   M      A01X+011958Y+010790X0198Y0197R270 S1      
317LM75_2_A0        VIA   -    M      A01X+032211Y+002619X0200Y    R090 S2      
017LM75_2_A0        VIA   -    M      A18X+032211Y+002619X0260Y    R090 S2      
017LM75_2_A0              -    MD0100PA00X+032211Y+002619                       
327LM75_2_A0        R5811 -1          A01X+032533Y+003181X0198Y0197     S1      
327LM75_2_A0        U416  -7          A01X+031582Y+002441X0240Y0520R270 S1      
327LM75_2_A0        R5805 -1   M      A01X+032533Y+002781X0198Y0197     S1      
317m0888            VIA   -    M      A01X+001731Y+016694X0200Y         S2      
017m0888            VIA   -    M      A18X+001731Y+016694X0260Y         S2      
017m0888                  -    MD0100PA00X+001731Y+016694                       
327m0888            R5866 -2          A01X+001671Y+017023X0198Y0197R270 S1      
327m0888            PU81  -9          A01X+001692Y+016404X0100Y0280     S1      
317SMB_LM75_3_SDA   VIA   -    M      A01X+145735Y+003152X0200Y    R090 S2      
017SMB_LM75_3_SDA   VIA   -    M      A18X+145735Y+003152X0260Y    R090 S2      
017SMB_LM75_3_SDA         -    MD0100PA00X+145735Y+003152                       
327SMB_LM75_3_SDA   U417  -1          A01X+146268Y+003264X0240Y0520R270 S1      
327SMB_LM75_3_SDA   R5818 -2          A01X+145466Y+003039X0198Y0197     S1      
327m0889            PC660 -1          A01X+006622Y+046748X0198Y0197R090 S1      
327m0889            PU80  -8          A01X+006512Y+045943X0100Y0280     S1      
317m0889            VIA   -    M      A01X+006767Y+046482X0200Y         S2      
017m0889            VIA   -    M      A18X+006767Y+046482X0260Y         S2      
017m0889                  -    MD0100PA00X+006767Y+046482                       
317m0890            VIA   -    M      A01X+001821Y+026457X0200Y         S2      
017m0890            VIA   -    M      A18X+001821Y+026457X0260Y         S2      
017m0890                  -    MD0100PA00X+001821Y+026457                       
327m0890            Q133  -3          A01X+001846Y+026729X0240Y0240R270 S1      
327m0890            R5868 -2          A01X+002069Y+026208X0198Y0197R180 S1      
327m0890            R5870 -1   M      A01X+001686Y+026208X0198Y0197R180 S1      
317LM75_3_A0        VIA   -    M      A01X+148983Y+002942X0200Y    R090 S2      
017LM75_3_A0        VIA   -    M      A18X+148983Y+002942X0260Y    R090 S2      
017LM75_3_A0              -    MD0100PA00X+148983Y+002942                       
327LM75_3_A0        R5821 -1          A01X+149305Y+003504X0198Y0197     S1      
327LM75_3_A0        R5815 -1   M      A01X+149305Y+003104X0198Y0197     S1      
327LM75_3_A0        U417  -7          A01X+148354Y+002764X0240Y0520R270 S1      
327m0891            Q212  -5          A01X+004564Y+045438X0160Y0240R180 S1      
327m0891            R5860 -2   M      A01X+004864Y+044849X0198Y0197R090 S1      
327m0891            Q212  -6          A01X+004860Y+045438X0240Y0240R180 S1      
317m0891            VIA   -    M      A01X+004860Y+045142X0200Y         S2      
017m0891            VIA   -    M      A18X+004860Y+045142X0260Y         S2      
017m0891                  -    MD0100PA00X+004860Y+045142                       
317m0892            VIA   -    M      A01X+018502Y+014374X0200Y         S2      
017m0892            VIA   -    M      A18X+018502Y+014374X0260Y         S2      
017m0892                  -    MD0100PA00X+018502Y+014374                       
327m0892            Q135  -3          A01X+018528Y+014646X0240Y0240R270 S1      
327m0892            R5882 -1          A01X+018751Y+014125X0198Y0197     S1      
327m0892            R5880 -2   M      A01X+018368Y+014125X0198Y0197     S1      
317m0893            VIA   -    M      A01X+001225Y+016634X0200Y         S2      
017m0893            VIA   -    M      A18X+001225Y+016634X0260Y         S2      
017m0893                  -    MD0100PA00X+001225Y+016634                       
327m0893            PC675 -1          A01X+001271Y+017023X0198Y0197R090 S1      
327m0893            PU81  -10         A01X+001495Y+016404X0100Y0280     S1      
317m0894            VIA   -    M      A01X+001691Y+015326X0200Y         S2      
017m0894            VIA   -    M      A18X+001691Y+015326X0260Y         S2      
017m0894                  -    MD0100PA00X+001691Y+015326                       
327m0894            PU81  -4          A01X+001692Y+015616X0100Y0280     S1      
327m0894            PR6920-1          A01X+001518Y+015038X0198Y0197R270 S1      
317m0895            VIA   -    M      A01X+009481Y+015237X0200Y         S2      
017m0895            VIA   -    M      A18X+009481Y+015237X0260Y         S2      
017m0895                  -    MD0100PA00X+009481Y+015237                       
327m0895            Q134  -6          A01X+009000Y+015237X0240Y0240R270 S1      
327m0895            Q134  -5          A01X+009000Y+014941X0160Y0240R270 S1      
327m0895            R5873 -2   M      A01X+009481Y+014977X0198Y0197R180 S1      
317m0896            VIA   -    M      A01X+022025Y+012466X0200Y         S2      
017m0896            VIA   -    M      A18X+022025Y+012466X0260Y         S2      
017m0896                  -    MD0100PA00X+022025Y+012466                       
327m0896            PU83  -8          A01X+021765Y+012156X0100Y0280     S1      
327m0896            PC680 -1          A01X+021997Y+012775X0198Y0197R090 S1      
317m0897            VIA   -    M      A01X+022067Y+011078X0200Y         S2      
017m0897            VIA   -    M      A18X+022067Y+011078X0260Y         S2      
017m0897                  -    MD0100PA00X+022067Y+011078                       
327m0897            PU83  -5          A01X+021765Y+011368X0100Y0280     S1      
327m0897            PR6923-1          A01X+021794Y+010790X0198Y0197R270 S1      
327m0897            PC684 -1   M      A01X+022194Y+010790X0198Y0197R270 S1      
317m0898            VIA   -    M      A01X+008004Y+014828X0200Y         S2      
017m0898            VIA   -    M      A18X+008004Y+014828X0260Y         S2      
017m0898                  -    MD0100PA00X+008004Y+014828                       
327m0898            Q134  -2          A01X+008292Y+014941X0160Y0240R270 S1      
327m0898            R5877 -1          A01X+007735Y+015154X0198Y0197R180 S1      
327m0898            R5875 -2   M      A01X+007735Y+014754X0198Y0197     S1      
317m0899            VIA   -    M      A01X+029954Y+015237X0200Y         S2      
017m0899            VIA   -    M      A18X+029954Y+015237X0260Y         S2      
017m0899                  -    MD0100PA00X+029954Y+015237                       
327m0899            Q136  -6          A01X+029473Y+015237X0240Y0240R270 S1      
327m0899            Q136  -5          A01X+029473Y+014941X0160Y0240R270 S1      
327m0899            R5885 -2   M      A01X+029954Y+014977X0198Y0197R180 S1      
317m0900            VIA   -    M      A01X+002555Y+027639X0200Y         S2      
017m0900            VIA   -    M      A18X+002555Y+027639X0260Y         S2      
017m0900                  -    MD0100PA00X+002555Y+027639                       
327m0900            Q133  -6          A01X+002555Y+027320X0240Y0240R270 S1      
327m0900            R5872 -2   M      A01X+003036Y+027060X0198Y0197R180 S1      
327m0900            Q133  -5          A01X+002555Y+027024X0160Y0240R270 S1      
317m0901            VIA   -    M      A01X+028738Y+014374X0200Y         S2      
017m0901            VIA   -    M      A18X+028738Y+014374X0260Y         S2      
017m0901                  -    MD0100PA00X+028738Y+014374                       
327m0901            Q136  -3          A01X+028764Y+014646X0240Y0240R270 S1      
327m0901            R5883 -1          A01X+028987Y+014125X0198Y0197     S1      
327m0901            R5881 -2   M      A01X+028604Y+014125X0198Y0197     S1      
317m0902            VIA   -    M      A01X+008266Y+014374X0200Y         S2      
017m0902            VIA   -    M      A18X+008266Y+014374X0260Y         S2      
017m0902                  -    MD0100PA00X+008266Y+014374                       
327m0902            Q134  -3          A01X+008292Y+014646X0240Y0240R270 S1      
327m0902            R5871 -1          A01X+008515Y+014125X0198Y0197     S1      
327m0902            R5869 -2   M      A01X+008132Y+014125X0198Y0197     S1      
327m0903            VIA   -    M      A18X+101390Y+090495X0260Y         S2      
327m0903            U67   -4          A18X+099055Y+090483X0140Y0610R180 S2      
327m0903            R3481 -1          A18X+101390Y+090027X0198Y0197R090 S2      
327m0904            VIA   -    M      A18X+100218Y+087530X0260Y         S2      
327m0904            U67   -9          A18X+100055Y+088323X0140Y0610R180 S2      
327m0904            R3483 -1          A18X+100078Y+087040X0198Y0197     S2      
327m0905            VIA   -    M      A18X+097313Y+088016X0260Y         S2      
327m0905            R3484 -1          A18X+097313Y+087418X0198Y0197R090 S2      
327m0905            U67   -7          A18X+099805Y+090483X0140Y0610R180 S2      
327HSC_D_OC_R       R6801 -2   M      A01X+103897Y+136501X0198Y0197     S1      
327HSC_D_OC_R       U436  -6          A01X+102757Y+134446X0250Y0480R270 S1      
327HSC_D_OC_R       R6656 -2   M      A01X+103896Y+136129X0198Y0197     S1      
327HSC_D_OC_R       R6652 -2   M      A01X+103902Y+135737X0198Y0197     S1      
327HSC_D_OC_R       R6655 -2   M      A01X+103900Y+136849X0198Y0197R270 S1      
317HSC_D_OC_R       VIA   -    M      A01X+101939Y+137706X0200Y         S2      
017HSC_D_OC_R       VIA   -    M      A18X+101939Y+137706X0260Y         S2      
017HSC_D_OC_R             -    MD0100PA00X+101939Y+137706                       
327HSC_D_OC_R       R493  -2          A01X+081020Y+140477X0198Y0197     S1      
327HSC_D_OC_R       U415  -2          A01X+081006Y+139751X0220Y0530R180 S1      
317HSC_D_OC_R       VIA   -    M      A01X+081020Y+140166X0200Y    R270 S2      
017HSC_D_OC_R       VIA   -    M      A18X+081020Y+140166X0260Y    R270 S2      
017HSC_D_OC_R             -    MD0100PA00X+081020Y+140166                       
317TP_JTAG_PIN4     JP2   -4    D0410PA00X+103064Y+079455X0610Y         S3      
317HSC_UV_N         VIA   -    M      A01X+073227Y+161826X0200Y    R090 S2      
017HSC_UV_N         VIA   -    M      A18X+073227Y+161826X0260Y    R090 S2      
017HSC_UV_N               -    MD0100PA00X+073227Y+161826                       
327HSC_UV_N         Q125  -D          A01X+073306Y+161445X0240Y0320R090 S1      
327HSC_UV_N         R4420 -1          A01X+073616Y+162202X0198Y0197     S1      
327HSC_UV_N         R498  -1   M      A01X+073217Y+162202X0198Y0197R090 S1      
327m0906            R5799 -1          A01X+080615Y+137761X0198Y0197R090 S1      
327m0906            VIA   -    M      A01X+102991Y+085384X0300Y         S1      
317m0906            VIA   -    MD0100PA00X+099046Y+085204X0200Y         S0      
317m0906            VIA   -    MD0100PA00X+126963Y+084812X0200Y         S0      
327m0906            R6645 -2          A01X+127360Y+084814X0198Y0197R180 S1      
327m0906            R6646 -2          A01X+102991Y+084722X0198Y0197R180 S1      
327m0906            R6647 -2          A18X+099378Y+139420X0198Y0197R180 S2      
317m0906            VIA   -    M      A01X+080615Y+137521X0200Y    R270 S2      
017m0906            VIA   -    M      A18X+080615Y+137521X0260Y    R270 S2      
017m0906                  -    MD0100PA00X+080615Y+137521                       
327HSC_D_OC_BUF_N   R496  -2          A01X+081015Y+138076X0198Y0197R090 S1      
327HSC_D_OC_BUF_N   R5799 -2   M      A01X+080615Y+138076X0198Y0197R090 S1      
317HSC_D_OC_BUF_N   VIA   -    M      A01X+080615Y+138372X0200Y    R270 S2      
017HSC_D_OC_BUF_N   VIA   -    M      A18X+080615Y+138372X0260Y    R270 S2      
017HSC_D_OC_BUF_N         -    MD0100PA00X+080615Y+138372                       
327HSC_D_OC_BUF_N   U415  -4          A01X+080632Y+138786X0220Y0530R180 S1      
317m0907            VIA   -    M      A01X+067868Y+013884X0200Y         S2      
017m0907            VIA   -    M      A18X+067868Y+013884X0260Y         S2      
017m0907                  -    MD0100PA00X+067868Y+013884                       
327m0907            U389  -4          A01X+067518Y+013674X0240Y0240     S1      
327m0907            R5678 -2          A01X+068111Y+013090X0198Y0197R090 S1      
327m0907            R5675 -1   M      A01X+068108Y+013484X0198Y0197     S1      
327m0907            R5679 -1   M      A01X+068108Y+013884X0198Y0197     S1      
317m0908            VIA   -    M      A01X+079544Y+035695X0200Y         S2      
017m0908            VIA   -    M      A18X+079544Y+035695X0260Y         S2      
017m0908                  -    MD0100PA00X+079544Y+035695                       
327m0908            R5771 -1          A01X+081190Y+035037X0198Y0197     S1      
317m0908            VIA   -    MD0100PA00X+082367Y+071054X0200Y         S0      
317m0908            VIA   -    MD0100PA00X+088452Y+084214X0180Y         S0      
317m0908            VIA   -    MD0100PA00X+090284Y+070366X0200Y         S0      
327m0908            U5    -C14        A01X+088609Y+084372X0160Y    R180 S1      
317RST_SMB_SSD6_N   VIA   -    M      A01X+065516Y+014352X0200Y         S2      
017RST_SMB_SSD6_N   VIA   -    M      A18X+065516Y+014352X0260Y         S2      
017RST_SMB_SSD6_N         -    MD0100PA00X+065516Y+014352                       
327RST_SMB_SSD6_N   U389  -2          A01X+066809Y+013970X0160Y0240R090 S1      
327RST_SMB_SSD6_N   R5677 -2          A01X+065741Y+014577X0198Y0197     S1      
327m0909            J35   -A9         A01X+060144Y+009287X0150Y0500R090 S1      
317m0909            VIA   -    MD0100PA00X+059029Y+009511X0200Y         S0      
317m0909            VIA   -    M      A01X+057995Y+012511X0200Y         S2      
017m0909            VIA   -    M      A18X+057995Y+012511X0260Y         S2      
017m0909                  -    MD0100PA00X+057995Y+012511                       
327m0909            R5666 -1          A01X+057875Y+012775X0198Y0197R090 S1      
327m0910            J42   -A9         A01X+141325Y+009287X0150Y0500R090 S1      
317m0910            VIA   -    MD0100PA00X+140210Y+009511X0200Y         S0      
317m0910            VIA   -    M      A01X+139176Y+012511X0200Y         S2      
017m0910            VIA   -    M      A18X+139176Y+012511X0260Y         S2      
017m0910                  -    MD0100PA00X+139176Y+012511                       
327m0910            R5702 -1          A01X+139056Y+012775X0198Y0197R090 S1      
327m0911            J44   -A9         A01X+161797Y+009287X0150Y0500R090 S1      
317m0911            VIA   -    MD0100PA00X+160682Y+009511X0200Y         S0      
317m0911            VIA   -    M      A01X+159649Y+012511X0200Y         S2      
017m0911            VIA   -    M      A18X+159649Y+012511X0260Y         S2      
017m0911                  -    MD0100PA00X+159649Y+012511                       
327m0911            R5710 -1          A01X+159528Y+012775X0198Y0197R090 S1      
317m0912            VIA   -    M      A01X+057632Y+013884X0200Y         S2      
017m0912            VIA   -    M      A18X+057632Y+013884X0260Y         S2      
017m0912                  -    MD0100PA00X+057632Y+013884                       
327m0912            U386  -4          A01X+057282Y+013674X0240Y0240     S1      
327m0912            R5668 -1   M      A01X+057872Y+013884X0198Y0197     S1      
327m0912            R5666 -2          A01X+057875Y+013090X0198Y0197R090 S1      
327m0912            R5664 -1   M      A01X+057872Y+013484X0198Y0197     S1      
327m0913            J38   -A9         A01X+095616Y+009287X0150Y0500R090 S1      
317m0913            VIA   -    MD0100PA00X+094501Y+009511X0200Y         S0      
317m0913            VIA   -    M      A01X+093468Y+012511X0200Y         S2      
017m0913            VIA   -    M      A18X+093468Y+012511X0260Y         S2      
017m0913                  -    MD0100PA00X+093468Y+012511                       
327m0913            R5686 -1          A01X+093347Y+012775X0198Y0197R090 S1      
317RST_SMB_SSD5_N   VIA   -    M      A01X+055280Y+014352X0200Y         S2      
017RST_SMB_SSD5_N   VIA   -    M      A18X+055280Y+014352X0260Y         S2      
017RST_SMB_SSD5_N         -    MD0100PA00X+055280Y+014352                       
327RST_SMB_SSD5_N   U386  -2          A01X+056573Y+013970X0160Y0240R090 S1      
327RST_SMB_SSD5_N   R5665 -2          A01X+055505Y+014577X0198Y0197     S1      
327m0914            J39   -A9         A01X+105852Y+009287X0150Y0500R090 S1      
317m0914            VIA   -    MD0100PA00X+104737Y+009511X0200Y         S0      
317m0914            VIA   -    M      A01X+103704Y+012511X0200Y         S2      
017m0914            VIA   -    M      A18X+103704Y+012511X0260Y         S2      
017m0914                  -    MD0100PA00X+103704Y+012511                       
327m0914            R5682 -1          A01X+103583Y+012775X0198Y0197R090 S1      
317m0915            VIA   -    M      A01X+082948Y+034510X0200Y         S2      
017m0915            VIA   -    M      A18X+082948Y+034510X0260Y         S2      
017m0915                  -    MD0100PA00X+082948Y+034510                       
327m0915            R4359 -2          A01X+081505Y+035474X0198Y0197     S1      
327m0915            R5771 -2   M      A01X+081505Y+035037X0198Y0197     S1      
327m0915            U330  -1          A01X+083296Y+033784X0240Y0540R270 S1      
327m0916            J34   -A9         A01X+049908Y+009287X0150Y0500R090 S1      
317m0916            VIA   -    M      A01X+047759Y+012511X0200Y         S2      
017m0916            VIA   -    M      A18X+047759Y+012511X0260Y         S2      
017m0916                  -    MD0100PA00X+047759Y+012511                       
317m0916            VIA   -    MD0100PA00X+048792Y+009511X0200Y         S0      
327m0916            R5670 -1          A01X+047639Y+012775X0198Y0197R090 S1      
327m0917            J43   -A9         A01X+151561Y+009287X0150Y0500R090 S1      
317m0917            VIA   -    MD0100PA00X+150446Y+009511X0200Y         S0      
317m0917            VIA   -    M      A01X+149413Y+012511X0200Y         S2      
017m0917            VIA   -    M      A18X+149413Y+012511X0260Y         S2      
017m0917                  -    MD0100PA00X+149413Y+012511                       
327m0917            R5698 -1          A01X+149292Y+012775X0198Y0197R090 S1      
327m0918            J41   -A9         A01X+126325Y+009287X0150Y0500R090 S1      
317m0918            VIA   -    MD0100PA00X+125210Y+009511X0200Y         S0      
317m0918            VIA   -    M      A01X+124176Y+012511X0200Y         S2      
017m0918            VIA   -    M      A18X+124176Y+012511X0260Y         S2      
017m0918                  -    MD0100PA00X+124176Y+012511                       
327m0918            R5690 -1          A01X+124056Y+012775X0198Y0197R090 S1      
327JTAG_BIC_TDO_R   R4893 -1          A01X+095868Y+083135X0198Y0197R090 S1      
317JTAG_BIC_TDO_R   VIA   -    MD0100PA00X+095624Y+082958X0200Y         S0      
317JTAG_BIC_TDO_R   VIA   -    M      A01X+099638Y+081614X0200Y         S2      
017JTAG_BIC_TDO_R   VIA   -    M      A18X+099638Y+081614X0280Y         S2      
017JTAG_BIC_TDO_R         -    MD0100PA00X+099638Y+081614                       
327JTAG_BIC_TDO_R   R5068 -2          A01X+100270Y+081382X0198Y0197R270 S1      
327JTAG_BIC_TDO_R   R5642 -1          A01X+099405Y+081692X0198Y0197R270 S1      
317m0919            VIA   -    M      A01X+047396Y+013884X0200Y         S2      
017m0919            VIA   -    M      A18X+047396Y+013884X0260Y         S2      
017m0919                  -    MD0100PA00X+047396Y+013884                       
327m0919            U387  -4          A01X+047045Y+013674X0240Y0240     S1      
327m0919            R5671 -1   M      A01X+047636Y+013884X0198Y0197     S1      
327m0919            R5670 -2          A01X+047639Y+013090X0198Y0197R090 S1      
327m0919            R5667 -1   M      A01X+047636Y+013484X0198Y0197     S1      
327m0920            J40   -A9         A01X+116088Y+009287X0150Y0500R090 S1      
317m0920            VIA   -    MD0100PA00X+114974Y+009511X0200Y         S0      
317m0920            VIA   -    M      A01X+113940Y+012511X0200Y         S2      
017m0920            VIA   -    M      A18X+113940Y+012511X0260Y         S2      
017m0920                  -    MD0100PA00X+113940Y+012511                       
327m0920            R5694 -1          A01X+113820Y+012775X0198Y0197R090 S1      
317RST_SMB_SSD4_N   VIA   -    M      A01X+045044Y+014352X0200Y         S2      
017RST_SMB_SSD4_N   VIA   -    M      A18X+045044Y+014352X0260Y         S2      
017RST_SMB_SSD4_N         -    MD0100PA00X+045044Y+014352                       
327RST_SMB_SSD4_N   R5669 -2          A01X+045269Y+014577X0198Y0197     S1      
327RST_SMB_SSD4_N   U387  -2          A01X+046337Y+013970X0160Y0240R090 S1      
327m0921            J45   -A9         A01X+172033Y+009287X0150Y0500R090 S1      
317m0921            VIA   -    MD0100PA00X+170918Y+009511X0200Y         S0      
317m0921            VIA   -    M      A01X+169885Y+012511X0200Y         S2      
017m0921            VIA   -    M      A18X+169885Y+012511X0260Y         S2      
017m0921                  -    MD0100PA00X+169885Y+012511                       
327m0921            R5706 -1          A01X+169764Y+012775X0198Y0197R090 S1      
327m0922            J33   -A9         A01X+034907Y+009287X0150Y0500R090 S1      
317m0922            VIA   -    MD0100PA00X+033792Y+009511X0200Y         S0      
317m0922            VIA   -    M      A01X+032759Y+012511X0200Y         S2      
017m0922            VIA   -    M      A18X+032759Y+012511X0260Y         S2      
017m0922                  -    MD0100PA00X+032759Y+012511                       
327m0922            R5658 -1          A01X+032638Y+012775X0198Y0197R090 S1      
317m0923            VIA   -    M      A01X+098799Y+077400X0200Y         S2      
017m0923            VIA   -    M      A18X+098799Y+077400X0280Y         S2      
017m0923                  -    MD0100PA00X+098799Y+077400                       
327m0923            U294  -2          A01X+099326Y+078330X0140Y0590     S1      
327m0923            R5645 -2          A01X+098799Y+077155X0198Y0197R090 S1      
317m0924            VIA   -    M      A01X+099999Y+077467X0200Y         S2      
017m0924            VIA   -    M      A18X+099999Y+077467X0280Y         S2      
017m0924                  -    MD0100PA00X+099999Y+077467                       
327m0924            U294  -5          A01X+100094Y+078330X0140Y0590     S1      
327m0924            R5644 -2          A01X+099999Y+077155X0198Y0197R090 S1      
317m0925            VIA   -    M      A01X+032395Y+013884X0200Y         S2      
017m0925            VIA   -    M      A18X+032395Y+013884X0260Y         S2      
017m0925                  -    MD0100PA00X+032395Y+013884                       
327m0925            R5659 -1   M      A01X+032635Y+013884X0198Y0197     S1      
327m0925            U384  -4          A01X+032045Y+013674X0240Y0240     S1      
327m0925            R5658 -2          A01X+032638Y+013090X0198Y0197R090 S1      
327m0925            R5656 -1   M      A01X+032635Y+013484X0198Y0197     S1      
317RST_SMB_SSD3_N   VIA   -    M      A01X+030044Y+014352X0200Y         S2      
017RST_SMB_SSD3_N   VIA   -    M      A18X+030044Y+014352X0260Y         S2      
017RST_SMB_SSD3_N         -    MD0100PA00X+030044Y+014352                       
327RST_SMB_SSD3_N   R5657 -2          A01X+030268Y+014577X0198Y0197     S1      
327RST_SMB_SSD3_N   U384  -2          A01X+031337Y+013970X0160Y0240R090 S1      
317m0926            VIA   -    M      A01X+101070Y+080345X0200Y         S2      
017m0926            VIA   -    M      A18X+101070Y+080345X0280Y         S2      
017m0926                  -    MD0100PA00X+101070Y+080345                       
327m0926            U294  -9          A01X+100349Y+080630X0140Y0590     S1      
327m0926            R5643 -2          A01X+101070Y+081382X0198Y0197R270 S1      
327m0927            J32   -A9         A01X+024671Y+009287X0150Y0500R090 S1      
317m0927            VIA   -    MD0100PA00X+023556Y+009511X0200Y         S0      
317m0927            VIA   -    M      A01X+022523Y+012511X0200Y         S2      
017m0927            VIA   -    M      A18X+022523Y+012511X0260Y         S2      
017m0927                  -    MD0100PA00X+022523Y+012511                       
327m0927            R5662 -1          A01X+022402Y+012775X0198Y0197R090 S1      
327m0928            U385  -4          A01X+021809Y+013674X0240Y0240     S1      
317m0928            VIA   -    M      A01X+022159Y+013884X0200Y         S2      
017m0928            VIA   -    M      A18X+022159Y+013884X0260Y         S2      
017m0928                  -    MD0100PA00X+022159Y+013884                       
327m0928            R5662 -2          A01X+022402Y+013090X0198Y0197R090 S1      
327m0928            R5660 -1   M      A01X+022399Y+013484X0198Y0197     S1      
327m0928            R5663 -1   M      A01X+022399Y+013884X0198Y0197     S1      
327RST_SMB_SSD2_N   U385  -2          A01X+021100Y+013970X0160Y0240R090 S1      
317RST_SMB_SSD2_N   VIA   -    M      A01X+019807Y+014352X0200Y         S2      
017RST_SMB_SSD2_N   VIA   -    M      A18X+019807Y+014352X0260Y         S2      
017RST_SMB_SSD2_N         -    MD0100PA00X+019807Y+014352                       
327RST_SMB_SSD2_N   R5661 -2          A01X+020032Y+014577X0198Y0197     S1      
327m0929            VIA   -    M      A01X+086997Y+070456X0300Y         S1      
327m0929            Q58   -5          A01X+087780Y+071317X0170Y0240R270 S1      
327m0929            U360  -4          A01X+086948Y+068523X0220Y0530R270 S1      
327m0930            J31   -A9         A01X+014435Y+009287X0150Y0500R090 S1      
317m0930            VIA   -    MD0100PA00X+013320Y+009511X0200Y         S0      
317m0930            VIA   -    M      A01X+012287Y+012511X0200Y         S2      
017m0930            VIA   -    M      A18X+012287Y+012511X0260Y         S2      
017m0930                  -    MD0100PA00X+012287Y+012511                       
327m0930            R5650 -1          A01X+012166Y+012775X0198Y0197R090 S1      
317m0931            VIA   -    M      A01X+149049Y+013884X0200Y         S2      
017m0931            VIA   -    M      A18X+149049Y+013884X0260Y         S2      
017m0931                  -    MD0100PA00X+149049Y+013884                       
327m0931            U394  -4          A01X+148699Y+013674X0240Y0240     S1      
327m0931            R5700 -1   M      A01X+149289Y+013884X0198Y0197     S1      
327m0931            R5698 -2          A01X+149292Y+013090X0198Y0197R090 S1      
327m0931            R5696 -1   M      A01X+149289Y+013484X0198Y0197     S1      
317m0932            VIA   -    M      A01X+156933Y+014352X0200Y         S2      
017m0932            VIA   -    M      A18X+156933Y+014352X0260Y         S2      
017m0932                  -    MD0100PA00X+156933Y+014352                       
327m0932            R5709 -2          A01X+157158Y+014577X0198Y0197     S1      
327m0932            U397  -2          A01X+158226Y+013970X0160Y0240R090 S1      
317m0933            VIA   -    M      A01X+011923Y+013884X0200Y         S2      
017m0933            VIA   -    M      A18X+011923Y+013884X0260Y         S2      
017m0933                  -    MD0100PA00X+011923Y+013884                       
327m0933            U382  -4          A01X+011573Y+013674X0240Y0240     S1      
327m0933            R5651 -1   M      A01X+012163Y+013884X0198Y0197     S1      
327m0933            R5650 -2          A01X+012166Y+013090X0198Y0197R090 S1      
327m0933            R5648 -1   M      A01X+012163Y+013484X0198Y0197     S1      
317RST_SMB_SSD9_N   VIA   -    M      A01X+100988Y+014352X0200Y         S2      
017RST_SMB_SSD9_N   VIA   -    M      A18X+100988Y+014352X0260Y         S2      
017RST_SMB_SSD9_N         -    MD0100PA00X+100988Y+014352                       
327RST_SMB_SSD9_N   U390  -2          A01X+102282Y+013970X0160Y0240R090 S1      
327RST_SMB_SSD9_N   R5681 -2          A01X+101213Y+014577X0198Y0197     S1      
317RST_SMB_SSD1_N   VIA   -    M      A01X+009571Y+014352X0200Y         S2      
017RST_SMB_SSD1_N   VIA   -    M      A18X+009571Y+014352X0260Y         S2      
017RST_SMB_SSD1_N         -    MD0100PA00X+009571Y+014352                       
327RST_SMB_SSD1_N   R5649 -2          A01X+009796Y+014577X0198Y0197     S1      
327RST_SMB_SSD1_N   U382  -2          A01X+010864Y+013970X0160Y0240R090 S1      
317m0934            VIA   -    M      A01X+123813Y+013884X0200Y         S2      
017m0934            VIA   -    M      A18X+123813Y+013884X0260Y         S2      
017m0934                  -    MD0100PA00X+123813Y+013884                       
327m0934            U392  -4          A01X+123463Y+013674X0240Y0240     S1      
327m0934            R5692 -1   M      A01X+124053Y+013884X0198Y0197     S1      
327m0934            R5690 -2          A01X+124056Y+013090X0198Y0197R090 S1      
327m0934            R5688 -1   M      A01X+124053Y+013484X0198Y0197     S1      
317RST_SMB_SSD0_N   VIA   -    M      A01X+001481Y+028218X0200Y         S2      
017RST_SMB_SSD0_N   VIA   -    M      A18X+001481Y+028218X0260Y         S2      
017RST_SMB_SSD0_N         -    MD0100PA00X+001481Y+028218                       
327RST_SMB_SSD0_N   U383  -2          A01X+001908Y+028408X0160Y0240R090 S1      
327RST_SMB_SSD0_N   R5653 -2          A01X+001148Y+028412X0198Y0197     S1      
317RST_SMB_SSD8_N   VIA   -    M      A01X+090752Y+014352X0200Y         S2      
017RST_SMB_SSD8_N   VIA   -    M      A18X+090752Y+014352X0260Y         S2      
017RST_SMB_SSD8_N         -    MD0100PA00X+090752Y+014352                       
327RST_SMB_SSD8_N   R5685 -2          A01X+090977Y+014577X0198Y0197     S1      
327RST_SMB_SSD8_N   U391  -2          A01X+092045Y+013970X0160Y0240R090 S1      
317m0935            VIA   -    M      A01X+138813Y+013884X0200Y         S2      
017m0935            VIA   -    M      A18X+138813Y+013884X0260Y         S2      
017m0935                  -    MD0100PA00X+138813Y+013884                       
327m0935            U395  -4          A01X+138463Y+013674X0240Y0240     S1      
327m0935            R5703 -1   M      A01X+139053Y+013884X0198Y0197     S1      
327m0935            R5702 -2          A01X+139056Y+013090X0198Y0197R090 S1      
327m0935            R5699 -1   M      A01X+139053Y+013484X0198Y0197     S1      
327m0936            J30   -A9         A01X+004199Y+009287X0150Y0500R090 S1      
317m0936            VIA   -    MD0100PA00X+001800Y+009000X0200Y         S0      
317m0936            VIA   -    M      A01X+003712Y+027999X0200Y         S2      
017m0936            VIA   -    M      A18X+003712Y+027999X0260Y         S2      
017m0936                  -    MD0100PA00X+003712Y+027999                       
327m0936            R5654 -1          A01X+003484Y+028127X0198Y0197R180 S1      
317m0937            VIA   -    M      A01X+146697Y+014352X0200Y         S2      
017m0937            VIA   -    M      A18X+146697Y+014352X0260Y         S2      
017m0937                  -    MD0100PA00X+146697Y+014352                       
327m0937            R5697 -2          A01X+146922Y+014577X0198Y0197     S1      
327m0937            U394  -2          A01X+147990Y+013970X0160Y0240R090 S1      
317m0938            VIA   -    M      A01X+103340Y+013884X0200Y         S2      
017m0938            VIA   -    M      A18X+103340Y+013884X0260Y         S2      
017m0938                  -    MD0100PA00X+103340Y+013884                       
327m0938            U390  -4          A01X+102990Y+013674X0240Y0240     S1      
327m0938            R5684 -1   M      A01X+103580Y+013884X0198Y0197     S1      
327m0938            R5682 -2          A01X+103583Y+013090X0198Y0197R090 S1      
327m0938            R5680 -1   M      A01X+103580Y+013484X0198Y0197     S1      
317m0939            VIA   -    M      A01X+002912Y+028113X0200Y         S2      
017m0939            VIA   -    M      A18X+002912Y+028113X0260Y         S2      
017m0939                  -    MD0100PA00X+002912Y+028113                       
327m0939            R5652 -1          A01X+003170Y+028927X0198Y0197     S1      
327m0939            R5655 -1   M      A01X+003170Y+028527X0198Y0197     S1      
327m0939            R5654 -2   M      A01X+003170Y+028127X0198Y0197R180 S1      
327m0939            U383  -4          A01X+002616Y+028113X0240Y0240     S1      
317m0940            VIA   -    M      A01X+111225Y+014352X0200Y         S2      
017m0940            VIA   -    M      A18X+111225Y+014352X0260Y         S2      
017m0940                  -    MD0100PA00X+111225Y+014352                       
327m0940            U393  -2          A01X+112518Y+013970X0160Y0240R090 S1      
327m0940            R5693 -2          A01X+111450Y+014577X0198Y0197     S1      
317m0941            VIA   -    M      A01X+167170Y+014352X0200Y         S2      
017m0941            VIA   -    M      A18X+167170Y+014352X0260Y         S2      
017m0941                  -    MD0100PA00X+167170Y+014352                       
327m0941            R5705 -2          A01X+167394Y+014577X0198Y0197     S1      
327m0941            U396  -2          A01X+168463Y+013970X0160Y0240R090 S1      
317m0942            VIA   -    M      A01X+136461Y+014352X0200Y         S2      
017m0942            VIA   -    M      A18X+136461Y+014352X0260Y         S2      
017m0942                  -    MD0100PA00X+136461Y+014352                       
327m0942            R5701 -2          A01X+136686Y+014577X0198Y0197     S1      
327m0942            U395  -2          A01X+137754Y+013970X0160Y0240R090 S1      
317m0943            VIA   -    M      A01X+159285Y+013884X0200Y         S2      
017m0943            VIA   -    M      A18X+159285Y+013884X0260Y         S2      
017m0943                  -    MD0100PA00X+159285Y+013884                       
327m0943            U397  -4          A01X+158935Y+013674X0240Y0240     S1      
327m0943            R5711 -1   M      A01X+159525Y+013884X0198Y0197     S1      
327m0943            R5710 -2          A01X+159528Y+013090X0198Y0197R090 S1      
327m0943            R5707 -1   M      A01X+159525Y+013484X0198Y0197     S1      
317m0944            VIA   -    M      A01X+121461Y+014352X0200Y         S2      
017m0944            VIA   -    M      A18X+121461Y+014352X0260Y         S2      
017m0944                  -    MD0100PA00X+121461Y+014352                       
327m0944            R5689 -2          A01X+121686Y+014577X0198Y0197     S1      
327m0944            U392  -2          A01X+122754Y+013970X0160Y0240R090 S1      
317m0945            VIA   -    M      A01X+113576Y+013884X0200Y         S2      
017m0945            VIA   -    M      A18X+113576Y+013884X0260Y         S2      
017m0945                  -    MD0100PA00X+113576Y+013884                       
327m0945            U393  -4          A01X+113226Y+013674X0240Y0240     S1      
327m0945            R5695 -1   M      A01X+113816Y+013884X0198Y0197     S1      
327m0945            R5694 -2          A01X+113820Y+013090X0198Y0197R090 S1      
327m0945            R5691 -1   M      A01X+113816Y+013484X0198Y0197     S1      
317SSD15_LED        VIA   -    M      A01X+086304Y+033014X0200Y         S2      
017SSD15_LED        VIA   -    M      A18X+086304Y+033014X0260Y         S2      
017SSD15_LED              -    MD0100PA00X+086304Y+033014                       
327SSD15_LED        U330  -20         A01X+085599Y+032721X0160Y0540R270 S1      
327SSD15_LED        R5769 -1          A01X+087240Y+033337X0198Y0197     S1      
317m0946            VIA   -    M      A01X+093104Y+013884X0200Y         S2      
017m0946            VIA   -    M      A18X+093104Y+013884X0260Y         S2      
017m0946                  -    MD0100PA00X+093104Y+013884                       
327m0946            U391  -4          A01X+092754Y+013674X0240Y0240     S1      
327m0946            R5687 -1   M      A01X+093344Y+013884X0198Y0197     S1      
327m0946            R5686 -2          A01X+093347Y+013090X0198Y0197R090 S1      
327m0946            R5683 -1   M      A01X+093344Y+013484X0198Y0197     S1      
317SSD14_LED        VIA   -    M      A01X+086992Y+032872X0200Y         S2      
017SSD14_LED        VIA   -    M      A18X+086992Y+032872X0260Y         S2      
017SSD14_LED              -    MD0100PA00X+086992Y+032872                       
327SSD14_LED        U330  -19         A01X+085599Y+032465X0160Y0540R270 S1      
327SSD14_LED        R5768 -1          A01X+087240Y+032937X0198Y0197     S1      
317PWR_EN_PEX_R1    VIA   -    M      A01X+144087Y+101026X0200Y         S2      
017PWR_EN_PEX_R1    VIA   -    M      A18X+144087Y+101026X0260Y         S2      
017PWR_EN_PEX_R1          -    MD0100PA00X+144087Y+101026                       
327PWR_EN_PEX_R1    R3068 -2          A01X+144319Y+100152X0198Y0197     S1      
327PWR_EN_PEX_R1    U379  -2          A01X+144087Y+101440X0160Y0360     S1      
327m0947            VIA   -           A18X+129647Y+090347X0260Y         S2      
327m0947            VIA   -           A18X+129990Y+089654X0260Y         S2      
317m0947            VIA   -    MD0100PA00X+129647Y+089961X0200Y         S0      
317m0947            VIA   -    MD0100PA00X+129897Y+089961X0200Y         S0      
327m0947            C2085 -1          A18X+131848Y+088499X0164Y0164     S2      
327m0947            C2087 -1          A18X+130639Y+089343X0164Y0164R270 S2      
327m0947            C2088 -1          A18X+131048Y+089343X0164Y0164R270 S2      
327m0947            VIA   -           A18X+131560Y+088952X0260Y         S2      
327m0947            R5641 -2          A18X+129340Y+089742X0280Y0320R270 S2      
317m0947            VIA   -    MD0100PA00X+132006Y+088341X0180Y         S0      
327m0947            U6    -F3         A01X+132163Y+088184X0160Y         S1      
317m0947            VIA   -    MD0100PA00X+133580Y+087081X0180Y         S0      
327m0947            U6    -K8         A01X+133738Y+086924X0160Y         S1      
317m0947            VIA   -    MD0100PA00X+133580Y+087396X0180Y         S0      
327m0947            U6    -J8         A01X+133738Y+087239X0160Y         S1      
327m0947            C2086 -1          A18X+133423Y+087554X0164Y0164R270 S2      
327m0947            C2089 -1          A18X+133738Y+087239X0164Y0164R270 S2      
327PWR_EN_PEX_BUF   VIA   -    M      A01X+144343Y+102900X0300Y         S1      
327PWR_EN_PEX_BUF   R3067 -2          A01X+144346Y+103434X0198Y0197R270 S1      
327PWR_EN_PEX_BUF   U379  -4          A01X+144343Y+102306X0160Y0360     S1      
327m0948            C2083 -1          A18X+133738Y+086609X0164Y0164R270 S2      
327m0948            U6    -L8         A01X+133738Y+086609X0160Y         S1      
317m0948            VIA   -    MD0100PA00X+133580Y+086766X0180Y         S0      
327m0948            C2081 -1          A18X+133738Y+086294X0164Y0164R090 S2      
327m0948            VIA   -           A18X+133220Y+086457X0260Y         S2      
317m0948            VIA   -    MD0100PA00X+132006Y+086137X0180Y         S0      
327m0948            U6    -M3         A01X+132163Y+086294X0160Y         S1      
317m0948            VIA   -    MD0100PA00X+133580Y+086137X0180Y         S0      
327m0948            U6    -M8         A01X+133738Y+086294X0160Y         S1      
327m0948            VIA   -           A18X+132629Y+086460X0260Y         S2      
327m0948            VIA   -           A18X+131012Y+086385X0260Y         S2      
327m0948            C2082 -1          A18X+130603Y+085909X0164Y0164     S2      
327m0948            C2084 -1          A18X+131456Y+086418X0164Y0164R270 S2      
327m0948            C2080 -1          A18X+131854Y+086313X0164Y0164R180 S2      
327m0948            R5640 -2          A18X+130498Y+086399X0280Y0320R270 S2      
317SSD13_LED        VIA   -    M      A01X+086311Y+032450X0200Y         S2      
017SSD13_LED        VIA   -    M      A18X+086311Y+032450X0260Y         S2      
017SSD13_LED              -    MD0100PA00X+086311Y+032450                       
327SSD13_LED        R5767 -1          A01X+087240Y+032537X0198Y0197     S1      
327SSD13_LED        U330  -18         A01X+085599Y+032209X0160Y0540R270 S1      
327m0949            VIA   -           A18X+131236Y+084579X0260Y         S2      
327m0949            VIA   -           A18X+131068Y+085698X0260Y         S2      
327m0949            C2079 -1          A18X+133738Y+085664X0164Y0164R090 S2      
317m0949            VIA   -    MD0100PA00X+133580Y+085822X0180Y         S0      
327m0949            U6    -N8         A01X+133738Y+085979X0160Y         S1      
317m0949            VIA   -    MD0100PA00X+133580Y+085507X0180Y         S0      
327m0949            U6    -P8         A01X+133738Y+085664X0160Y         S1      
327m0949            C2076 -1          A18X+133423Y+085349X0164Y0164R090 S2      
327m0949            VIA   -           A18X+131510Y+085220X0260Y         S2      
327m0949            C2077 -1          A18X+130593Y+085119X0164Y0164     S2      
327m0949            C2078 -1          A18X+130592Y+085482X0164Y0164     S2      
327m0949            R5639 -2          A18X+130677Y+084667X0280Y0320R270 S2      
327m0949            C2075 -1   M      A18X+131846Y+084092X0164Y0164     S2      
327m0949            U6    -V3         A01X+132163Y+084404X0160Y         S1      
317m0949            VIA   -    MD0100PA00X+132006Y+084247X0180Y         S0      
317m0950            VIA   -    M      A01X+141345Y+082393X0200Y         S2      
017m0950            VIA   -    M      A18X+141345Y+082393X0260Y         S2      
017m0950                  -    MD0100PA00X+141345Y+082393                       
317m0950            VIA   -    MD0100PA00X+095995Y+073418X0200Y         S0      
327m0950            R3152 -1          A01X+095995Y+073161X0198Y0197R270 S1      
327m0950            R5780 -1          A01X+141102Y+082393X0198Y0197R180 S1      
327m0951            VIA   -           A18X+131128Y+083756X0260Y         S2      
327m0951            VIA   -           A18X+130363Y+084105X0260Y         S2      
327m0951            C2053 -1          A18X+130633Y+083598X0164Y0164     S2      
327m0951            C2058 -1          A18X+130634Y+083225X0164Y0164     S2      
327m0951            R5638 -2          A18X+130769Y+082807X0280Y0320     S2      
327m0951            C2056 -1          A18X+135313Y+085349X0164Y0164R270 S2      
327m0951            C2055 -1          A18X+135628Y+085349X0164Y0164R270 S2      
327m0951            C2057 -1          A18X+134053Y+085349X0164Y0164R270 S2      
327m0951            C2059 -1          A18X+134368Y+085349X0164Y0164R270 S2      
327m0951            C2060 -1          A18X+134998Y+085349X0164Y0164R270 S2      
327m0951            C2054 -1          A18X+134683Y+085349X0164Y0164R270 S2      
327m0951            VIA   -           A18X+134828Y+084917X0260Y         S2      
327m0951            U6    -R14        A01X+135628Y+085349X0160Y         S1      
317m0951            VIA   -    MD0100PA00X+135785Y+085192X0180Y         S0      
327m0951            U6    -R13        A01X+135312Y+085349X0160Y         S1      
317m0951            VIA   -    MD0100PA00X+135470Y+085192X0180Y         S0      
327m0951            U6    -R12        A01X+134998Y+085349X0160Y         S1      
317m0951            VIA   -    MD0100PA00X+135155Y+085192X0180Y         S0      
327m0951            U6    -R11        A01X+134683Y+085349X0160Y         S1      
317m0951            VIA   -    MD0100PA00X+134525Y+085192X0180Y         S0      
327m0951            U6    -R10        A01X+134368Y+085349X0160Y         S1      
317m0951            VIA   -    MD0100PA00X+134210Y+085192X0180Y         S0      
327m0951            U6    -R9         A01X+134053Y+085349X0160Y         S1      
317m0951            VIA   -    MD0100PA00X+133895Y+085192X0180Y         S0      
317m0951            VIA   -    MD0100PA00X+136415Y+083932X0180Y         S0      
327m0951            U6    -W16        A01X+136257Y+084089X0160Y         S1      
327m0951            C2050 -1          A18X+136257Y+084089X0164Y0164R090 S2      
317m0951            VIA   -    MD0100PA00X+134525Y+083932X0180Y         S0      
327m0951            U6    -W11        A01X+134683Y+084089X0160Y         S1      
327m0951            C2051 -1          A18X+134683Y+084089X0164Y0164R180 S2      
317m0951            VIA   -    MD0100PA00X+133265Y+083932X0180Y         S0      
327m0951            U6    -W7         A01X+133423Y+084089X0160Y         S1      
327m0951            C2052 -1          A18X+133108Y+083774X0164Y0164R090 S2      
327m0951            R5803 -1          A01X+139454Y+080610X0198Y0197R090 S1      
317m0951            VIA   -    MD0100PA00X+139454Y+080365X0200Y         S0      
317m0951            VIA   -    MD0100PA00X+131069Y+082771X0200Y         S0      
317m0951            VIA   -    MD0100PA00X+131069Y+083271X0200Y         S0      
317m0951            VIA   -    MD0100PA00X+131069Y+083021X0200Y         S0      
327m0952            R5742 -2          A01X+064561Y+009748X0198Y0197R270 S1      
317m0952            VIA   -    M      A01X+064311Y+009748X0200Y    R090 S2      
017m0952            VIA   -    M      A18X+064311Y+009748X0260Y    R090 S2      
017m0952                  -    MD0100PA00X+064311Y+009748                       
327m0952            J35   -A10        A01X+060144Y+009524X0150Y0500R090 S1      
317m0952            VIA   -    MD0100PA00X+060544Y+009524X0200Y         S0      
327m0953            C2041 -1          A18X+137831Y+088502X0164Y0164R180 S2      
327m0953            C2042 -1          A18X+139080Y+086662X0164Y0164R180 S2      
327m0953            C2040 -1          A18X+137202Y+086609X0164Y0164R270 S2      
327m0953            C2048 -1          A18X+135942Y+087554X0164Y0164R090 S2      
327m0953            C2043 -1          A18X+136257Y+087239X0164Y0164R270 S2      
327m0953            C2046 -1          A18X+135942Y+086924X0164Y0164R090 S2      
327m0953            C2044 -1          A18X+139082Y+086283X0164Y0164R180 S2      
327m0953            R5637 -2          A18X+139045Y+085412X0280Y0320R090 S2      
327m0953            VIA   -           A18X+137849Y+086485X0260Y         S2      
327m0953            VIA   -           A18X+138415Y+085518X0260Y         S2      
327m0953            C2045 -1          A18X+135942Y+085349X0164Y0164R270 S2      
327m0953            C2049 -1          A18X+136257Y+085664X0164Y0164R090 S2      
327m0953            C2047 -1          A18X+135942Y+085979X0164Y0164R270 S2      
327m0953            VIA   -           A18X+138940Y+084705X0260Y         S2      
327m0953            C2039 -1          A18X+137512Y+084402X0164Y0164R180 S2      
327m0953            U6    -F20        A01X+137517Y+088184X0160Y         S1      
317m0953            VIA   -    MD0100PA00X+137675Y+088341X0180Y         S0      
327m0953            U6    -J15        A01X+135942Y+087239X0160Y         S1      
317m0953            VIA   -    MD0100PA00X+136100Y+087396X0180Y         S0      
327m0953            U6    -K15        A01X+135942Y+086924X0160Y         S1      
317m0953            VIA   -    MD0100PA00X+136100Y+087081X0180Y         S0      
327m0953            U6    -L15        A01X+135942Y+086609X0160Y         S1      
317m0953            VIA   -    MD0100PA00X+136100Y+086766X0180Y         S0      
317m0953            VIA   -    MD0100PA00X+138849Y+085782X0200Y         S0      
317m0953            VIA   -    MD0100PA00X+139132Y+085785X0200Y         S0      
327m0953            U6    -M18        A01X+136887Y+086294X0160Y         S1      
317m0953            VIA   -    MD0100PA00X+137045Y+086137X0180Y         S0      
327m0953            U6    -M15        A01X+135942Y+086294X0160Y         S1      
317m0953            VIA   -    MD0100PA00X+136100Y+086137X0180Y         S0      
327m0953            U6    -N15        A01X+135942Y+085979X0160Y         S1      
317m0953            VIA   -    MD0100PA00X+136100Y+085822X0180Y         S0      
327m0953            U6    -P15        A01X+135942Y+085664X0160Y         S1      
317m0953            VIA   -    MD0100PA00X+136100Y+085507X0180Y         S0      
327m0953            U6    -V20        A01X+137517Y+084404X0160Y         S1      
317m0953            VIA   -    MD0100PA00X+137675Y+084247X0180Y         S0      
317SSD5_LED_ISO_N   VIA   -    M      A01X+065009Y+010062X0200Y    R270 S2      
017SSD5_LED_ISO_N   VIA   -    M      A18X+065009Y+010062X0260Y    R270 S2      
017SSD5_LED_ISO_N         -    MD0100PA00X+065009Y+010062                       
327SSD5_LED_ISO_N   U403  -D          A01X+065502Y+009926X0400Y0560R180 S1      
327SSD5_LED_ISO_N   R5741 -2          A01X+064561Y+010509X0198Y0197R270 S1      
327SSD5_LED_ISO_N   R5742 -1   M      A01X+064561Y+010062X0198Y0197R270 S1      
327m0954            U6    -P17        A01X+136572Y+085664X0160Y         S1      
317m0954            VIA   -    MD0100PA00X+136730Y+085507X0180Y         S0      
327m0954            R5780 -2          A01X+140787Y+082393X0198Y0197R180 S1      
317m0954            VIA   -    M      A01X+140007Y+082752X0200Y         S2      
017m0954            VIA   -    M      A18X+140007Y+082752X0260Y         S2      
017m0954                  -    MD0100PA00X+140007Y+082752                       
327m0955            VIA   -           A18X+138675Y+089655X0260Y         S2      
317m0955            VIA   -    MD0100PA00X+139098Y+089292X0200Y         S0      
317m0955            VIA   -    MD0100PA00X+138598Y+089292X0200Y         S0      
317m0955            VIA   -    MD0100PA00X+138848Y+089292X0200Y         S0      
327m0955            R5636 -2          A18X+139678Y+089611X0280Y0320R180 S2      
317m0955            VIA   -    MD0100PA00X+136415Y+089286X0180Y         S0      
327m0955            U6    -C16        A01X+136257Y+089129X0160Y         S1      
327m0955            C2038 -1          A18X+136572Y+089129X0164Y0164R270 S2      
317m0955            VIA   -    MD0100PA00X+135155Y+089286X0180Y         S0      
327m0955            U6    -C12        A01X+134998Y+089129X0160Y         S1      
327m0955            C2028 -1          A18X+134998Y+089129X0164Y0164     S2      
327m0955            VIA   -           A18X+134813Y+089628X0260Y         S2      
317m0955            VIA   -    MD0100PA00X+133265Y+089286X0180Y         S0      
327m0955            U6    -C7         A01X+133423Y+089129X0160Y         S1      
327m0955            C2029 -1          A18X+133423Y+089129X0164Y0164R270 S2      
327m0955            VIA   -           A18X+134817Y+088010X0260Y         S2      
327m0955            C2033 -1          A18X+135312Y+087554X0164Y0164R090 S2      
327m0955            C2035 -1          A18X+135627Y+087554X0164Y0164R090 S2      
327m0955            C2034 -1          A18X+135628Y+087869X0164Y0164R180 S2      
327m0955            C2031 -1          A18X+134053Y+087869X0164Y0164     S2      
327m0955            C2032 -1          A18X+134997Y+087554X0164Y0164R090 S2      
327m0955            C2036 -1          A18X+134682Y+087554X0164Y0164R090 S2      
327m0955            C2030 -1          A18X+134368Y+087554X0164Y0164R090 S2      
327m0955            C2037 -1          A18X+134053Y+087554X0164Y0164R090 S2      
327m0955            U6    -G13        A01X+135312Y+087869X0160Y         S1      
317m0955            VIA   -    MD0100PA00X+135470Y+088026X0180Y         S0      
327m0955            U6    -G10        A01X+134368Y+087869X0160Y         S1      
317m0955            VIA   -    MD0100PA00X+134210Y+088026X0180Y         S0      
327m0955            U6    -H14        A01X+135628Y+087554X0160Y         S1      
317m0955            VIA   -    MD0100PA00X+135785Y+087711X0180Y         S0      
327m0955            U6    -H12        A01X+134998Y+087554X0160Y         S1      
317m0955            VIA   -    MD0100PA00X+135155Y+087711X0180Y         S0      
327m0955            U6    -H11        A01X+134683Y+087554X0160Y         S1      
317m0955            VIA   -    MD0100PA00X+134525Y+087711X0180Y         S0      
327m0955            U6    -H9         A01X+134053Y+087554X0160Y         S1      
317m0955            VIA   -    MD0100PA00X+133895Y+087711X0180Y         S0      
327m0956            R5740 -2          A01X+054325Y+009748X0198Y0197R270 S1      
317m0956            VIA   -    M      A01X+054075Y+009748X0200Y    R090 S2      
017m0956            VIA   -    M      A18X+054075Y+009748X0260Y    R090 S2      
017m0956                  -    MD0100PA00X+054075Y+009748                       
327m0956            J34   -A10        A01X+049908Y+009524X0150Y0500R090 S1      
317m0956            VIA   -    MD0100PA00X+050308Y+009524X0200Y         S0      
317SSD12_LED        VIA   -    M      A01X+086992Y+032137X0200Y         S2      
017SSD12_LED        VIA   -    M      A18X+086992Y+032137X0260Y         S2      
017SSD12_LED              -    MD0100PA00X+086992Y+032137                       
327SSD12_LED        U330  -17         A01X+085599Y+031953X0160Y0540R270 S1      
327SSD12_LED        R5766 -1          A01X+087240Y+032137X0198Y0197     S1      
327m0957            VIA   -           A18X+138536Y+087568X0260Y         S2      
317m0957            VIA   -    MD0100PA00X+138758Y+087349X0200Y         S0      
317m0957            VIA   -    MD0100PA00X+139018Y+087346X0200Y         S0      
327m0957            R5635 -2          A18X+138892Y+088091X0280Y0320R090 S2      
327m0957            C2073 -1          A18X+138984Y+087620X0164Y0164R180 S2      
327m0957            C2061 -1          A18X+138985Y+087102X0164Y0164R180 S2      
327m0957            VIA   -           A18X+138593Y+088659X0260Y         S2      
327m0957            VIA   -           A18X+139176Y+088713X0260Y         S2      
327m0957            C2065 -1          A18X+135627Y+086924X0164Y0164R090 S2      
327m0957            C2071 -1          A18X+135312Y+086924X0164Y0164R090 S2      
327m0957            U6    -K13        A01X+135312Y+086924X0160Y         S1      
317m0957            VIA   -    MD0100PA00X+135470Y+087081X0180Y         S0      
327m0957            C2074 -1          A18X+134997Y+086924X0164Y0164R090 S2      
327m0957            C2070 -1          A18X+134682Y+086924X0164Y0164R090 S2      
327m0957            C2072 -1          A18X+134053Y+086924X0164Y0164R090 S2      
327m0957            C2067 -1          A18X+134368Y+086924X0164Y0164R090 S2      
327m0957            U6    -L12        A01X+134998Y+086609X0160Y         S1      
317m0957            VIA   -    MD0100PA00X+135155Y+086766X0180Y         S0      
327m0957            U6    -K12        A01X+134998Y+086924X0160Y         S1      
317m0957            VIA   -    MD0100PA00X+135155Y+087081X0180Y         S0      
327m0957            U6    -L11        A01X+134683Y+086609X0160Y         S1      
317m0957            VIA   -    MD0100PA00X+134525Y+086766X0180Y         S0      
327m0957            U6    -K11        A01X+134683Y+086924X0160Y         S1      
317m0957            VIA   -    MD0100PA00X+134525Y+087081X0180Y         S0      
327m0957            U6    -K10        A01X+134368Y+086924X0160Y         S1      
317m0957            VIA   -    MD0100PA00X+134210Y+087081X0180Y         S0      
317m0957            VIA   -    MD0100PA00X+135155Y+086137X0180Y         S0      
327m0957            U6    -M12        A01X+134998Y+086294X0160Y         S1      
317m0957            VIA   -    MD0100PA00X+134210Y+085822X0180Y         S0      
327m0957            U6    -N10        A01X+134368Y+085979X0160Y         S1      
317m0957            VIA   -    MD0100PA00X+134525Y+086137X0180Y         S0      
327m0957            U6    -M11        A01X+134683Y+086294X0160Y         S1      
317m0957            VIA   -    MD0100PA00X+134525Y+085822X0180Y         S0      
327m0957            U6    -N11        A01X+134683Y+085979X0160Y         S1      
317m0957            VIA   -    MD0100PA00X+135155Y+085822X0180Y         S0      
327m0957            U6    -N12        A01X+134998Y+085979X0160Y         S1      
327m0957            C2069 -1          A18X+134368Y+085979X0164Y0164R270 S2      
327m0957            C2066 -1          A18X+134683Y+085979X0164Y0164R270 S2      
327m0957            C2064 -1          A18X+134053Y+085979X0164Y0164R270 S2      
327m0957            C2068 -1          A18X+134998Y+085979X0164Y0164R270 S2      
317m0957            VIA   -    MD0100PA00X+135470Y+085822X0180Y         S0      
327m0957            U6    -N13        A01X+135312Y+085979X0160Y         S1      
327m0957            C2062 -1          A18X+135313Y+085979X0164Y0164R270 S2      
327m0957            C2063 -1          A18X+135628Y+085979X0164Y0164R270 S2      
317SSD4_LED_ISO_N   VIA   -    M      A01X+054773Y+010062X0200Y    R270 S2      
017SSD4_LED_ISO_N   VIA   -    M      A18X+054773Y+010062X0260Y    R270 S2      
017SSD4_LED_ISO_N         -    MD0100PA00X+054773Y+010062                       
327SSD4_LED_ISO_N   U402  -D          A01X+055265Y+009926X0400Y0560R180 S1      
327SSD4_LED_ISO_N   R5739 -2          A01X+054325Y+010509X0198Y0197R270 S1      
327SSD4_LED_ISO_N   R5740 -1   M      A01X+054325Y+010062X0198Y0197R270 S1      
327m0958            R5738 -2          A01X+039325Y+009748X0198Y0197R270 S1      
317m0958            VIA   -    M      A01X+039075Y+009748X0200Y    R090 S2      
017m0958            VIA   -    M      A18X+039075Y+009748X0260Y    R090 S2      
017m0958                  -    MD0100PA00X+039075Y+009748                       
327m0958            J33   -A10        A01X+034907Y+009524X0150Y0500R090 S1      
317m0958            VIA   -    MD0100PA00X+035307Y+009524X0200Y         S0      
317SSD3_LED_ISO_N   VIA   -    M      A01X+039773Y+010062X0200Y    R270 S2      
017SSD3_LED_ISO_N   VIA   -    M      A18X+039773Y+010062X0260Y    R270 S2      
017SSD3_LED_ISO_N         -    MD0100PA00X+039773Y+010062                       
327SSD3_LED_ISO_N   R5737 -2          A01X+039325Y+010509X0198Y0197R270 S1      
327SSD3_LED_ISO_N   R5738 -1   M      A01X+039325Y+010062X0198Y0197R270 S1      
327SSD3_LED_ISO_N   U401  -D          A01X+040265Y+009926X0400Y0560R180 S1      
317SSD11_LED        VIA   -    M      A01X+086343Y+031697X0200Y         S2      
017SSD11_LED        VIA   -    M      A18X+086343Y+031697X0260Y         S2      
017SSD11_LED              -    MD0100PA00X+086343Y+031697                       
327SSD11_LED        R5765 -1          A01X+087240Y+031737X0198Y0197     S1      
327SSD11_LED        U330  -16         A01X+085599Y+031697X0160Y0540R270 S1      
317m0959            VIA   -    M      A01X+078104Y+013884X0200Y         S2      
017m0959            VIA   -    M      A18X+078104Y+013884X0260Y         S2      
017m0959                  -    MD0100PA00X+078104Y+013884                       
327m0959            U388  -4          A01X+077754Y+013674X0240Y0240     S1      
327m0959            R5676 -1   M      A01X+078344Y+013884X0198Y0197     S1      
327m0959            R5674 -2          A01X+078347Y+013090X0198Y0197R090 S1      
327m0959            R5672 -1   M      A01X+078344Y+013484X0198Y0197     S1      
327m0960            J32   -A10        A01X+024671Y+009524X0150Y0500R090 S1      
317m0960            VIA   -    M      A01X+028839Y+009748X0200Y    R090 S2      
017m0960            VIA   -    M      A18X+028839Y+009748X0260Y    R090 S2      
017m0960                  -    MD0100PA00X+028839Y+009748                       
327m0960            R5736 -2          A01X+029089Y+009748X0198Y0197R270 S1      
317m0960            VIA   -    MD0100PA00X+025071Y+009524X0200Y         S0      
317m0961            VIA   -    M      A01X+169521Y+013884X0200Y         S2      
017m0961            VIA   -    M      A18X+169521Y+013884X0260Y         S2      
017m0961                  -    MD0100PA00X+169521Y+013884                       
327m0961            U396  -4          A01X+169171Y+013674X0240Y0240     S1      
327m0961            R5708 -1   M      A01X+169761Y+013884X0198Y0197     S1      
327m0961            R5706 -2          A01X+169764Y+013090X0198Y0197R090 S1      
327m0961            R5704 -1   M      A01X+169761Y+013484X0198Y0197     S1      
317SSD2_LED_ISO_N   VIA   -    M      A01X+029537Y+010062X0200Y    R270 S2      
017SSD2_LED_ISO_N   VIA   -    M      A18X+029537Y+010062X0260Y    R270 S2      
017SSD2_LED_ISO_N         -    MD0100PA00X+029537Y+010062                       
327SSD2_LED_ISO_N   U400  -D          A01X+030029Y+009926X0400Y0560R180 S1      
327SSD2_LED_ISO_N   R5735 -2          A01X+029089Y+010509X0198Y0197R270 S1      
327SSD2_LED_ISO_N   R5736 -1   M      A01X+029089Y+010062X0198Y0197R270 S1      
317m0962            VIA   -    M      A01X+137842Y+056978X0200Y         S2      
017m0962            VIA   -    M      A18X+137842Y+056978X0260Y         S2      
017m0962                  -    MD0100PA00X+137842Y+056978                       
327m0962            U350  -15         A01X+137402Y+056654X0160Y0540R270 S1      
327m0962            R4841 -1          A01X+138517Y+056900X0198Y0197     S1      
317m0963            VIA   -    M      A01X+137842Y+056398X0200Y         S2      
017m0963            VIA   -    M      A18X+137842Y+056398X0260Y         S2      
017m0963                  -    MD0100PA00X+137842Y+056398                       
327m0963            U350  -14         A01X+137402Y+056398X0160Y0540R270 S1      
327m0963            R4840 -1          A01X+138517Y+056500X0198Y0197     S1      
317m0964            VIA   -    M      A01X+137842Y+070778X0200Y         S2      
017m0964            VIA   -    M      A18X+137842Y+070778X0260Y         S2      
017m0964                  -    MD0100PA00X+137842Y+070778                       
327m0964            U347  -15         A01X+137402Y+070454X0160Y0540R270 S1      
327m0964            R4759 -1          A01X+139142Y+070700X0198Y0197     S1      
317SSD10_LED        VIA   -    M      A01X+086992Y+031337X0200Y         S2      
017SSD10_LED        VIA   -    M      A18X+086992Y+031337X0260Y         S2      
017SSD10_LED              -    MD0100PA00X+086992Y+031337                       
327SSD10_LED        U330  -15         A01X+085599Y+031441X0160Y0540R270 S1      
327SSD10_LED        R5764 -1          A01X+087240Y+031337X0198Y0197     S1      
317m0965            VIA   -    M      A01X+137842Y+070198X0200Y         S2      
017m0965            VIA   -    M      A18X+137842Y+070198X0260Y         S2      
017m0965                  -    MD0100PA00X+137842Y+070198                       
327m0965            U347  -14         A01X+137402Y+070198X0160Y0540R270 S1      
327m0965            R4758 -1          A01X+139142Y+070300X0198Y0197     S1      
327m0966            J31   -A10        A01X+014435Y+009524X0150Y0500R090 S1      
317m0966            VIA   -    MD0100PA00X+014835Y+009524X0200Y         S0      
317m0966            VIA   -    M      A01X+018603Y+009748X0200Y    R090 S2      
017m0966            VIA   -    M      A18X+018603Y+009748X0260Y    R090 S2      
017m0966                  -    MD0100PA00X+018603Y+009748                       
327m0966            R5734 -2          A01X+018853Y+009748X0198Y0197R270 S1      
317m0967            VIA   -    M      A01X+147950Y+069763X0200Y         S2      
017m0967            VIA   -    M      A18X+147950Y+069763X0260Y         S2      
017m0967                  -    MD0100PA00X+147950Y+069763                       
327m0967            U346  -15         A01X+146502Y+068904X0160Y0540R270 S1      
327m0967            R4715 -1          A01X+148192Y+069763X0198Y0197     S1      
317SSD1_LED_ISO_N   VIA   -    M      A01X+019301Y+010062X0200Y    R270 S2      
017SSD1_LED_ISO_N   VIA   -    M      A18X+019301Y+010062X0260Y    R270 S2      
017SSD1_LED_ISO_N         -    MD0100PA00X+019301Y+010062                       
327SSD1_LED_ISO_N   R5733 -2          A01X+018853Y+010509X0198Y0197R270 S1      
327SSD1_LED_ISO_N   R5734 -1   M      A01X+018853Y+010062X0198Y0197R270 S1      
327SSD1_LED_ISO_N   U399  -D          A01X+019793Y+009926X0400Y0560R180 S1      
317m0968            VIA   -    M      A01X+147950Y+068963X0200Y         S2      
017m0968            VIA   -    M      A18X+147950Y+068963X0260Y         S2      
017m0968                  -    MD0100PA00X+147950Y+068963                       
327m0968            U346  -14         A01X+146502Y+068648X0160Y0540R270 S1      
327m0968            R4714 -1          A01X+148192Y+068963X0198Y0197     S1      
317SSD0_LED_ISO_N   VIA   -    M      A01X+001101Y+007972X0200Y         S2      
017SSD0_LED_ISO_N   VIA   -    M      A18X+001101Y+007972X0260Y         S2      
017SSD0_LED_ISO_N         -    MD0100PA00X+001101Y+007972                       
327SSD0_LED_ISO_N   U398  -D          A01X+001101Y+007534X0400Y0560     S1      
327SSD0_LED_ISO_N   R5731 -2          A01X+000879Y+008235X0198Y0197R270 S1      
327SSD0_LED_ISO_N   R5732 -1   M      A01X+001279Y+008235X0198Y0197R090 S1      
317m0969            VIA   -    M      A01X+149700Y+078100X0200Y         S2      
017m0969            VIA   -    M      A18X+149700Y+078100X0260Y         S2      
017m0969                  -    MD0100PA00X+149700Y+078100                       
327m0969            R4696 -1          A01X+149942Y+078100X0198Y0197     S1      
327m0969            U345  -15         A01X+148202Y+077454X0160Y0540R270 S1      
327m0970            J30   -A10        A01X+004199Y+009524X0150Y0500R090 S1      
317m0970            VIA   -    M      A01X+001279Y+008790X0200Y         S2      
017m0970            VIA   -    M      A18X+001279Y+008790X0260Y         S2      
017m0970                  -    MD0100PA00X+001279Y+008790                       
327m0970            R5732 -2          A01X+001279Y+008550X0198Y0197R090 S1      
317m0971            VIA   -    M      A01X+149681Y+077300X0200Y         S2      
017m0971            VIA   -    M      A18X+149681Y+077300X0260Y         S2      
017m0971                  -    MD0100PA00X+149681Y+077300                       
327m0971            R4695 -1          A01X+149942Y+077300X0198Y0197     S1      
327m0971            U345  -14         A01X+148202Y+077198X0160Y0540R270 S1      
317SSD9_LED         VIA   -    M      A01X+086343Y+030937X0200Y         S2      
017SSD9_LED         VIA   -    M      A18X+086343Y+030937X0260Y         S2      
017SSD9_LED               -    MD0100PA00X+086343Y+030937                       
327SSD9_LED         R5763 -1          A01X+087240Y+030937X0198Y0197     S1      
327SSD9_LED         U330  -14         A01X+085599Y+031185X0160Y0540R270 S1      
327m0972            VIA   -    M      A18X+119043Y+088887X0260Y    R090 S2      
327m0972            R1868 -2          A18X+118743Y+088189X0198Y0197R270 S2      
327m0972            U309  -6          A18X+119043Y+089575X0140Y0520R180 S2      
317m0973            VIA   -    M      A01X+149524Y+082500X0200Y    R180 S2      
017m0973            VIA   -    M      A18X+149524Y+082500X0260Y    R180 S2      
017m0973                  -    MD0100PA00X+149524Y+082500                       
327m0973            R4633 -1          A01X+149942Y+082500X0198Y0197     S1      
327m0973            U343  -15         A01X+148202Y+081854X0160Y0540R270 S1      
317m0974            VIA   -    M      A01X+149681Y+081700X0200Y    R180 S2      
017m0974            VIA   -    M      A18X+149681Y+081700X0260Y    R180 S2      
017m0974                  -    MD0100PA00X+149681Y+081700                       
327m0974            U343  -14         A01X+148202Y+081598X0160Y0540R270 S1      
327m0974            R4632 -1          A01X+149942Y+081700X0198Y0197     S1      
317m0975            VIA   -    M      A01X+148000Y+073950X0200Y         S2      
017m0975            VIA   -    M      A18X+148000Y+073950X0260Y         S2      
017m0975                  -    MD0100PA00X+148000Y+073950                       
327m0975            R4652 -1          A01X+148242Y+073950X0198Y0197     S1      
327m0975            U344  -15         A01X+146502Y+073304X0160Y0540R270 S1      
317m0976            VIA   -    M      A01X+148000Y+073150X0200Y         S2      
017m0976            VIA   -    M      A18X+148000Y+073150X0260Y         S2      
017m0976                  -    MD0100PA00X+148000Y+073150                       
327m0976            U344  -14         A01X+146502Y+073048X0160Y0540R270 S1      
327m0976            R4651 -1          A01X+148242Y+073150X0198Y0197     S1      
317m0977            VIA   -    M      A01X+176899Y+010062X0200Y    R270 S2      
017m0977            VIA   -    M      A18X+176899Y+010062X0260Y    R270 S2      
017m0977                  -    MD0100PA00X+176899Y+010062                       
327m0977            R5749 -2          A01X+176451Y+010509X0198Y0197R270 S1      
327m0977            R5750 -1   M      A01X+176451Y+010062X0198Y0197R270 S1      
327m0977            U407  -D          A01X+177391Y+009926X0400Y0560R180 S1      
317m0978            VIA   -    M      A01X+166663Y+010062X0200Y    R270 S2      
017m0978            VIA   -    M      A18X+166663Y+010062X0260Y    R270 S2      
017m0978                  -    MD0100PA00X+166663Y+010062                       
327m0978            U406  -D          A01X+167155Y+009926X0400Y0560R180 S1      
327m0978            R5747 -2          A01X+166215Y+010509X0198Y0197R270 S1      
327m0978            R5748 -1   M      A01X+166215Y+010062X0198Y0197R270 S1      
327m0979            R772  -2   M      A01X+006766Y+108366X0198Y0197     S1      
327m0979            R768  -2          A01X+006766Y+108766X0198Y0197     S1      
317m0979            VIA   -    MD0100PA00X+007633Y+095342X0200Y         S0      
327m0979            U5    -A16        A01X+087979Y+083742X0160Y    R180 S1      
317m0979            VIA   -    MD0100PA00X+087822Y+083584X0180Y         S0      
317m0979            VIA   -    MD0100PA00X+087898Y+099402X0200Y         S0      
317m0979            VIA   -    MD0100PA00X+037010Y+095370X0200Y    R180 S0      
327m0979            R817  -2          A01X+037286Y+095581X0198Y0197R180 S1      
327m0979            R812  -2          A01X+037286Y+095181X0198Y0197R180 S1      
317m0979            VIA   -    MD0100PA00X+038061Y+078693X0200Y         S0      
317m0979            VIA   -    M      A01X+091675Y+109266X0200Y         S2      
017m0979            VIA   -    M      A18X+091675Y+109266X0260Y         S2      
017m0979                  -    MD0100PA00X+091675Y+109266                       
327m0979            R783  -2          A01X+091435Y+109266X0198Y0197     S1      
327m0979            R779  -2          A01X+091435Y+109666X0198Y0197     S1      
327m0979            R801  -2          A01X+182231Y+109714X0198Y0197     S1      
327m0979            R805  -2          A01X+182231Y+109314X0198Y0197     S1      
317m0979            VIA   -    MD0100PA00X+182471Y+109315X0200Y         S0      
317m0979            VIA   -    MD0100PA00X+098824Y+102397X0200Y         S0      
317m0979            VIA   -    MD0100PA00X+098073Y+109266X0200Y         S0      
327m0979            R795  -2          A01X+097833Y+109266X0198Y0197     S1      
327m0979            R790  -2          A01X+097833Y+109666X0198Y0197     S1      
327m0980            J45   -A10        A01X+172033Y+009524X0150Y0500R090 S1      
317m0980            VIA   -    M      A01X+176201Y+009748X0200Y    R090 S2      
017m0980            VIA   -    M      A18X+176201Y+009748X0260Y    R090 S2      
017m0980                  -    MD0100PA00X+176201Y+009748                       
327m0980            R5750 -2          A01X+176451Y+009748X0198Y0197R270 S1      
317m0980            VIA   -    MD0100PA00X+172433Y+009524X0200Y         S0      
327m0981            J44   -A10        A01X+161797Y+009524X0150Y0500R090 S1      
317m0981            VIA   -    M      A01X+165965Y+009748X0200Y    R090 S2      
017m0981            VIA   -    M      A18X+165965Y+009748X0260Y    R090 S2      
017m0981                  -    MD0100PA00X+165965Y+009748                       
327m0981            R5748 -2          A01X+166215Y+009748X0198Y0197R270 S1      
317m0981            VIA   -    MD0100PA00X+162197Y+009524X0200Y         S0      
327m0982            J42   -A10        A01X+141325Y+009524X0150Y0500R090 S1      
317m0982            VIA   -    M      A01X+145492Y+009748X0200Y    R090 S2      
017m0982            VIA   -    M      A18X+145492Y+009748X0260Y    R090 S2      
017m0982                  -    MD0100PA00X+145492Y+009748                       
327m0982            R5752 -2          A01X+145742Y+009748X0198Y0197R270 S1      
317m0982            VIA   -    MD0100PA00X+141725Y+009524X0200Y         S0      
327SSD12_LED_R      R4350 -2          A01X+088040Y+032137X0198Y0197R180 S1      
327SSD12_LED_R      R5766 -2          A01X+087555Y+032137X0198Y0197     S1      
317SSD12_LED_R      VIA   -    MD0100PA00X+087798Y+032137X0200Y         S0      
317SSD12_LED_R      VIA   -    MD0100PA00X+149429Y+037270X0200Y         S0      
317SSD12_LED_R      VIA   -    M      A01X+147057Y+010362X0200Y    R090 S2      
017SSD12_LED_R      VIA   -    M      A18X+147057Y+010362X0260Y    R090 S2      
017SSD12_LED_R            -    MD0100PA00X+147057Y+010362                       
327SSD12_LED_R      U408  -G          A01X+147057Y+010792X0400Y0560R180 S1      
317m0983            VIA   -    MD0100PA00X+010007Y+038198X0200Y         S0      
327m0983            R695  -2          A01X+035849Y+037957X0198Y0197R270 S1      
327m0983            R691  -2          A01X+036249Y+037957X0198Y0197R270 S1      
317m0983            VIA   -    MD0100PA00X+035849Y+037717X0200Y    R270 S0      
317m0983            VIA   -    MD0100PA00X+044832Y+037964X0200Y         S0      
317m0983            VIA   -    M      A01X+006768Y+060564X0200Y    R090 S2      
017m0983            VIA   -    M      A18X+006768Y+060564X0260Y    R090 S2      
017m0983                  -    MD0100PA00X+006768Y+060564                       
327m0983            R684  -2          A01X+007168Y+060280X0198Y0197R090 S1      
327m0983            R680  -2   M      A01X+006768Y+060280X0198Y0197R090 S1      
317m0983            VIA   -    MD0100PA00X+145821Y+040623X0200Y         S0      
317m0983            VIA   -    MD0100PA00X+175896Y+054304X0200Y         S0      
327m0983            R757  -2   M      A01X+143894Y+060280X0198Y0197R090 S1      
327m0983            R750  -2          A01X+144294Y+060280X0198Y0197R090 S1      
317m0983            VIA   -    MD0100PA00X+143894Y+060564X0200Y    R090 S0      
317m0983            VIA   -    MD0100PA00X+172975Y+037717X0200Y    R270 S0      
327m0983            R746  -2          A01X+173375Y+037957X0198Y0197R270 S1      
327m0983            R761  -2          A01X+172975Y+037957X0198Y0197R270 S1      
317m0983            VIA   -    MD0100PA00X+127444Y+037735X0200Y    R270 S0      
327m0983            R740  -2          A01X+127266Y+037957X0198Y0197R270 S1      
327m0983            R735  -2          A01X+127666Y+037957X0198Y0197R270 S1      
317m0983            VIA   -    MD0100PA00X+086409Y+038400X0200Y         S0      
327m0983            R717  -2          A01X+086309Y+038742X0198Y0197R270 S1      
327m0983            R713  -2          A01X+086309Y+038008X0198Y0197R090 S1      
317m0983            VIA   -    M      A01X+052477Y+060564X0200Y    R090 S2      
017m0983            VIA   -    M      A18X+052477Y+060564X0260Y    R090 S2      
017m0983                  -    MD0100PA00X+052477Y+060564                       
327m0983            R702  -2   M      A01X+052477Y+060280X0198Y0197R090 S1      
327m0983            R706  -2          A01X+052877Y+060280X0198Y0197R090 S1      
317m0983            VIA   -    MD0100PA00X+095453Y+066667X0200Y         S0      
317m0983            VIA   -    MD0100PA00X+088137Y+084529X0180Y    R270 S0      
317m0983            VIA   -    MD0100PA00X+092870Y+068026X0200Y         S0      
327m0983            U5    -D15        A01X+088294Y+084687X0160Y    R180 S1      
317m0983            VIA   -    MD0100PA00X+098186Y+060564X0200Y    R090 S0      
327m0983            R724  -2   M      A01X+098186Y+060280X0198Y0197R090 S1      
327m0983            R728  -2          A01X+098586Y+060280X0198Y0197R090 S1      
327m0984            J43   -A10        A01X+151561Y+009524X0150Y0500R090 S1      
317m0984            VIA   -    M      A01X+155729Y+009748X0200Y    R090 S2      
017m0984            VIA   -    M      A18X+155729Y+009748X0260Y    R090 S2      
017m0984                  -    MD0100PA00X+155729Y+009748                       
327m0984            R5754 -2          A01X+155979Y+009748X0198Y0197R270 S1      
317m0984            VIA   -    MD0100PA00X+151961Y+009524X0200Y         S0      
317m0985            VIA   -    MD0100PA00X+112419Y+018678X0200Y         S0      
327m0985            R607  -2          A01X+112143Y+018466X0198Y0197     S1      
327m0985            R603  -2          A01X+112143Y+018866X0198Y0197     S1      
317m0985            VIA   -    MD0100PA00X+087822Y+084529X0180Y    R270 S0      
327m0985            U5    -C16        A01X+087979Y+084372X0160Y    R180 S1      
327m0985            R596  -2          A01X+101907Y+018466X0198Y0197     S1      
327m0985            R592  -2          A01X+101907Y+018866X0198Y0197     S1      
317m0985            VIA   -    M      A01X+102183Y+018678X0200Y         S2      
017m0985            VIA   -    M      A18X+102183Y+018678X0260Y         S2      
017m0985                  -    MD0100PA00X+102183Y+018678                       
317m0985            VIA   -    MD0100PA00X+091645Y+016798X0200Y         S0      
327m0985            R614  -2          A01X+122379Y+018866X0198Y0197     S1      
327m0985            R618  -2          A01X+122379Y+018466X0198Y0197     S1      
317m0985            VIA   -    MD0100PA00X+122655Y+018678X0200Y         S0      
327m0985            R625  -2          A01X+132616Y+018866X0198Y0197     S1      
327m0985            R629  -2          A01X+132616Y+018466X0198Y0197     S1      
317m0985            VIA   -    MD0100PA00X+132891Y+018678X0200Y         S0      
327m0985            R636  -2          A01X+147616Y+018866X0198Y0197     S1      
327m0985            R642  -2          A01X+147616Y+018466X0198Y0197     S1      
317m0985            VIA   -    MD0100PA00X+147891Y+018678X0200Y         S0      
327m0985            R647  -2          A01X+157852Y+018866X0198Y0197     S1      
327m0985            R653  -2          A01X+157852Y+018466X0198Y0197     S1      
317m0985            VIA   -    MD0100PA00X+158128Y+018678X0200Y         S0      
327m0985            R658  -2          A01X+168088Y+018866X0198Y0197     S1      
327m0985            R662  -2          A01X+168088Y+018466X0198Y0197     S1      
317m0985            VIA   -    MD0100PA00X+168364Y+018678X0200Y         S0      
327m0985            R669  -2          A01X+178324Y+018866X0198Y0197     S1      
327m0985            R674  -2          A01X+178324Y+018466X0198Y0197     S1      
317m0985            VIA   -    MD0100PA00X+178600Y+018678X0200Y         S0      
317m0986            VIA   -    M      A01X+156427Y+010062X0200Y    R270 S2      
017m0986            VIA   -    M      A18X+156427Y+010062X0260Y    R270 S2      
017m0986                  -    MD0100PA00X+156427Y+010062                       
327m0986            U409  -D          A01X+156919Y+009926X0400Y0560R180 S1      
327m0986            R5753 -2          A01X+155979Y+010509X0198Y0197R270 S1      
327m0986            R5754 -1   M      A01X+155979Y+010062X0198Y0197R270 S1      
327SSD9_LED_R       R4347 -2          A01X+088040Y+030937X0198Y0197R180 S1      
327SSD9_LED_R       R5763 -2          A01X+087555Y+030937X0198Y0197     S1      
317SSD9_LED_R       VIA   -    MD0100PA00X+087798Y+030937X0200Y         S0      
317SSD9_LED_R       VIA   -    M      A01X+111584Y+010362X0200Y    R090 S2      
017SSD9_LED_R       VIA   -    M      A18X+111584Y+010362X0260Y    R090 S2      
017SSD9_LED_R             -    MD0100PA00X+111584Y+010362                       
327SSD9_LED_R       U413  -G          A01X+111584Y+010792X0400Y0560R180 S1      
317SSD9_LED_R       VIA   -    MD0100PA00X+118800Y+033199X0200Y         S0      
317m0987            VIA   -    M      A01X+146190Y+010062X0200Y    R270 S2      
017m0987            VIA   -    M      A18X+146190Y+010062X0260Y    R270 S2      
017m0987                  -    MD0100PA00X+146190Y+010062                       
327m0987            R5751 -2          A01X+145742Y+010509X0198Y0197R270 S1      
327m0987            R5752 -1   M      A01X+145742Y+010062X0198Y0197R270 S1      
327m0987            U408  -D          A01X+146683Y+009926X0400Y0560R180 S1      
327SSD8_LED_R       R4346 -2          A01X+088040Y+030537X0198Y0197R180 S1      
327SSD8_LED_R       R4268 -2          A01X+087555Y+030537X0198Y0197     S1      
317SSD8_LED_R       VIA   -    MD0100PA00X+087798Y+030537X0200Y         S0      
317SSD8_LED_R       VIA   -    M      A01X+101348Y+010362X0200Y    R090 S2      
017SSD8_LED_R       VIA   -    M      A18X+101348Y+010362X0260Y    R090 S2      
017SSD8_LED_R             -    MD0100PA00X+101348Y+010362                       
317SSD8_LED_R       VIA   -    MD0100PA00X+109348Y+031030X0200Y         S0      
327SSD8_LED_R       U412  -G          A01X+101348Y+010792X0400Y0560R180 S1      
317m0988            VIA   -    MD0100PA00X+089324Y+070466X0200Y         S0      
327m0988            R509  -2          A01X+010490Y+018466X0198Y0197     S1      
327m0988            R504  -2          A01X+010490Y+018866X0198Y0197     S1      
317m0988            VIA   -    MD0100PA00X+010765Y+018678X0200Y         S0      
327m0988            R520  -2          A01X+020726Y+018466X0198Y0197     S1      
327m0988            R515  -2          A01X+020726Y+018866X0198Y0197     S1      
317m0988            VIA   -    MD0100PA00X+021002Y+018678X0200Y         S0      
327m0988            R526  -2          A01X+030962Y+018866X0198Y0197     S1      
327m0988            R530  -2          A01X+030962Y+018466X0198Y0197     S1      
317m0988            VIA   -    MD0100PA00X+031238Y+018678X0200Y         S0      
327m0988            R537  -2          A01X+041198Y+018866X0198Y0197     S1      
327m0988            R541  -2          A01X+041198Y+018466X0198Y0197     S1      
317m0988            VIA   -    M      A01X+041474Y+018678X0200Y         S2      
017m0988            VIA   -    M      A18X+041474Y+018678X0260Y         S2      
017m0988                  -    MD0100PA00X+041474Y+018678                       
327m0988            R552  -2          A01X+056198Y+018466X0198Y0197     S1      
327m0988            R548  -2          A01X+056198Y+018866X0198Y0197     S1      
317m0988            VIA   -    MD0100PA00X+056474Y+018678X0200Y         S0      
327m0988            R565  -2          A01X+066435Y+018466X0198Y0197     S1      
327m0988            R559  -2          A01X+066435Y+018866X0198Y0197     S1      
317m0988            VIA   -    MD0100PA00X+066710Y+018678X0200Y         S0      
327m0988            R570  -2          A01X+076671Y+018866X0198Y0197     S1      
327m0988            R576  -2          A01X+076671Y+018466X0198Y0197     S1      
317m0988            VIA   -    MD0100PA00X+076946Y+018678X0200Y         S0      
327m0988            R587  -2          A01X+086907Y+018466X0198Y0197     S1      
327m0988            R581  -2          A01X+086907Y+018866X0198Y0197     S1      
317m0988            VIA   -    MD0100PA00X+087183Y+018678X0200Y         S0      
327m0988            U5    -D16        A01X+087979Y+084687X0160Y    R180 S1      
317m0988            VIA   -    MD0100PA00X+087822Y+084844X0180Y    R270 S0      
327SSD11_LED_R      R5765 -2          A01X+087555Y+031737X0198Y0197     S1      
327SSD11_LED_R      R4349 -2          A01X+088040Y+031737X0198Y0197R180 S1      
317SSD11_LED_R      VIA   -    MD0100PA00X+087798Y+031737X0200Y         S0      
317SSD11_LED_R      VIA   -    M      A01X+132057Y+010362X0200Y    R090 S2      
017SSD11_LED_R      VIA   -    M      A18X+132057Y+010362X0260Y    R090 S2      
017SSD11_LED_R            -    MD0100PA00X+132057Y+010362                       
327SSD11_LED_R      U411  -G          A01X+132057Y+010792X0400Y0560R180 S1      
317SSD11_LED_R      VIA   -    MD0100PA00X+138785Y+036671X0200Y         S0      
317m0989            VIA   -    M      A01X+120954Y+010062X0200Y    R270 S2      
017m0989            VIA   -    M      A18X+120954Y+010062X0260Y    R270 S2      
017m0989                  -    MD0100PA00X+120954Y+010062                       
327m0989            R5755 -2          A01X+120506Y+010509X0198Y0197R270 S1      
327m0989            R5756 -1   M      A01X+120506Y+010062X0198Y0197R270 S1      
327m0989            U410  -D          A01X+121446Y+009926X0400Y0560R180 S1      
327m0990            J2    -B6         A01X+090330Y+024331X0150Y0530R090 S1      
327m0990            R5779 -2          A01X+139054Y+080610X0198Y0197R270 S1      
317m0990            VIA   -    MD0100PA00X+139054Y+080368X0200Y         S0      
317m0990            VIA   -    MD0100PA00X+088592Y+028950X0200Y         S0      
317m0990            VIA   -    MD0100PA00X+089603Y+024331X0200Y         S0      
317m0990            VIA   -    M      A01X+144304Y+036365X0200Y         S2      
017m0990            VIA   -    M      A18X+144304Y+036365X0260Y         S2      
017m0990                  -    MD0100PA00X+144304Y+036365                       
317m0991            VIA   -    M      A01X+131190Y+010062X0200Y    R270 S2      
017m0991            VIA   -    M      A18X+131190Y+010062X0260Y    R270 S2      
017m0991                  -    MD0100PA00X+131190Y+010062                       
327m0991            U411  -D          A01X+131683Y+009926X0400Y0560R180 S1      
327m0991            R5757 -2          A01X+130742Y+010509X0198Y0197R270 S1      
327m0991            R5758 -1   M      A01X+130742Y+010062X0198Y0197R270 S1      
327SSD14_LED_R      R4352 -2          A01X+088040Y+032937X0198Y0197R180 S1      
327SSD14_LED_R      R5768 -2          A01X+087555Y+032937X0198Y0197     S1      
317SSD14_LED_R      VIA   -    MD0100PA00X+087798Y+032937X0200Y         S0      
317SSD14_LED_R      VIA   -    MD0100PA00X+163656Y+034307X0200Y         S0      
317SSD14_LED_R      VIA   -    M      A01X+167529Y+010362X0200Y    R090 S2      
017SSD14_LED_R      VIA   -    M      A18X+167529Y+010362X0260Y    R090 S2      
017SSD14_LED_R            -    MD0100PA00X+167529Y+010362                       
327SSD14_LED_R      U406  -G          A01X+167529Y+010792X0400Y0560R180 S1      
327m0992            J41   -A10        A01X+126325Y+009524X0150Y0500R090 S1      
317m0992            VIA   -    M      A01X+130492Y+009748X0200Y    R090 S2      
017m0992            VIA   -    M      A18X+130492Y+009748X0260Y    R090 S2      
017m0992                  -    MD0100PA00X+130492Y+009748                       
327m0992            R5758 -2          A01X+130742Y+009748X0198Y0197R270 S1      
317m0992            VIA   -    MD0100PA00X+126725Y+009524X0200Y         S0      
327SSD15_LED_R      R4353 -2          A01X+088040Y+033337X0198Y0197R180 S1      
327SSD15_LED_R      R5769 -2          A01X+087555Y+033337X0198Y0197     S1      
317SSD15_LED_R      VIA   -    MD0100PA00X+087798Y+033337X0200Y         S0      
317SSD15_LED_R      VIA   -    M      A01X+169118Y+035702X0200Y         S2      
017SSD15_LED_R      VIA   -    M      A18X+169118Y+035702X0260Y         S2      
017SSD15_LED_R            -    MD0100PA00X+169118Y+035702                       
317SSD15_LED_R      VIA   -    MD0100PA00X+177765Y+010362X0200Y    R090 S0      
327SSD15_LED_R      U407  -G          A01X+177765Y+010792X0400Y0560R180 S1      
327m0993            J40   -A10        A01X+116088Y+009524X0150Y0500R090 S1      
317m0993            VIA   -    MD0100PA00X+116488Y+009524X0200Y         S0      
317m0993            VIA   -    M      A01X+120256Y+009748X0200Y    R090 S2      
017m0993            VIA   -    M      A18X+120256Y+009748X0260Y    R090 S2      
017m0993                  -    MD0100PA00X+120256Y+009748                       
327m0993            R5756 -2          A01X+120506Y+009748X0198Y0197R270 S1      
327m0994            J2    -B5         A01X+090330Y+024094X0150Y0530R090 S1      
327m0994            R5778 -2          A01X+138634Y+080613X0198Y0197R270 S1      
317m0994            VIA   -    MD0100PA00X+138634Y+080370X0200Y         S0      
317m0994            VIA   -    MD0100PA00X+144591Y+036603X0200Y         S0      
317m0994            VIA   -    M      A01X+088606Y+028464X0200Y         S2      
017m0994            VIA   -    M      A18X+088606Y+028464X0260Y         S2      
017m0994                  -    MD0100PA00X+088606Y+028464                       
317m0994            VIA   -    MD0100PA00X+089138Y+024320X0200Y         S0      
317m0995            VIA   -    M      A01X+099784Y+009748X0200Y    R090 S2      
017m0995            VIA   -    M      A18X+099784Y+009748X0260Y    R090 S2      
017m0995                  -    MD0100PA00X+099784Y+009748                       
327m0995            R5760 -2          A01X+100034Y+009748X0198Y0197R270 S1      
317m0995            VIA   -    MD0100PA00X+096016Y+009524X0200Y         S0      
327m0995            J38   -A10        A01X+095616Y+009524X0150Y0500R090 S1      
327SSD13_LED_R      R4351 -2          A01X+088040Y+032537X0198Y0197R180 S1      
327SSD13_LED_R      R5767 -2          A01X+087555Y+032537X0198Y0197     S1      
317SSD13_LED_R      VIA   -    MD0100PA00X+087798Y+032537X0200Y         S0      
317SSD13_LED_R      VIA   -    M      A01X+157293Y+010362X0200Y    R090 S2      
017SSD13_LED_R      VIA   -    M      A18X+157293Y+010362X0260Y    R090 S2      
017SSD13_LED_R            -    MD0100PA00X+157293Y+010362                       
327SSD13_LED_R      U409  -G          A01X+157293Y+010792X0400Y0560R180 S1      
317SSD13_LED_R      VIA   -    MD0100PA00X+160597Y+034379X0200Y         S0      
317SSD8_LED_ISO_N   VIA   -    M      A01X+100482Y+010062X0200Y    R270 S2      
017SSD8_LED_ISO_N   VIA   -    M      A18X+100482Y+010062X0260Y    R270 S2      
017SSD8_LED_ISO_N         -    MD0100PA00X+100482Y+010062                       
327SSD8_LED_ISO_N   R5759 -2          A01X+100034Y+010509X0198Y0197R270 S1      
327SSD8_LED_ISO_N   R5760 -1   M      A01X+100034Y+010062X0198Y0197R270 S1      
327SSD8_LED_ISO_N   U412  -D          A01X+100974Y+009926X0400Y0560R180 S1      
317SSD9_LED_ISO_N   VIA   -    M      A01X+110718Y+010062X0200Y    R270 S2      
017SSD9_LED_ISO_N   VIA   -    M      A18X+110718Y+010062X0260Y    R270 S2      
017SSD9_LED_ISO_N         -    MD0100PA00X+110718Y+010062                       
327SSD9_LED_ISO_N   R5761 -2          A01X+110270Y+010509X0198Y0197R270 S1      
327SSD9_LED_ISO_N   R5762 -1   M      A01X+110270Y+010062X0198Y0197R270 S1      
327SSD9_LED_ISO_N   U413  -D          A01X+111210Y+009926X0400Y0560R180 S1      
327m0996            J39   -A10        A01X+105852Y+009524X0150Y0500R090 S1      
317m0996            VIA   -    M      A01X+110020Y+009748X0200Y    R090 S2      
017m0996            VIA   -    M      A18X+110020Y+009748X0260Y    R090 S2      
017m0996                  -    MD0100PA00X+110020Y+009748                       
327m0996            R5762 -2          A01X+110270Y+009748X0198Y0197R270 S1      
317m0996            VIA   -    MD0100PA00X+106252Y+009524X0200Y         S0      
327SSD10_LED_R      R5764 -2          A01X+087555Y+031337X0198Y0197     S1      
327SSD10_LED_R      R4348 -2          A01X+088040Y+031337X0198Y0197R180 S1      
317SSD10_LED_R      VIA   -    MD0100PA00X+087798Y+031337X0200Y         S0      
317SSD10_LED_R      VIA   -    M      A01X+121820Y+010362X0200Y    R090 S2      
017SSD10_LED_R      VIA   -    M      A18X+121820Y+010362X0260Y    R090 S2      
017SSD10_LED_R            -    MD0100PA00X+121820Y+010362                       
317SSD10_LED_R      VIA   -    MD0100PA00X+125600Y+034050X0200Y         S0      
327SSD10_LED_R      U410  -G          A01X+121820Y+010792X0400Y0560R180 S1      
327m0997            R5746 -2          A01X+085034Y+009748X0198Y0197R270 S1      
317m0997            VIA   -    M      A01X+084784Y+009748X0200Y    R090 S2      
017m0997            VIA   -    M      A18X+084784Y+009748X0260Y    R090 S2      
017m0997                  -    MD0100PA00X+084784Y+009748                       
327m0997            J37   -A10        A01X+080616Y+009524X0150Y0500R090 S1      
317m0997            VIA   -    MD0100PA00X+081016Y+009524X0200Y         S0      
327m0998            R5777 -2          A18X+138630Y+091792X0198Y0197R090 S2      
317m0998            VIA   -    M      A01X+138775Y+091263X0200Y         S2      
017m0998            VIA   -    M      A18X+138775Y+091263X0260Y         S2      
017m0998                  -    MD0100PA00X+138775Y+091263                       
317m0998            VIA   -    MD0100PA00X+136100Y+088656X0180Y         S0      
327m0998            U6    -E15        A01X+135942Y+088499X0160Y         S1      
317SSD7_LED_ISO_N   VIA   -    M      A01X+085482Y+010062X0200Y    R270 S2      
017SSD7_LED_ISO_N   VIA   -    M      A18X+085482Y+010062X0260Y    R270 S2      
017SSD7_LED_ISO_N         -    MD0100PA00X+085482Y+010062                       
327SSD7_LED_ISO_N   U405  -D          A01X+085974Y+009926X0400Y0560R180 S1      
327SSD7_LED_ISO_N   R5745 -2          A01X+085034Y+010509X0198Y0197R270 S1      
327SSD7_LED_ISO_N   R5746 -1   M      A01X+085034Y+010062X0198Y0197R270 S1      
327m0999            J36   -A10        A01X+070380Y+009524X0150Y0500R090 S1      
317m0999            VIA   -    M      A01X+074548Y+009748X0200Y    R090 S2      
017m0999            VIA   -    M      A18X+074548Y+009748X0260Y    R090 S2      
017m0999                  -    MD0100PA00X+074548Y+009748                       
327m0999            R5744 -2          A01X+074798Y+009748X0198Y0197R270 S1      
317m0999            VIA   -    MD0100PA00X+070780Y+009524X0200Y         S0      
327SSD6_LED_R       U404  -G          A01X+076112Y+010792X0400Y0560R180 S1      
317SSD6_LED_R       VIA   -    MD0100PA00X+076112Y+010362X0200Y    R090 S0      
327SSD6_LED_R       R4336 -2          A01X+080705Y+030937X0198Y0197     S1      
327SSD6_LED_R       R4308 -1          A01X+081190Y+030937X0198Y0197     S1      
317SSD6_LED_R       VIA   -    M      A01X+080947Y+031060X0200Y         S2      
017SSD6_LED_R       VIA   -    M      A18X+080947Y+031060X0260Y         S2      
017SSD6_LED_R             -    MD0100PA00X+080947Y+031060                       
317SSD6_LED_ISO_N   VIA   -    M      A01X+075246Y+010062X0200Y    R270 S2      
017SSD6_LED_ISO_N   VIA   -    M      A18X+075246Y+010062X0260Y    R270 S2      
017SSD6_LED_ISO_N         -    MD0100PA00X+075246Y+010062                       
327SSD6_LED_ISO_N   R5743 -2          A01X+074798Y+010509X0198Y0197R270 S1      
327SSD6_LED_ISO_N   R5744 -1   M      A01X+074798Y+010062X0198Y0197R270 S1      
327SSD6_LED_ISO_N   U404  -D          A01X+075738Y+009926X0400Y0560R180 S1      
327SSD3_LED_R       R4305 -1          A01X+081190Y+032137X0198Y0197     S1      
327SSD3_LED_R       R4333 -2          A01X+080705Y+032137X0198Y0197     S1      
317SSD3_LED_R       VIA   -    MD0100PA00X+080949Y+032137X0200Y         S0      
317SSD3_LED_R       VIA   -    M      A01X+051964Y+031435X0200Y         S2      
017SSD3_LED_R       VIA   -    M      A18X+051964Y+031435X0260Y         S2      
017SSD3_LED_R             -    MD0100PA00X+051964Y+031435                       
327SSD3_LED_R       U401  -G          A01X+040639Y+010792X0400Y0560R180 S1      
317SSD3_LED_R       VIA   -    MD0100PA00X+040639Y+010362X0200Y    R090 S0      
317SSD5_LED_R       VIA   -    M      A01X+065876Y+010362X0200Y    R090 S2      
017SSD5_LED_R       VIA   -    M      A18X+065876Y+010362X0260Y    R090 S2      
017SSD5_LED_R             -    MD0100PA00X+065876Y+010362                       
327SSD5_LED_R       U403  -G          A01X+065876Y+010792X0400Y0560R180 S1      
327SSD5_LED_R       R4307 -1          A01X+081190Y+031337X0198Y0197     S1      
327SSD5_LED_R       R4335 -2          A01X+080705Y+031337X0198Y0197     S1      
317SSD5_LED_R       VIA   -    MD0100PA00X+080949Y+031383X0200Y         S0      
317SSD5_LED_R       VIA   -    MD0100PA00X+071834Y+030527X0200Y         S0      
317SSD4_LED_R       VIA   -    MD0100PA00X+055639Y+010362X0200Y    R090 S0      
327SSD4_LED_R       U402  -G          A01X+055639Y+010792X0400Y0560R180 S1      
317SSD4_LED_R       VIA   -    MD0100PA00X+059290Y+030987X0200Y         S0      
327SSD4_LED_R       R4334 -2          A01X+080705Y+031737X0198Y0197     S1      
327SSD4_LED_R       R4306 -1          A01X+081190Y+031737X0198Y0197     S1      
317SSD4_LED_R       VIA   -    M      A01X+080949Y+031737X0200Y         S2      
017SSD4_LED_R       VIA   -    M      A18X+080949Y+031737X0260Y         S2      
017SSD4_LED_R             -    MD0100PA00X+080949Y+031737                       
327SSD7_LED_R       R4337 -2          A01X+080705Y+030537X0198Y0197     S1      
327SSD7_LED_R       R4309 -1          A01X+081190Y+030537X0198Y0197     S1      
317SSD7_LED_R       VIA   -    M      A01X+080949Y+030537X0200Y         S2      
017SSD7_LED_R       VIA   -    M      A18X+080949Y+030537X0260Y         S2      
017SSD7_LED_R             -    MD0100PA00X+080949Y+030537                       
317SSD7_LED_R       VIA   -    MD0100PA00X+087911Y+030237X0200Y         S0      
327SSD7_LED_R       U405  -G          A01X+086348Y+010792X0400Y0560R180 S1      
317SSD7_LED_R       VIA   -    MD0100PA00X+086348Y+010362X0200Y    R090 S0      
317SSD2_LED_R       VIA   -    MD0100PA00X+030403Y+010362X0200Y    R090 S0      
327SSD2_LED_R       R4332 -2          A01X+080705Y+032537X0198Y0197     S1      
327SSD2_LED_R       R4304 -1          A01X+081190Y+032537X0198Y0197     S1      
317SSD2_LED_R       VIA   -    M      A01X+080949Y+032537X0200Y         S2      
017SSD2_LED_R       VIA   -    M      A18X+080949Y+032537X0260Y         S2      
017SSD2_LED_R             -    MD0100PA00X+080949Y+032537                       
317SSD2_LED_R       VIA   -    MD0100PA00X+035938Y+029059X0200Y         S0      
327SSD2_LED_R       U400  -G          A01X+030403Y+010792X0400Y0560R180 S1      
317RST_FT4232_R_N   VIA   -    MD0100PA00X+147349Y+086135X0200Y         S0      
327RST_FT4232_R_N   R5774 -1          A18X+138267Y+081630X0198Y0197R270 S2      
317RST_FT4232_R_N   VIA   -    MD0100PA00X+138143Y+081229X0200Y         S0      
327RST_FT4232_R_N   R5775 -2          A01X+056026Y+077610X0198Y0197R270 S1      
317RST_FT4232_R_N   VIA   -    M      A01X+056320Y+073960X0200Y         S2      
017RST_FT4232_R_N   VIA   -    M      A18X+056320Y+073960X0260Y         S2      
017RST_FT4232_R_N         -    MD0100PA00X+056320Y+073960                       
327RST_FT4232_R_N   R5776 -2          A01X+152502Y+090345X0198Y0197R270 S1      
317RST_FT4232_R_N   VIA   -    MD0100PA00X+148034Y+091478X0200Y         S0      
317RST_FT4232_R_N   VIA   -    MD0100PA00X+174660Y+093510X0200Y         S0      
327RST_FT4232_R_N   R6601 -2          A01X+175412Y+093510X0198Y0197R180 S1      
317RST_FT4232_R_N   VIA   -    MD0100PA00X+046930Y+079950X0200Y         S0      
327RST_FT4232_R_N   R6622 -2          A01X+037847Y+079334X0198Y0197R090 S1      
317SSD0_LED_R       VIA   -    MD0100PA00X+000727Y+007098X0200Y         S0      
327SSD0_LED_R       R4302 -1          A01X+081190Y+033337X0198Y0197     S1      
327SSD0_LED_R       R4330 -2          A01X+080705Y+033337X0198Y0197     S1      
317SSD0_LED_R       VIA   -    MD0100PA00X+080949Y+033337X0200Y         S0      
317SSD0_LED_R       VIA   -    M      A01X+016450Y+030940X0200Y         S2      
017SSD0_LED_R       VIA   -    M      A18X+016450Y+030940X0260Y         S2      
017SSD0_LED_R             -    MD0100PA00X+016450Y+030940                       
327SSD0_LED_R       U398  -G          A01X+000727Y+006668X0400Y0560     S1      
317RST_FT4232_N     VIA   -    MD0100PA00X+137675Y+083617X0180Y         S0      
327RST_FT4232_N     VIA   -    M      A18X+138148Y+082542X0260Y         S2      
327RST_FT4232_N     R5774 -2          A18X+138267Y+081945X0198Y0197R270 S2      
327RST_FT4232_N     U6    -Y20        A01X+137517Y+083774X0160Y         S1      
317SSD1_LED_R       VIA   -    MD0100PA00X+020167Y+010362X0200Y    R090 S0      
327SSD1_LED_R       R4331 -2          A01X+080705Y+032937X0198Y0197     S1      
327SSD1_LED_R       R4303 -1          A01X+081190Y+032937X0198Y0197     S1      
317SSD1_LED_R       VIA   -    M      A01X+080946Y+033046X0200Y         S2      
017SSD1_LED_R       VIA   -    M      A18X+080946Y+033046X0260Y         S2      
017SSD1_LED_R             -    MD0100PA00X+080946Y+033046                       
317SSD1_LED_R       VIA   -    MD0100PA00X+025799Y+030799X0200Y         S0      
327SSD1_LED_R       U399  -G          A01X+020167Y+010792X0400Y0560R180 S1      
327m1000            VIA   -    M      A01X+021380Y+055460X0300Y         S1      
327m1000            R37   -1          A01X+022702Y+054970X0198Y0197     S1      
327m1000            J20   -A9         A01X+019938Y+055656X0140Y0480R270 S1      
327m1001            R291  -1          A18X+117274Y+043832X0198Y0197R180 S2      
317m1001            VIA   -    MD0100PA00X+116868Y+043832X0200Y         S0      
327m1001            R36   -1          A18X+022050Y+053642X0198Y0197R270 S2      
317m1001            VIA   -    MD0100PA00X+022550Y+053000X0200Y         S0      
327m1001            R87   -1          A18X+025857Y+043832X0198Y0197R180 S2      
317m1001            VIA   -    MD0100PA00X+071160Y+043832X0200Y         S0      
317m1001            VIA   -    M      A01X+071269Y+035678X0200Y         S2      
017m1001            VIA   -    M      A18X+071269Y+035678X0260Y         S2      
017m1001                  -    MD0100PA00X+071269Y+035678                       
327m1001            R189  -1   M      A18X+071566Y+043832X0198Y0197R180 S2      
317m1001            VIA   -    MD0100PA00X+025451Y+043832X0200Y         S0      
317m1001            VIA   -    MD0100PA00X+068259Y+053000X0200Y         S0      
317m1001            VIA   -    MD0100PA00X+083327Y+050668X0200Y         S0      
317m1001            VIA   -    MD0100PA00X+087914Y+063255X0200Y         S0      
317m1001            VIA   -    MD0100PA00X+088392Y+080082X0200Y    R090 S0      
327m1001            R5289 -1          A01X+088392Y+080332X0198Y0197R090 S1      
317m1001            VIA   -    MD0100PA00X+087465Y+054530X0200Y         S0      
317m1001            VIA   -    MD0100PA00X+113967Y+053000X0200Y         S0      
317m1001            VIA   -    MD0100PA00X+159676Y+053000X0200Y         S0      
327m1001            R342  -1          A18X+159176Y+053642X0198Y0197R270 S2      
327m1001            R240  -1          A18X+113467Y+053642X0198Y0197R270 S2      
317m1001            VIA   -    MD0100PA00X+100288Y+062252X0200Y         S0      
317m1001            VIA   -    MD0100PA00X+072436Y+050473X0200Y         S0      
327m1001            R138  -1          A18X+067759Y+053642X0198Y0197R270 S2      
327m1001            R393  -1          A18X+162983Y+043832X0198Y0197R180 S2      
317m1001            VIA   -    MD0100PA00X+162577Y+043832X0200Y         S0      
327PD_BIC_ENTEST    VIA   -    M      A01X+092243Y+082131X0300Y    R270 S1      
327PD_BIC_ENTEST    U5    -A3         A01X+092074Y+083742X0160Y    R180 S1      
327PD_BIC_ENTEST    R5712 -1          A01X+092179Y+081662X0198Y0197R270 S1      
317m1002            VIA   -    M      A01X+127440Y+091412X0200Y         S2      
017m1002            VIA   -    M      A18X+127440Y+091412X0260Y         S2      
017m1002                  -    MD0100PA00X+127440Y+091412                       
327m1002            R5647 -2          A01X+127186Y+091495X0198Y0197     S1      
317m1002            VIA   -    MD0100PA00X+135155Y+088656X0180Y         S0      
327m1002            U6    -E12        A01X+134998Y+088499X0160Y         S1      
327m1003            U6    -D12        A01X+134998Y+088814X0160Y         S1      
317m1003            VIA   -    MD0100PA00X+135155Y+088971X0180Y         S0      
317m1003            VIA   -    M      A01X+127467Y+091981X0200Y         S2      
017m1003            VIA   -    M      A18X+127467Y+091981X0260Y         S2      
017m1003                  -    MD0100PA00X+127467Y+091981                       
327m1003            R5646 -2          A01X+127186Y+091896X0198Y0197     S1      
317m1004            VIA   -    M      A01X+078111Y+159525X0200Y    R090 S2      
017m1004            VIA   -    M      A18X+078111Y+159525X0260Y    R090 S2      
017m1004                  -    MD0100PA00X+078111Y+159525                       
327m1004            R5714 -1          A01X+078111Y+159257X0198Y0197R270 S1      
327m1004            Q123  -3          A01X+078106Y+159826X0170Y0240     S1      
327HSC_P12V_EN      R494  -2          A18X+080619Y+142515X0198Y0197R180 S2      
317HSC_P12V_EN      VIA   -    MD0100PA00X+099860Y+137340X0200Y         S0      
327HSC_P12V_EN      PR7162-2          A18X+099378Y+137340X0198Y0197R180 S2      
327HSC_P12V_EN      R6600 -1          A01X+080642Y+143656X0198Y0197R180 S1      
317HSC_P12V_EN      VIA   -    MD0100PA00X+081210Y+142648X0200Y         S0      
327HSC_P12V_EN      R495  -1   M      A18X+080621Y+142914X0198Y0197     S2      
317HSC_P12V_EN      VIA   -    M      A01X+074053Y+152411X0300Y         S1      
017HSC_P12V_EN      VIA   -    M      A18X+074053Y+152411X0200Y         S1      
017HSC_P12V_EN            -    MD0100PA00X+074053Y+152411                       
317HSC_P12V_EN      VIA   -    MD0100PA00X+078112Y+158355X0200Y         S0      
327HSC_P12V_EN      R5714 -2   M      A01X+078111Y+158942X0198Y0197R270 S1      
327HSC_P12V_EN      C3990 -2          A01X+077703Y+158942X0198Y0197R270 S1      
317m1005            VIA   -    M      A01X+012025Y+075884X0200Y         S2      
017m1005            VIA   -    M      A18X+012025Y+075884X0260Y         S2      
017m1005                  -    MD0100PA00X+012025Y+075884                       
317m1005            VIA   -    MD0100PA00X+008829Y+102654X0200Y         S0      
327m1005            R5727 -2          A01X+009106Y+102838X0198Y0197R090 S1      
317m1005            VIA   -    MD0100PA00X+130975Y+087759X0200Y         S0      
327m1005            U6    -H2         A01X+131848Y+087554X0160Y         S1      
327m1006            R6414 -1          A18X+084384Y+084753X0198Y0197     S2      
327m1006            R5720 -2   M      A18X+084588Y+085146X0198Y0197R180 S2      
327m1006            VIA   -    M      A18X+087384Y+085558X0260Y         S2      
317m1006            VIA   -    MD0100PA00X+089397Y+085159X0180Y         S0      
327m1006            U5    -F11        A01X+089554Y+085317X0160Y    R180 S1      
327m1007            R6413 -1   M      A01X+084586Y+083156X0198Y0197R180 S1      
327m1007            VIA   -    M      A01X+086160Y+083690X0300Y         S1      
327m1007            R5719 -2          A01X+084588Y+083546X0198Y0197     S1      
327m1007            U5    -B16        A01X+087979Y+084057X0160Y    R180 S1      
327m1008            R6412 -1          A01X+085680Y+083147X0198Y0197R180 S1      
327m1008            VIA   -    M      A01X+086476Y+084093X0300Y         S1      
327m1008            R5718 -2   M      A01X+085683Y+083546X0198Y0197     S1      
327m1008            U5    -C15        A01X+088294Y+084372X0160Y    R180 S1      
327m1009            VIA   -    M      A18X+087517Y+085009X0260Y         S2      
317m1009            VIA   -    MD0100PA00X+089082Y+085159X0180Y         S0      
327m1009            R5716 -2          A18X+085683Y+084746X0198Y0197R180 S2      
327m1009            U5    -F12        A01X+089239Y+085317X0160Y    R180 S1      
327m1010            U6    -A21        A01X+137832Y+089759X0160Y         S1      
327m1010            R5912 -1   M      A01X+138835Y+092722X0198Y0197R270 S1      
317m1010            VIA   -    M      A01X+138278Y+093028X0200Y         S2      
017m1010            VIA   -    M      A18X+138278Y+093028X0260Y         S2      
017m1010                  -    MD0100PA00X+138278Y+093028                       
317m1010            VIA   -    MD0100PA00X+089134Y+099438X0200Y         S0      
317m1010            VIA   -    MD0100PA00X+088863Y+091804X0200Y         S0      
327m1010            R4556 -2          A18X+088729Y+091191X0198Y0197R270 S2      
327m1011            U340  -4          A01X+076728Y+160466X0220Y0530     S1      
317m1011            VIA   -    M      A01X+076836Y+161008X0200Y    R090 S2      
017m1011            VIA   -    M      A18X+076836Y+161008X0260Y    R090 S2      
017m1011                  -    MD0100PA00X+076836Y+161008                       
327m1011            R500  -2          A01X+076745Y+161377X0198Y0197R270 S1      
317HSC_ALERT1_R_N   VIA   -    M      A01X+099864Y+139827X0200Y         S2      
017HSC_ALERT1_R_N   VIA   -    M      A18X+099864Y+139827X0260Y         S2      
017HSC_ALERT1_R_N         -    MD0100PA00X+099864Y+139827                       
327HSC_ALERT1_R_N   PR7164-2          A18X+099375Y+139827X0198Y0197R180 S2      
317HSC_ALERT1_R_N   VIA   -    M      A01X+108400Y+152960X0200Y         S2      
017HSC_ALERT1_R_N   VIA   -    M      A18X+108400Y+152960X0260Y         S2      
017HSC_ALERT1_R_N         -    MD0100PA00X+108400Y+152960                       
327HSC_ALERT1_R_N   PR6618-2          A18X+108872Y+153726X0198Y0197     S2      
327HSC_ALERT1_R_N   PR7158-1   M      A18X+108872Y+153346X0198Y0197R180 S2      
317HSC_ALERT1_R_N   VIA   -    MD0100PA00X+078369Y+141098X0200Y         S0      
327HSC_ALERT1_R_N   R6248 -1          A18X+079927Y+146098X0198Y0197R180 S2      
317HSC_ALERT1_R_N   VIA   -    MD0100PA00X+079732Y+147124X0200Y         S0      
327HSC_ALERT1_R_N   U340  -2          A01X+076354Y+159501X0220Y0530     S1      
317HSC_ALERT1_R_N   VIA   -    M      A01X+076354Y+159019X0200Y         S2      
017HSC_ALERT1_R_N   VIA   -    M      A18X+076354Y+159019X0260Y         S2      
017HSC_ALERT1_R_N         -    MD0100PA00X+076354Y+159019                       
327RST_SMB_FPGA_N   VIA   -    M      A01X+088666Y+082572X0300Y    R270 S1      
327RST_SMB_FPGA_N   U5    -A13        A01X+088924Y+083742X0160Y    R180 S1      
327RST_SMB_FPGA_N   R5715 -2          A01X+088392Y+081662X0198Y0197R090 S1      
327m1012            R4358 -2          A01X+080705Y+033737X0198Y0197     S1      
327m1012            U330  -3   M      A01X+083296Y+033232X0160Y0540R270 S1      
317m1012            VIA   -    M      A01X+084544Y+035617X0200Y         S2      
017m1012            VIA   -    M      A18X+084544Y+035617X0260Y         S2      
017m1012                  -    MD0100PA00X+084544Y+035617                       
317m1012            VIA   -    MD0100PA00X+084822Y+082350X0200Y         S0      
327m1012            R5721 -1          A01X+085376Y+082747X0198Y0197     S1      
327m1012            R5524 -2   M      A01X+084922Y+082769X0198Y0197     S1      
327m1012            R5523 -2   M      A01X+084142Y+082746X0198Y0197     S1      
327m1013            J37   -A9         A01X+080616Y+009287X0150Y0500R090 S1      
317m1013            VIA   -    M      A01X+078468Y+012511X0200Y         S2      
017m1013            VIA   -    M      A18X+078468Y+012511X0260Y         S2      
017m1013                  -    MD0100PA00X+078468Y+012511                       
317m1013            VIA   -    MD0100PA00X+079501Y+009511X0200Y         S0      
327m1013            R5674 -1          A01X+078347Y+012775X0198Y0197R090 S1      
327m1014            VIA   -    M      A01X+086788Y+083696X0300Y         S1      
327m1014            R5721 -2          A01X+085691Y+082747X0198Y0197     S1      
327m1014            U5    -B15        A01X+088294Y+084057X0160Y    R180 S1      
317RST_SMB_SSD7_N   VIA   -    M      A01X+075752Y+014352X0200Y         S2      
017RST_SMB_SSD7_N   VIA   -    M      A18X+075752Y+014352X0260Y         S2      
017RST_SMB_SSD7_N         -    MD0100PA00X+075752Y+014352                       
327RST_SMB_SSD7_N   R5673 -2          A01X+075977Y+014577X0198Y0197     S1      
327RST_SMB_SSD7_N   U388  -2          A01X+077045Y+013970X0160Y0240R090 S1      
327m1015            J36   -A9         A01X+070380Y+009287X0150Y0500R090 S1      
317m1015            VIA   -    MD0100PA00X+069265Y+009511X0200Y         S0      
317m1015            VIA   -    M      A01X+068232Y+012511X0200Y         S2      
017m1015            VIA   -    M      A18X+068232Y+012511X0260Y         S2      
017m1015                  -    MD0100PA00X+068232Y+012511                       
327m1015            R5678 -1          A01X+068111Y+012775X0198Y0197R090 S1      
317m1016            VIA   -    MD0100PA00X+133265Y+085822X0180Y         S0      
327m1016            U6    -N7         A01X+133423Y+085979X0160Y         S1      
327m1016            R4741 -1          A01X+132458Y+067350X0198Y0197R180 S1      
327m1016            R4769 -2          A01X+132942Y+066950X0198Y0197R180 S1      
327m1016            R4726 -2   M      A01X+132458Y+066950X0198Y0197     S1      
317m1016            VIA   -    M      A01X+128490Y+067880X0200Y         S2      
017m1016            VIA   -    M      A18X+128490Y+067880X0260Y         S2      
017m1016                  -    MD0100PA00X+128490Y+067880                       
317m1017            VIA   -    M      A01X+143753Y+074840X0200Y    R180 S2      
017m1017            VIA   -    M      A18X+143753Y+074840X0260Y    R180 S2      
017m1017                  -    MD0100PA00X+143753Y+074840                       
327m1017            R4642 -1          A01X+142358Y+074900X0198Y0197R180 S1      
327m1017            U344  -4          A01X+144198Y+074840X0160Y0540R270 S1      
327m1018            C2796 -1          A18X+090402Y+055636X0198Y0197     S2      
327m1018            C2795 -1          A18X+090439Y+056463X0198Y0197R270 S2      
327m1018            C2794 -1          A18X+090852Y+056463X0198Y0197R270 S2      
327m1018            C2793 -1          A18X+090585Y+055186X0280Y0320R090 S2      
327m1018            L80   -2          A18X+090519Y+054586X0440Y0540     S2      
317m1018            VIA   -    M      A01X+090885Y+056012X0200Y    R090 S2      
017m1018            VIA   -    M      A18X+090885Y+056012X0260Y    R090 S2      
017m1018                  -    MD0100PA00X+090885Y+056012                       
327m1018            U117  -A12        A01X+090885Y+056404X0070Y0220R180 S1      
317m1018            VIA   -    M      A01X+087838Y+055494X0200Y         S2      
017m1018            VIA   -    M      A18X+087838Y+055494X0260Y         S2      
017m1018                  -    MD0100PA00X+087838Y+055494                       
327m1018            R4187 -1          A18X+087795Y+056046X0280Y0320     S2      
317m1019            VIA   -    M      A01X+149684Y+080900X0200Y    R180 S2      
017m1019            VIA   -    M      A18X+149684Y+080900X0260Y    R180 S2      
017m1019                  -    MD0100PA00X+149684Y+080900                       
327m1019            U343  -13         A01X+148202Y+081303X0240Y0540R270 S1      
327m1019            R4631 -1          A01X+149942Y+080900X0198Y0197     S1      
317m1020            VIA   -    MD0100PA00X+141350Y+085200X0200Y         S0      
327m1020            R4631 -2          A01X+150258Y+080900X0198Y0197     S1      
317m1020            VIA   -    M      A01X+148705Y+080941X0200Y         S2      
017m1020            VIA   -    M      A18X+148705Y+080941X0260Y         S2      
017m1020                  -    MD0100PA00X+148705Y+080941                       
327m1020            R4092 -1          A01X+141108Y+085200X0198Y0197R180 S1      
327m1021            VIA   -           A18X+089427Y+056504X0260Y         S2      
327m1021            VIA   -           A18X+089027Y+056504X0260Y         S2      
327m1021            U117  -B6         A01X+089999Y+056699X0110Y0180R180 S1      
317m1021            VIA   -    MD0100PA00X+089941Y+056002X0200Y    R090 S0      
327m1021            C2806 -1   M      A18X+089882Y+056463X0198Y0197R270 S2      
327m1021            C2805 -1          A18X+089495Y+055976X0280Y0320R180 S2      
327m1021            VIA   -           A18X+088352Y+055462X0260Y         S2      
327m1021            R4198 -2   M      A18X+088995Y+055976X0280Y0320     S2      
317m1022            VIA   -    M      A01X+144700Y+081850X0200Y    R180 S2      
017m1022            VIA   -    M      A18X+144700Y+081850X0260Y    R180 S2      
017m1022                  -    MD0100PA00X+144700Y+081850                       
327m1022            R4627 -1          A01X+144058Y+081850X0198Y0197R180 S1      
327m1022            U343  -8          A01X+145898Y+082366X0160Y0540R270 S1      
327m1023            VIA   -           A18X+087226Y+056253X0260Y         S2      
327m1023            VIA   -           A18X+087226Y+055853X0260Y         S2      
327m1023            C2797 -1          A18X+088295Y+056626X0280Y0320R180 S2      
327m1023            R4187 -2          A18X+087795Y+056626X0280Y0320     S2      
327m1023            VIA   -           A18X+087226Y+056653X0260Y         S2      
317m1023            VIA   -    MD0100PA00X+088742Y+056671X0200Y    R090 S0      
327m1023            C2798 -1          A18X+088648Y+057153X0198Y0197R180 S2      
327m1023            U117  -B1         A01X+089014Y+056699X0110Y0180R180 S1      
327m1024            VIA   -    M      A01X+088276Y+071385X0300Y         S1      
327m1024            R5495 -1          A01X+088369Y+072277X0198Y0197     S1      
327m1024            R5491 -2   M      A01X+088369Y+071857X0198Y0197R180 S1      
327m1024            U362  -4          A01X+087773Y+072206X0400Y0150     S1      
327m1024            Q58   -6   M      A01X+087780Y+071573X0170Y0240R270 S1      
327m1025            VIA   -    M      A18X+092787Y+082308X0260Y         S2      
317m1025            VIA   -    MD0100PA00X+092523Y+081693X0200Y         S0      
327m1025            U5    -C3         A01X+092074Y+084372X0160Y    R180 S1      
317m1025            VIA   -    MD0100PA00X+092231Y+084214X0180Y    R270 S0      
327m1025            R5480 -2          A01X+092792Y+080646X0198Y0197R090 S1      
327m1025            R5501 -2   M      A01X+092792Y+081146X0198Y0197R270 S1      
317m1026            VIA   -    M      A01X+144800Y+083450X0200Y    R180 S2      
017m1026            VIA   -    M      A18X+144800Y+083450X0260Y    R180 S2      
017m1026                  -    MD0100PA00X+144800Y+083450                       
327m1026            U343  -4          A01X+145898Y+083390X0160Y0540R270 S1      
327m1026            R4623 -1          A01X+144058Y+083450X0198Y0197R180 S1      
327RST_BIC_SRST_N   VIA   -    M      A01X+091933Y+068562X0300Y         S1      
327RST_BIC_SRST_N   U327  -4          A01X+092493Y+068724X0220Y0530R180 S1      
327RST_BIC_SRST_N   R4258 -1          A01X+092542Y+068094X0198Y0197R270 S1      
327RST_BIC_SRST_N   R4256 -1   M      A01X+092142Y+068094X0198Y0197R270 S1      
327m1027            R4091 -2          A01X+141108Y+084400X0198Y0197     S1      
327m1027            C4494 -1          A01X+051458Y+078623X0198Y0197R090 S1      
317m1027            VIA   -    MD0100PA00X+051355Y+077320X0200Y         S0      
327m1027            U441  -3   M      A01X+051464Y+077713X0140Y0440R180 S1      
317m1027            VIA   -    MD0100PA00X+141350Y+084400X0200Y         S0      
317m1027            VIA   -    M      A01X+050464Y+078914X0200Y         S2      
017m1027            VIA   -    M      A18X+050464Y+078914X0260Y         S2      
017m1027                  -    MD0100PA00X+050464Y+078914                       
327m1028            VIA   -    M      A18X+127337Y+119763X0260Y         S2      
327m1028            R4181 -1          A01X+128058Y+120344X0198Y0197R090 S1      
327m1028            R4182 -2          A01X+128057Y+119857X0198Y0197R090 S1      
317m1028            VIA   -    MD0100PA00X+128058Y+120097X0200Y         S0      
327m1028            PEX2  -L37        A01X+119390Y+121732X0180Y         S1      
317m1028            VIA   -    MD0080PA00X+119577Y+121545X0160Y         S0      
327m1029            R5480 -1          A01X+092792Y+080332X0198Y0197R090 S1      
317m1029            VIA   -    MD0100PA00X+092792Y+080091X0200Y    R090 S0      
317m1029            VIA   -    MD0100PA00X+090926Y+067780X0200Y         S0      
327m1029            R4256 -2          A01X+092142Y+067780X0198Y0197R270 S1      
317m1029            VIA   -    M      A01X+085944Y+067802X0200Y         S2      
017m1029            VIA   -    M      A18X+085944Y+067802X0260Y         S2      
017m1029                  -    MD0100PA00X+085944Y+067802                       
317m1029            VIA   -    MD0100PA00X+085799Y+072267X0200Y         S0      
327m1029            R5500 -1          A01X+086049Y+072267X0198Y0197     S1      
327REV_ID2          VIA   -    M      A01X+088415Y+089644X0300Y    R090 S1      
327REV_ID2          R4546 -1          A01X+086863Y+090951X0198Y0197R090 S1      
327REV_ID2          R4549 -2   M      A01X+086463Y+090951X0198Y0197R270 S1      
327REV_ID2          U5    -R12        A01X+089239Y+088151X0160Y    R180 S1      
327m1030            VIA   -    M      A01X+086501Y+072739X0300Y         S1      
327m1030            R5500 -2          A01X+086364Y+072267X0198Y0197     S1      
327m1030            U362  -2          A01X+087073Y+072462X0400Y0150     S1      
317m1031            VIA   -    M      A01X+129896Y+065961X0200Y         S2      
017m1031            VIA   -    M      A18X+129896Y+065961X0260Y         S2      
017m1031                  -    MD0100PA00X+129896Y+065961                       
327m1031            R4774 -2          A01X+132942Y+064950X0198Y0197R180 S1      
327m1031            R4733 -2   M      A01X+132458Y+064950X0198Y0197     S1      
317m1031            VIA   -    MD0100PA00X+132320Y+083932X0180Y         S0      
327m1031            U6    -W4         A01X+132478Y+084089X0160Y         S1      
317m1032            VIA   -    MD0100PA00X+164020Y+037469X0200Y         S0      
317m1032            VIA   -    MD0100PA00X+168641Y+033258X0200Y         S0      
327m1032            U46   -2          A01X+169153Y+033258X0220Y0530R090 S1      
317m1032            VIA   -    M      A01X+140784Y+041103X0200Y         S2      
017m1032            VIA   -    M      A18X+140784Y+041103X0260Y         S2      
017m1032                  -    MD0100PA00X+140784Y+041103                       
317m1032            VIA   -    MD0100PA00X+141350Y+085600X0200Y         S0      
327m1032            R4090 -1          A01X+141108Y+085600X0198Y0197R180 S1      
327REV_ID1          VIA   -    M      A01X+088665Y+090077X0300Y    R090 S1      
327REV_ID1          R4545 -1          A01X+087663Y+090951X0198Y0197R090 S1      
327REV_ID1          R4548 -2   M      A01X+087263Y+090951X0198Y0197R270 S1      
327REV_ID1          U5    -T12        A01X+089239Y+088466X0160Y    R180 S1      
317m1033            VIA   -    M      A01X+133929Y+056846X0200Y    R180 S2      
017m1033            VIA   -    M      A18X+133929Y+056846X0260Y    R180 S2      
017m1033                  -    MD0100PA00X+133929Y+056846                       
327m1033            R4835 -1          A01X+133258Y+056650X0198Y0197R180 S1      
327m1033            U350  -8          A01X+135098Y+057166X0160Y0540R270 S1      
317m1034            VIA   -    M      A01X+049071Y+085934X0200Y         S2      
017m1034            VIA   -    M      A18X+049071Y+085934X0260Y         S2      
017m1034                  -    MD0100PA00X+049071Y+085934                       
327m1034            PU6   -11         A01X+048494Y+101022X0070Y0240R090 S1      
327m1034            PR7131-2          A01X+050102Y+099677X0198Y0197R180 S1      
317m1034            VIA   -    M      A01X+049852Y+099759X0200Y         S2      
017m1034            VIA   -    M      A18X+049852Y+099759X0260Y         S2      
017m1034                  -    MD0100PA00X+049852Y+099759                       
317m1034            VIA   -    MD0100PA00X+083819Y+083696X0200Y         S0      
317m1034            VIA   -    MD0100PA00X+081244Y+086231X0200Y         S0      
327m1034            R5772 -2          A01X+084278Y+083929X0198Y0197R180 S1      
317m1035            VIA   -    M      A01X+134653Y+058190X0200Y    R180 S2      
017m1035            VIA   -    M      A18X+134653Y+058190X0260Y    R180 S2      
017m1035                  -    MD0100PA00X+134653Y+058190                       
327m1035            R4831 -1          A01X+133258Y+058250X0198Y0197R180 S1      
327m1035            U350  -4          A01X+135098Y+058190X0160Y0540R270 S1      
317m1036            VIA   -    M      A01X+132700Y+071650X0200Y         S2      
017m1036            VIA   -    M      A18X+132700Y+071650X0260Y         S2      
017m1036                  -    MD0100PA00X+132700Y+071650                       
327m1036            R4750 -2          A01X+132942Y+071650X0198Y0197R180 S1      
327m1036            R4739 -1          A01X+132458Y+072050X0198Y0197R180 S1      
327m1036            R4724 -2   M      A01X+132458Y+071650X0198Y0197     S1      
327m1036            U6    -U1         A01X+131533Y+084719X0160Y         S1      
317m1036            VIA   -    MD0100PA00X+131056Y+084868X0180Y         S0      
327m1037            PEX0  -L37        A01X+027972Y+121732X0180Y         S1      
317m1037            VIA   -    MD0080PA00X+028159Y+121545X0160Y         S0      
327m1037            VIA   -    M      A18X+035920Y+119763X0260Y         S2      
327m1037            R4179 -1          A01X+036640Y+120344X0198Y0197R090 S1      
327m1037            R4180 -2          A01X+036640Y+119857X0198Y0197R090 S1      
317m1037            VIA   -    MD0100PA00X+036640Y+120097X0200Y         S0      
317m1038            VIA   -    MD0100PA00X+131099Y+086686X0200Y         S0      
327m1038            R6197 -2          A18X+093263Y+092255X0198Y0197R090 S2      
327m1038            R4529 -2          A18X+093129Y+091191X0198Y0197R270 S2      
317m1038            VIA   -    MD0100PA00X+093263Y+091804X0200Y         S0      
317m1038            VIA   -    M      A01X+100119Y+085008X0200Y         S2      
017m1038            VIA   -    M      A18X+100119Y+085008X0260Y         S2      
017m1038                  -    MD0100PA00X+100119Y+085008                       
327m1038            U6    -L1         A01X+131533Y+086609X0160Y         S1      
327m1039            R4590 -2          A01X+149886Y+115293X0198Y0197R270 S1      
327m1039            C3554 -1          A01X+149259Y+115351X0280Y0320R090 S1      
317m1039            VIA   -           A01X+149618Y+115249X0200Y         S2      
017m1039            VIA   -           A18X+149618Y+115249X0260Y         S2      
017m1039                  -     D0100PA00X+149618Y+115249                       
327m1040            C3572 -1          A01X+150424Y+101037X0280Y0320R090 S1      
317m1040            VIA   -           A01X+150783Y+100935X0200Y         S2      
017m1040            VIA   -           A18X+150783Y+100935X0260Y         S2      
017m1040                  -     D0100PA00X+150783Y+100935                       
327m1040            R4593 -2          A01X+151051Y+100980X0198Y0197R270 S1      
327m1041            R4594 -2          A01X+149886Y+112773X0198Y0197R270 S1      
327m1041            C3583 -1          A01X+149259Y+112831X0280Y0320R090 S1      
317m1041            VIA   -           A01X+149618Y+112729X0200Y         S2      
017m1041            VIA   -           A18X+149618Y+112729X0260Y         S2      
017m1041                  -     D0100PA00X+149618Y+112729                       
327m1042            R4087 -2          A01X+141108Y+086000X0198Y0197     S1      
327m1042            C4495 -1          A01X+051976Y+078616X0198Y0197R090 S1      
317m1042            VIA   -    MD0100PA00X+052083Y+077339X0200Y         S0      
327m1042            U441  -1   M      A01X+051975Y+077713X0140Y0440R180 S1      
317m1042            VIA   -    MD0100PA00X+141350Y+086000X0200Y         S0      
317m1042            VIA   -    M      A01X+050451Y+078382X0200Y         S2      
017m1042            VIA   -    M      A18X+050451Y+078382X0260Y         S2      
017m1042                  -    MD0100PA00X+050451Y+078382                       
327m1043            R4592 -2          A01X+149886Y+114033X0198Y0197R270 S1      
327m1043            C3571 -1          A01X+149259Y+114091X0280Y0320R090 S1      
317m1043            VIA   -           A01X+149618Y+113989X0200Y         S2      
017m1043            VIA   -           A18X+149618Y+113989X0260Y         S2      
017m1043                  -     D0100PA00X+149618Y+113989                       
327m1044            VIA   -    M      A01X+082728Y+072126X0300Y         S1      
327m1044            U352  -4          A01X+082972Y+072718X0140Y0440R180 S1      
327m1044            R5300 -1          A01X+082728Y+071659X0198Y0197R270 S1      
327P1V8_PLL0_PEX3   R6585 -1          A01X+180836Y+097008X0198Y0197R090 S1      
327P1V8_PLL0_PEX3   R6594 -1          A01X+093625Y+089122X0198Y0197     S1      
317P1V8_PLL0_PEX3   VIA   -    M      A01X+152290Y+102126X0200Y         S2      
017P1V8_PLL0_PEX3   VIA   -    M      A18X+152290Y+102126X0260Y         S2      
017P1V8_PLL0_PEX3         -    MD0100PA00X+152290Y+102126                       
317P1V8_PLL0_PEX3   VIA   -           A01X+152681Y+102509X0200Y         S2      
017P1V8_PLL0_PEX3   VIA   -           A18X+152681Y+102509X0260Y         S2      
017P1V8_PLL0_PEX3         -     D0100PA00X+152681Y+102509                       
327P1V8_PLL0_PEX3   C3555 -1          A01X+148893Y+102986X0280Y0320R180 S1      
327P1V8_PLL0_PEX3   L139  -1          A01X+149788Y+102927X0440Y0540R180 S1      
327P1V8_PLL0_PEX3   C3556 -1          A01X+149334Y+102719X0120Y0150R270 S1      
327P1V8_PLL0_PEX3   U433  -2          A01X+180197Y+097359X0110Y0360R090 S1      
327P1V8_PLL0_PEX3   U433  -3          A01X+180197Y+097556X0110Y0360R090 S1      
327P1V8_PLL0_PEX3   U433  -1          A01X+180197Y+097162X0110Y0360R090 S1      
327P1V8_PLL0_PEX3   C4431 -1          A01X+180346Y+096456X0400Y0500     S1      
317P1V8_PLL0_PEX3   VIA   -    M      A01X+148727Y+100205X0200Y         S2      
017P1V8_PLL0_PEX3   VIA   -    M      A18X+148727Y+100205X0260Y         S2      
017P1V8_PLL0_PEX3         -    MD0100PA00X+148727Y+100205                       
317P1V8_PLL0_PEX3   VIA   -    M      A01X+149024Y+100482X0200Y         S2      
017P1V8_PLL0_PEX3   VIA   -    M      A18X+149024Y+100482X0260Y         S2      
017P1V8_PLL0_PEX3         -    MD0100PA00X+149024Y+100482                       
327P1V8_PLL0_PEX3   C3588 -1          A01X+147730Y+100976X0120Y0150     S1      
327P1V8_PLL0_PEX3   C3587 -1          A01X+147462Y+100535X0280Y0320R270 S1      
327P1V8_PLL0_PEX3   L145  -1          A01X+147522Y+101430X0440Y0540R270 S1      
317P1V8_PLL0_PEX3   VIA   -    MD0100PA00X+147506Y+100245X0200Y    R090 S0      
317P1V8_PLL0_PEX3   VIA   -    MD0100PA00X+147506Y+100830X0200Y    R090 S0      
327P1V8_PLL0_PEX3   L137  -1          A01X+148623Y+118501X0440Y0540R180 S1      
317P1V8_PLL0_PEX3   VIA   -    MD0100PA00X+148023Y+118516X0200Y         S0      
327P1V8_PLL0_PEX3   C3540 -1          A01X+148169Y+118293X0120Y0150R270 S1      
327P1V8_PLL0_PEX3   C3539 -1          A01X+147728Y+118560X0280Y0320R180 S1      
327P1V8_PLL0_PEX3   L138  -1          A01X+148623Y+115981X0440Y0540R180 S1      
327P1V8_PLL0_PEX3   C3542 -1          A01X+148169Y+115773X0120Y0150R270 S1      
327P1V8_PLL0_PEX3   C3541 -1          A01X+147728Y+116040X0280Y0320R180 S1      
327P1V8_PLL0_PEX3   L136  -1          A01X+148623Y+117241X0440Y0540R180 S1      
327P1V8_PLL0_PEX3   C3538 -1          A01X+148169Y+117033X0120Y0150R270 S1      
327P1V8_PLL0_PEX3   C3537 -1          A01X+147728Y+117300X0280Y0320R180 S1      
327P1V8_PLL0_PEX3   L140  -1          A01X+148623Y+114721X0440Y0540R180 S1      
327P1V8_PLL0_PEX3   C3558 -1          A01X+148169Y+114513X0120Y0150R270 S1      
327P1V8_PLL0_PEX3   C3557 -1          A01X+147728Y+114780X0280Y0320R180 S1      
327P1V8_PLL0_PEX3   L142  -1          A01X+148623Y+113461X0440Y0540R180 S1      
327P1V8_PLL0_PEX3   C3574 -1          A01X+148169Y+113253X0120Y0150R270 S1      
327P1V8_PLL0_PEX3   C3575 -1          A01X+147728Y+113520X0280Y0320R180 S1      
327P1V8_PLL0_PEX3   L143  -1          A01X+148623Y+112201X0440Y0540R180 S1      
327P1V8_PLL0_PEX3   C3560 -1          A01X+148169Y+111993X0120Y0150R270 S1      
327P1V8_PLL0_PEX3   C3573 -1          A01X+147728Y+112260X0280Y0320R180 S1      
327P1V8_PLL0_PEX3   C3585 -1          A01X+147728Y+111000X0280Y0320R180 S1      
327P1V8_PLL0_PEX3   L144  -1          A01X+148623Y+110941X0440Y0540R180 S1      
327P1V8_PLL0_PEX3   C3586 -1          A01X+148169Y+110733X0120Y0150R270 S1      
317P1V8_PLL0_PEX3   VIA   -    MD0100PA00X+147438Y+118516X0200Y         S0      
317P1V8_PLL0_PEX3   VIA   -    MD0100PA00X+148023Y+115996X0200Y         S0      
317P1V8_PLL0_PEX3   VIA   -    MD0100PA00X+147438Y+115996X0200Y         S0      
317P1V8_PLL0_PEX3   VIA   -    MD0100PA00X+148023Y+117256X0200Y         S0      
317P1V8_PLL0_PEX3   VIA   -    MD0100PA00X+147438Y+117256X0200Y         S0      
317P1V8_PLL0_PEX3   VIA   -    MD0100PA00X+148023Y+114736X0200Y         S0      
317P1V8_PLL0_PEX3   VIA   -    MD0100PA00X+147438Y+114736X0200Y         S0      
317P1V8_PLL0_PEX3   VIA   -    MD0100PA00X+148023Y+113476X0200Y         S0      
317P1V8_PLL0_PEX3   VIA   -    MD0100PA00X+147438Y+113476X0200Y         S0      
317P1V8_PLL0_PEX3   VIA   -    MD0100PA00X+148023Y+112216X0200Y         S0      
317P1V8_PLL0_PEX3   VIA   -    MD0100PA00X+147438Y+112216X0200Y         S0      
317P1V8_PLL0_PEX3   VIA   -    MD0100PA00X+148023Y+110956X0200Y         S0      
317P1V8_PLL0_PEX3   VIA   -    MD0100PA00X+147438Y+110956X0200Y         S0      
327P1V8_PLL0_PEX3   C3576 -1          A01X+149334Y+101459X0120Y0150R270 S1      
327P1V8_PLL0_PEX3   C3559 -1          A01X+148893Y+101726X0280Y0320R180 S1      
327P1V8_PLL0_PEX3   L141  -1          A01X+149788Y+101667X0440Y0540R180 S1      
317P1V8_PLL0_PEX3   VIA   -    M      A01X+149188Y+101683X0200Y         S2      
017P1V8_PLL0_PEX3   VIA   -    M      A18X+149188Y+101683X0260Y         S2      
017P1V8_PLL0_PEX3         -    MD0100PA00X+149188Y+101683                       
317P1V8_PLL0_PEX3   VIA   -    M      A01X+148603Y+101683X0200Y         S2      
017P1V8_PLL0_PEX3   VIA   -    M      A18X+148603Y+101683X0260Y         S2      
017P1V8_PLL0_PEX3         -    MD0100PA00X+148603Y+101683                       
317P1V8_PLL0_PEX3   VIA   -    MD0100PA00X+149188Y+102943X0200Y         S0      
317P1V8_PLL0_PEX3   VIA   -    MD0100PA00X+148603Y+102943X0200Y         S0      
317P1V8_PLL0_PEX3   VIA   -    MD0100PA00X+093230Y+089020X0200Y         S0      
317P1V8_PLL0_PEX3   VIA   -    MD0100PA00X+097950Y+090750X0200Y         S0      
317P1V8_PLL0_PEX3   VIA   -    MD0100PA00X+142070Y+095845X0200Y         S0      
327P1V8_PLL0_PEX3   C4432 -1          A18X+180164Y+096466X0198Y0197     S2      
317P1V8_PLL0_PEX3   VIA   -    MD0100PA00X+180766Y+096386X0200Y    R270 S0      
317P1V8_PLL0_PEX3   VIA   -    MD0100PA00X+180196Y+096916X0200Y    R270 S0      
317P1V8_PLL0_PEX3   VIA   -    MD0100PA00X+180546Y+096926X0200Y    R270 S0      
317P1V8_PLL0_PEX3   VIA   -    MD0100PA00X+180766Y+096666X0200Y    R270 S0      
317m1045            VIA   -    M      A01X+147979Y+070939X0200Y         S2      
017m1045            VIA   -    M      A18X+147979Y+070939X0260Y         S2      
017m1045                  -    MD0100PA00X+147979Y+070939                       
317m1045            VIA   -    MD0100PA00X+141350Y+086400X0200Y         S0      
327m1045            R4086 -1          A01X+141108Y+086400X0198Y0197R180 S1      
317m1045            VIA   -    MD0100PA00X+156887Y+068697X0200Y         S0      
327m1045            U41   -2          A01X+156887Y+068201X0220Y0530R180 S1      
327m1046            VIA   -    M      A01X+162738Y+062079X0300Y         S1      
327m1046            R2478 -1          A01X+162254Y+062079X0198Y0197R090 S1      
327m1046            J27   -A70        A01X+164156Y+062344X0140Y0480R090 S1      
327m1047            VIA   -    M      A01X+083628Y+072127X0300Y         S1      
327m1047            U352  -6          A01X+083484Y+072718X0140Y0440R180 S1      
327m1047            R5299 -1          A01X+083929Y+071657X0198Y0197R270 S1      
327m1048            R4596 -2          A01X+149886Y+110253X0198Y0197R270 S1      
327m1048            C3595 -1          A01X+149259Y+110311X0280Y0320R090 S1      
317m1048            VIA   -           A01X+149618Y+110209X0200Y         S2      
017m1048            VIA   -           A18X+149618Y+110209X0260Y         S2      
017m1048                  -     D0100PA00X+149618Y+110209                       
317m1049            VIA   -    M      A01X+145474Y+077249X0200Y    R180 S2      
017m1049            VIA   -    M      A18X+145474Y+077249X0260Y    R180 S2      
017m1049                  -    MD0100PA00X+145474Y+077249                       
327m1049            R4692 -1          A01X+144058Y+076650X0198Y0197R180 S1      
327m1049            U345  -10         A01X+145898Y+077454X0160Y0540R270 S1      
327m1050            VIA   -    M      A01X+084328Y+072126X0300Y         S1      
327m1050            U351  -4          A01X+084572Y+072718X0140Y0440R180 S1      
327m1050            R5298 -1          A01X+084328Y+071659X0198Y0197R270 S1      
327m1051            R4589 -2          A01X+149886Y+117813X0198Y0197R270 S1      
327m1051            C3553 -1          A01X+149259Y+117871X0280Y0320R090 S1      
317m1051            VIA   -           A01X+149618Y+117769X0200Y         S2      
017m1051            VIA   -           A18X+149618Y+117769X0260Y         S2      
017m1051                  -     D0100PA00X+149618Y+117769                       
317m1052            VIA   -    M      A01X+129872Y+079898X0200Y    R180 S2      
017m1052            VIA   -    M      A18X+129872Y+079898X0260Y    R180 S2      
017m1052                  -    MD0100PA00X+129872Y+079898                       
327m1052            OSC1  -1          A01X+129872Y+080276X0400Y0480R090 S1      
327m1052            R4404 -2          A01X+129864Y+079632X0198Y0197     S1      
327m1053            VIA   -    M      A01X+085228Y+072127X0300Y         S1      
327m1053            U351  -6          A01X+085084Y+072718X0140Y0440R180 S1      
327m1053            R5297 -1          A01X+085228Y+071659X0198Y0197R270 S1      
317m1054            VIA   -           A01X+148254Y+102425X0200Y    R090 S2      
017m1054            VIA   -           A18X+148254Y+102425X0260Y    R090 S2      
017m1054                  -     D0100PA00X+148254Y+102425                       
327m1054            R4597 -2          A01X+148209Y+102693X0198Y0197     S1      
327m1054            C3596 -1          A01X+148152Y+102066X0280Y0320R180 S1      
317m1055            VIA   -    M      A01X+144600Y+077050X0200Y    R180 S2      
017m1055            VIA   -    M      A18X+144600Y+077050X0260Y    R180 S2      
017m1055                  -    MD0100PA00X+144600Y+077050                       
327m1055            R4691 -1          A01X+144058Y+077050X0198Y0197R180 S1      
327m1055            U345  -9          A01X+145898Y+077710X0160Y0540R270 S1      
327m1056            R4588 -2          A01X+149886Y+116553X0198Y0197R270 S1      
327m1056            C3552 -1          A01X+149259Y+116611X0280Y0320R090 S1      
317m1056            VIA   -           A01X+149618Y+116509X0200Y         S2      
017m1056            VIA   -           A18X+149618Y+116509X0260Y         S2      
017m1056                  -     D0100PA00X+149618Y+116509                       
327m1057            R4595 -2          A01X+149886Y+111513X0198Y0197R270 S1      
327m1057            C3584 -1          A01X+149259Y+111571X0280Y0320R090 S1      
317m1057            VIA   -           A01X+149618Y+111469X0200Y         S2      
017m1057            VIA   -           A18X+149618Y+111469X0260Y         S2      
017m1057                  -     D0100PA00X+149618Y+111469                       
327m1058            PEX1  -L37        A01X+073681Y+121732X0180Y         S1      
317m1058            VIA   -    MD0080PA00X+073868Y+121545X0160Y         S0      
327m1058            VIA   -    M      A18X+081628Y+119763X0260Y         S2      
327m1058            R4178 -2          A01X+082349Y+119857X0198Y0197R090 S1      
327m1058            R4177 -1          A01X+082349Y+120344X0198Y0197R090 S1      
317m1058            VIA   -    MD0100PA00X+082349Y+120097X0200Y         S0      
327m1059            C3570 -1          A01X+150424Y+102297X0280Y0320R090 S1      
317m1059            VIA   -           A01X+150783Y+102195X0200Y         S2      
017m1059            VIA   -           A18X+150783Y+102195X0260Y         S2      
017m1059                  -     D0100PA00X+150783Y+102195                       
327m1059            R4591 -2          A01X+151051Y+102240X0198Y0197R270 S1      
317m1060            VIA   -    M      A01X+020468Y+038211X0200Y    R180 S2      
017m1060            VIA   -    M      A18X+020468Y+038211X0260Y    R180 S2      
017m1060                  -    MD0100PA00X+020468Y+038211                       
327m1060            J20   -A70        A01X+019938Y+038207X0140Y0480R270 S1      
327m1060            R2464 -1          A01X+024610Y+065382X0198Y0197R270 S1      
317m1060            VIA   -    MD0100PA00X+024610Y+065632X0200Y         S0      
317m1061            VIA   -    M      A01X+129669Y+083950X0200Y         S2      
017m1061            VIA   -    M      A18X+129669Y+083950X0260Y         S2      
017m1061                  -    MD0100PA00X+129669Y+083950                       
327m1061            R4154 -1          A01X+129108Y+083950X0198Y0197R180 S1      
317m1061            VIA   -    MD0100PA00X+132950Y+084877X0180Y         S0      
327m1061            U6    -T6         A01X+133108Y+085034X0160Y         S1      
327m1062            C3581 -1          A18X+155631Y+114813X0120Y0150     S2      
327m1062            C3582 -1          A18X+155935Y+114649X0120Y0150R090 S2      
317m1062            VIA   -    MD0080PA00X+155935Y+114813X0160Y         S0      
327m1062            PEX3  -AJ13       A01X+156122Y+115000X0180Y         S1      
317m1062            VIA   -    MD0100PA00X+149614Y+111769X0200Y         S0      
317m1062            VIA   -    M      A01X+150164Y+111769X0200Y         S2      
017m1062            VIA   -    M      A18X+150164Y+111769X0260Y         S2      
017m1062                  -    MD0100PA00X+150164Y+111769                       
327m1062            L143  -2          A01X+149371Y+112201X0440Y0540R180 S1      
327m1062            R4595 -1          A01X+149886Y+111828X0198Y0197R270 S1      
327m1062            C3580 -1          A01X+149941Y+112291X0280Y0320R270 S1      
327m1063            C3565 -1          A18X+155481Y+116245X0120Y0150     S2      
327m1063            C3566 -1   M      A18X+155481Y+115935X0120Y0150     S2      
317m1063            VIA   -    MD0080PA00X+155561Y+115935X0160Y         S0      
327m1063            PEX3  -AF12       A01X+155748Y+116122X0180Y         S1      
317m1063            VIA   -    M      A01X+150164Y+114289X0200Y         S2      
017m1063            VIA   -    M      A18X+150164Y+114289X0260Y         S2      
017m1063                  -    MD0100PA00X+150164Y+114289                       
317m1063            VIA   -    MD0100PA00X+149614Y+114289X0200Y         S0      
327m1063            L140  -2          A01X+149371Y+114721X0440Y0540R180 S1      
327m1063            R4592 -1          A01X+149886Y+114348X0198Y0197R270 S1      
327m1063            C3564 -1          A01X+149941Y+114811X0280Y0320R270 S1      
327m1064            C3562 -1          A18X+155935Y+116395X0120Y0150R090 S2      
327m1064            C3563 -1   M      A18X+155935Y+116683X0120Y0150R270 S2      
317m1064            VIA   -    MD0080PA00X+155935Y+116683X0160Y         S0      
327m1064            PEX3  -AE13       A01X+156122Y+116496X0180Y         S1      
327m1064            C3561 -1          A01X+151106Y+103017X0280Y0320R270 S1      
327m1064            L139  -2          A01X+150536Y+102927X0440Y0540R180 S1      
327m1064            R4591 -1          A01X+151051Y+102555X0198Y0197R270 S1      
317m1064            VIA   -    M      A01X+151329Y+102495X0200Y         S2      
017m1064            VIA   -    M      A18X+151329Y+102495X0260Y         S2      
017m1064                  -    MD0100PA00X+151329Y+102495                       
317m1064            VIA   -    MD0100PA00X+150779Y+102495X0200Y         S0      
327m1065            C3547 -1          A18X+155481Y+118180X0120Y0150     S2      
327m1065            C3548 -1   M      A18X+155481Y+117800X0120Y0150     S2      
317m1065            VIA   -    MD0080PA00X+155561Y+117805X0160Y    R270 S0      
327m1065            PEX3  -AB12       A01X+155748Y+117618X0180Y         S1      
317m1065            VIA   -    MD0100PA00X+149614Y+118069X0200Y         S0      
317m1065            VIA   -    M      A01X+150164Y+118069X0200Y         S2      
017m1065            VIA   -    M      A18X+150164Y+118069X0260Y         S2      
017m1065                  -    MD0100PA00X+150164Y+118069                       
327m1065            L137  -2          A01X+149371Y+118501X0440Y0540R180 S1      
327m1065            R4589 -1          A01X+149886Y+118128X0198Y0197R270 S1      
327m1065            C3546 -1          A01X+149941Y+118591X0280Y0320R270 S1      
317m1066            VIA   -    MD0100PA00X+092696Y+072380X0200Y         S0      
327m1066            VIA   -    M      A01X+092530Y+082566X0300Y    R270 S1      
327m1066            U5    -B3         A01X+092074Y+084057X0160Y    R180 S1      
327m1066            R5501 -1          A01X+092792Y+081462X0198Y0197R270 S1      
317m1066            VIA   -    MD0100PA00X+092792Y+081702X0200Y    R090 S0      
327m1066            R5494 -1          A01X+092506Y+071292X0198Y0197R270 S1      
327m1066            D12   -1   M      A01X+092696Y+072057X0320Y0340     S1      
327JTAG_BIC_EN_R    R4898 -1          A18X+088387Y+082042X0198Y0197R270 S2      
317JTAG_BIC_EN_R    VIA   -    MD0100PA00X+088400Y+079762X0200Y    R090 S0      
327JTAG_BIC_EN_R    R6411 -1          A18X+099200Y+078342X0198Y0197R270 S2      
317JTAG_BIC_EN_R    VIA   -    M      A01X+099070Y+077863X0200Y         S2      
017JTAG_BIC_EN_R    VIA   -    M      A18X+099070Y+077863X0280Y         S2      
017JTAG_BIC_EN_R          -    MD0100PA00X+099070Y+077863                       
327JTAG_BIC_EN_R    U294  -13         A01X+099326Y+080630X0140Y0590     S1      
327JTAG_BIC_EN_R    U294  -10         A01X+100094Y+080630X0140Y0590     S1      
327JTAG_BIC_EN_R    U294  -4          A01X+099838Y+078330X0140Y0590     S1      
327JTAG_BIC_EN_R    U294  -1   M      A01X+099070Y+078330X0140Y0590     S1      
327m1067            C3545 -1          A18X+155936Y+118035X0120Y0150R090 S2      
327m1067            C3544 -1          A18X+155936Y+118320X0120Y0150R270 S2      
317m1067            VIA   -    MD0080PA00X+155935Y+118179X0160Y    R270 S0      
327m1067            PEX3  -AA13       A01X+156122Y+117992X0180Y         S1      
327m1067            C3543 -1          A01X+149941Y+117331X0280Y0320R270 S1      
327m1067            R4588 -1          A01X+149886Y+116868X0198Y0197R270 S1      
317m1067            VIA   -    M      A01X+150164Y+116809X0200Y         S2      
017m1067            VIA   -    M      A18X+150164Y+116809X0260Y         S2      
017m1067                  -    MD0100PA00X+150164Y+116809                       
327m1067            L136  -2          A01X+149371Y+117241X0440Y0540R180 S1      
317m1067            VIA   -    MD0100PA00X+149614Y+116809X0200Y         S0      
317m1068            VIA   -    M      A01X+091246Y+068377X0200Y    R270 S2      
017m1068            VIA   -    M      A18X+091246Y+068377X0260Y    R270 S2      
017m1068                  -    MD0100PA00X+091246Y+068377                       
317m1068            VIA   -    MD0100PA00X+096395Y+073418X0200Y         S0      
327m1068            R3153 -1          A01X+096395Y+073161X0198Y0197R270 S1      
327m1068            R3149 -1          A01X+091004Y+068377X0198Y0197R180 S1      
327HP_NIC2_EN       PU50  -11         A01X+050524Y+048974X0110Y0240R090 S1      
317HP_NIC2_EN       VIA   -    M      A01X+050165Y+048216X0200Y    R180 S2      
017HP_NIC2_EN       VIA   -    M      A18X+050165Y+048216X0260Y    R180 S2      
017HP_NIC2_EN             -    MD0100PA00X+050165Y+048216                       
327HP_NIC2_EN       U19   -D          A01X+059392Y+045941X0400Y0560     S1      
327HP_NIC2_EN       R146  -2   M      A01X+060349Y+045538X0198Y0197R090 S1      
317HP_NIC2_EN       VIA   -    MD0100PA00X+060603Y+045592X0200Y         S0      
317HP_NIC2_EN       VIA   -    MD0100PA00X+051731Y+047004X0200Y    R180 S0      
327HP_NIC2_EN       C2881 -1          A01X+049847Y+047898X0198Y0197R180 S1      
317HP_NIC2_EN       VIA   -    MD0100PA00X+048290Y+052773X0200Y    R180 S0      
327HP_NIC2_EN       R4452 -1          A01X+048548Y+052773X0198Y0197     S1      
327HP_NIC2_EN       R5954 -1          A01X+051731Y+046763X0198Y0197R270 S1      
327HP_NIC2_EN       R946  -1          A01X+052178Y+063939X0198Y0197R270 S1      
317HP_NIC2_EN       VIA   -    MD0100PA00X+052178Y+064218X0200Y         S0      
317m1069            VIA   -    MD0080PA00X+028159Y+120049X0160Y         S0      
327m1069            PEX0  -T38        A01X+028346Y+119862X0180Y         S1      
317m1069            VIA   -    M      A01X+033519Y+117306X0200Y         S2      
017m1069            VIA   -    M      A18X+033519Y+117306X0260Y         S2      
017m1069                  -    MD0100PA00X+033519Y+117306                       
327m1069            R6388 -2          A01X+033676Y+113713X0198Y0197R270 S1      
327PECI_VDD         VIA   -    M      A18X+087825Y+086000X0260Y         S2      
327PECI_VDD         R4862 -2          A18X+084344Y+085540X0198Y0197R180 S2      
327PECI_VDD         C3621 -2   M      A18X+085683Y+085546X0198Y0197R180 S2      
327PECI_VDD         U5    -H13        A01X+088924Y+085946X0160Y    R180 S1      
317PECI_VDD         VIA   -    MD0100PA00X+088767Y+085789X0180Y    R270 S0      
327m1070            C3579 -1          A18X+155481Y+115561X0120Y0150     S2      
327m1070            C3578 -1   M      A18X+155481Y+115187X0120Y0150     S2      
317m1070            VIA   -    MD0080PA00X+155561Y+115187X0160Y         S0      
327m1070            PEX3  -AH12       A01X+155748Y+115374X0180Y         S1      
317m1070            VIA   -    MD0100PA00X+149614Y+113029X0200Y         S0      
317m1070            VIA   -    M      A01X+150164Y+113029X0200Y         S2      
017m1070            VIA   -    M      A18X+150164Y+113029X0260Y         S2      
017m1070                  -    MD0100PA00X+150164Y+113029                       
327m1070            L142  -2          A01X+149371Y+113461X0440Y0540R180 S1      
327m1070            R4594 -1          A01X+149886Y+113088X0198Y0197R270 S1      
327m1070            C3577 -1          A01X+149941Y+113551X0280Y0320R270 S1      
317m1071            VIA   -    MD0080PA00X+028533Y+120423X0160Y         S0      
327m1071            PEX0  -P39        A01X+028720Y+120610X0180Y         S1      
317m1071            VIA   -    M      A01X+034201Y+117610X0200Y         S2      
017m1071            VIA   -    M      A18X+034201Y+117610X0260Y         S2      
017m1071                  -    MD0100PA00X+034201Y+117610                       
327m1071            R6387 -2          A01X+034547Y+118505X0198Y0197R090 S1      
327m1072            C3568 -1          A18X+155935Y+115397X0120Y0150R090 S2      
327m1072            C3569 -1          A18X+155935Y+115695X0120Y0150R270 S2      
317m1072            VIA   -    MD0080PA00X+155935Y+115561X0160Y         S0      
327m1072            PEX3  -AG13       A01X+156122Y+115748X0180Y         S1      
327m1072            R4593 -1          A01X+151051Y+101295X0198Y0197R270 S1      
317m1072            VIA   -    MD0100PA00X+150779Y+101235X0200Y         S0      
317m1072            VIA   -    M      A01X+151329Y+101235X0200Y         S2      
017m1072            VIA   -    M      A18X+151329Y+101235X0260Y         S2      
017m1072                  -    MD0100PA00X+151329Y+101235                       
327m1072            L141  -2          A01X+150536Y+101667X0440Y0540R180 S1      
327m1072            C3567 -1          A01X+151106Y+101757X0280Y0320R270 S1      
327m1073            C3591 -1          A18X+155631Y+117431X0120Y0150     S2      
327m1073            PEX3  -AC13       A01X+156122Y+117244X0180Y         S1      
317m1073            VIA   -    MD0080PA00X+155935Y+117431X0160Y    R270 S0      
327m1073            C3590 -1   M      A18X+155935Y+117431X0120Y0150R090 S2      
327m1073            C3589 -1          A01X+149941Y+111031X0280Y0320R270 S1      
317m1073            VIA   -    M      A01X+150164Y+110509X0200Y         S2      
017m1073            VIA   -    M      A18X+150164Y+110509X0260Y         S2      
017m1073                  -    MD0100PA00X+150164Y+110509                       
327m1073            R4596 -1          A01X+149886Y+110568X0198Y0197R270 S1      
327m1073            L144  -2          A01X+149371Y+110941X0440Y0540R180 S1      
317m1073            VIA   -    MD0100PA00X+149614Y+110509X0200Y         S0      
327m1074            C3551 -1          A18X+155481Y+116683X0120Y0150     S2      
327m1074            C3550 -1   M      A18X+155481Y+117057X0120Y0150     S2      
317m1074            VIA   -    MD0080PA00X+155561Y+117057X0160Y         S0      
327m1074            PEX3  -AD12       A01X+155748Y+116870X0180Y         S1      
327m1074            C3549 -1          A01X+149941Y+116071X0280Y0320R270 S1      
327m1074            L138  -2          A01X+149371Y+115981X0440Y0540R180 S1      
327m1074            R4590 -1          A01X+149886Y+115608X0198Y0197R270 S1      
317m1074            VIA   -    M      A01X+150164Y+115549X0200Y         S2      
017m1074            VIA   -    M      A18X+150164Y+115549X0260Y         S2      
017m1074                  -    MD0100PA00X+150164Y+115549                       
317m1074            VIA   -    MD0100PA00X+149614Y+115549X0200Y         S0      
317ADM1085_IN       VIA   -    MD0100PA00X+088491Y+069028X0200Y         S0      
327ADM1085_IN       VIA   -           A01X+088184Y+068222X0300Y         S1      
327ADM1085_IN       R3146 -2   M      A01X+088184Y+069097X0198Y0197     S1      
327ADM1085_IN       U359  -3          A01X+088930Y+069156X0140Y0580R270 S1      
327ADM1085_IN       R3147 -1   M      A01X+088184Y+068697X0198Y0197R180 S1      
327ADM1085_IN       U450  -3          A18X+089103Y+069608X0110Y0200R270 S2      
327m1075            C3378 -1          A01X+103551Y+116611X0280Y0320R090 S1      
327m1075            R4578 -2          A01X+104178Y+116553X0198Y0197R270 S1      
317m1075            VIA   -           A01X+103910Y+116509X0200Y         S2      
017m1075            VIA   -           A18X+103910Y+116509X0260Y         S2      
017m1075                  -     D0100PA00X+103910Y+116509                       
327m1076            U313  -2          A01X+035813Y+116397X0170Y0460     S1      
317m1076            VIA   -    M      A01X+035795Y+116777X0200Y         S2      
017m1076            VIA   -    M      A18X+035795Y+116777X0260Y         S2      
017m1076                  -    MD0100PA00X+035795Y+116777                       
327m1076            R3886 -2          A01X+036228Y+117477X0198Y0197R270 S1      
327m1076            R4013 -2   M      A01X+035844Y+117411X0198Y0197R270 S1      
327m1076            R3874 -2   M      A01X+035782Y+117037X0198Y0197R180 S1      
327m1077            VIA   -    M      A18X+130405Y+087490X0260Y         S2      
327m1077            R4174 -2          A18X+129958Y+087580X0198Y0197R180 S2      
327m1077            U6    -H3         A01X+132163Y+087554X0160Y         S1      
317m1077            VIA   -    MD0100PA00X+132006Y+087711X0180Y         S0      
327m1078            R4586 -2          A01X+104178Y+110253X0198Y0197R270 S1      
327m1078            C3421 -1          A01X+103551Y+110311X0280Y0320R090 S1      
317m1078            VIA   -           A01X+103910Y+110209X0200Y         S2      
017m1078            VIA   -           A18X+103910Y+110209X0260Y         S2      
017m1078                  -     D0100PA00X+103910Y+110209                       
317m1079            VIA   -    M      A01X+143753Y+069928X0200Y    R180 S2      
017m1079            VIA   -    M      A18X+143753Y+069928X0260Y    R180 S2      
017m1079                  -    MD0100PA00X+143753Y+069928                       
327m1079            R4707 -1          A01X+142358Y+069700X0198Y0197R180 S1      
327m1079            U346  -6          A01X+144198Y+069928X0160Y0540R270 S1      
327m1080            C3379 -1          A01X+103551Y+117871X0280Y0320R090 S1      
327m1080            R4579 -2          A01X+104178Y+117813X0198Y0197R270 S1      
317m1080            VIA   -           A01X+103910Y+117769X0200Y         S2      
017m1080            VIA   -           A18X+103910Y+117769X0260Y         S2      
017m1080                  -     D0100PA00X+103910Y+117769                       
327m1081            U313  -3          A01X+035557Y+116397X0170Y0460     S1      
317m1081            VIA   -    M      A01X+035293Y+116777X0200Y         S2      
017m1081            VIA   -    M      A18X+035293Y+116777X0260Y         S2      
017m1081                  -    MD0100PA00X+035293Y+116777                       
327m1081            R3885 -2          A01X+035041Y+117509X0198Y0197R270 S1      
327m1081            R3873 -2   M      A01X+035393Y+117112X0198Y0197     S1      
327m1081            R4014 -2   M      A01X+035441Y+117509X0198Y0197R270 S1      
327m1082            VIA   -    M      A01X+130148Y+088178X0300Y         S1      
327m1082            U6    -G2         A01X+131848Y+087869X0160Y         S1      
327m1082            R4171 -2          A01X+129107Y+088178X0198Y0197     S1      
327THRESHOLD        U450  -5          A18X+089398Y+069411X0110Y0200R270 S2      
317THRESHOLD        VIA   -    M      A01X+090224Y+069433X0300Y         S1      
017THRESHOLD        VIA   -    M      A18X+090224Y+069433X0200Y         S1      
017THRESHOLD              -    MD0100PA00X+090224Y+069433                       
327THRESHOLD        U359  -5          A01X+089575Y+069412X0140Y0580R270 S1      
327THRESHOLD        C3647 -2          A01X+090689Y+069577X0198Y0197R180 S1      
327m1083            C3396 -1          A01X+104715Y+102297X0280Y0320R090 S1      
327m1083            R4581 -2          A01X+105342Y+102240X0198Y0197R270 S1      
317m1083            VIA   -           A01X+105074Y+102195X0200Y         S2      
017m1083            VIA   -           A18X+105074Y+102195X0260Y         S2      
017m1083                  -     D0100PA00X+105074Y+102195                       
317m1084            VIA   -    M      A01X+143305Y+070184X0200Y    R180 S2      
017m1084            VIA   -    M      A18X+143305Y+070184X0260Y    R180 S2      
017m1084                  -    MD0100PA00X+143305Y+070184                       
327m1084            R4706 -1          A01X+142358Y+070100X0198Y0197R180 S1      
327m1084            U346  -5          A01X+144198Y+070184X0160Y0540R270 S1      
327m1085            VIA   -    M      A18X+087582Y+084386X0260Y         S2      
317m1085            VIA   -    MD0100PA00X+088452Y+084529X0180Y         S0      
327m1085            R5770 -2          A18X+085683Y+083946X0198Y0197R180 S2      
327m1085            U5    -D14        A01X+088609Y+084687X0160Y    R180 S1      
317m1086            VIA   -           A01X+102457Y+102400X0200Y         S2      
017m1086            VIA   -           A18X+102457Y+102400X0260Y         S2      
017m1086                  -     D0100PA00X+102457Y+102400                       
327m1086            R4587 -2          A01X+102501Y+102693X0198Y0197     S1      
327m1086            C3422 -1          A01X+102443Y+102066X0280Y0320R180 S1      
317m1087            VIA   -    M      A01X+036622Y+118024X0200Y         S2      
017m1087            VIA   -    M      A18X+036622Y+118024X0260Y         S2      
017m1087                  -    MD0100PA00X+036622Y+118024                       
327m1087            R3881 -2          A01X+035976Y+118205X0198Y0197R270 S1      
327m1087            R3884 -2   M      A01X+036373Y+118209X0198Y0197R270 S1      
327m1087            R3886 -1          A01X+036228Y+117792X0198Y0197R270 S1      
317m1088            VIA   -    MD0100PA00X+138305Y+084247X0180Y         S0      
317m1088            VIA   -    MD0100PA00X+090863Y+091524X0200Y         S0      
317m1088            VIA   -    M      A01X+101315Y+075673X0200Y         S2      
017m1088            VIA   -    M      A18X+101315Y+075673X0260Y         S2      
017m1088                  -    MD0100PA00X+101315Y+075673                       
327m1088            R4537 -1          A01X+090730Y+091268X0198Y0197R270 S1      
327m1088            U6    -V22        A01X+138147Y+084404X0160Y         S1      
317m1089            VIA   -    MD0080PA00X+155935Y+121545X0160Y    R180 S0      
317m1089            VIA   -    M      A01X+147906Y+121817X0200Y    R315 S2      
017m1089            VIA   -    M      A18X+147906Y+121817X0260Y    R315 S2      
017m1089                  -    MD0100PA00X+147906Y+121817                       
327m1089            PEX3  -M13        A01X+156122Y+121358X0180Y         S1      
327m1089            R4363 -2          A01X+147701Y+121612X0198Y0197R045 S1      
327m1090            VIA   -    M      A18X+088040Y+083974X0260Y         S2      
317m1090            VIA   -    MD0100PA00X+089397Y+084844X0180Y         S0      
327m1090            R5722 -2          A18X+085683Y+083546X0198Y0197R180 S2      
327m1090            U5    -E11        A01X+089554Y+085002X0160Y    R180 S1      
317P1V8_PLL0_PEX2   VIA   -    MD0100PA00X+101730Y+118516X0200Y         S0      
317P1V8_PLL0_PEX2   VIA   -    M      A01X+102314Y+118486X0200Y         S2      
017P1V8_PLL0_PEX2   VIA   -    M      A18X+102314Y+118486X0260Y         S2      
017P1V8_PLL0_PEX2         -    MD0100PA00X+102314Y+118486                       
327P1V8_PLL0_PEX2   C3367 -1          A01X+102020Y+118560X0280Y0320R180 S1      
327P1V8_PLL0_PEX2   C3364 -1          A01X+102460Y+118293X0120Y0150R270 S1      
327P1V8_PLL0_PEX2   L121  -1          A01X+102915Y+118501X0440Y0540R180 S1      
327P1V8_PLL0_PEX2   R6579 -1          A01X+103372Y+093925X0198Y0197R090 S1      
327P1V8_PLL0_PEX2   R6593 -1          A01X+094052Y+089818X0198Y0197R270 S1      
327P1V8_PLL0_PEX2   C4426 -1          A01X+102882Y+093372X0400Y0500     S1      
327P1V8_PLL0_PEX2   U432  -1          A01X+102732Y+094078X0110Y0360R090 S1      
327P1V8_PLL0_PEX2   U432  -2          A01X+102732Y+094275X0110Y0360R090 S1      
327P1V8_PLL0_PEX2   U432  -3          A01X+102732Y+094472X0110Y0360R090 S1      
327P1V8_PLL0_PEX2   L126  -1          A01X+102915Y+113461X0440Y0540R180 S1      
327P1V8_PLL0_PEX2   C3402 -1          A01X+102460Y+113253X0120Y0150R270 S1      
327P1V8_PLL0_PEX2   C3365 -1          A01X+102020Y+113520X0280Y0320R180 S1      
327P1V8_PLL0_PEX2   L127  -1          A01X+102915Y+112201X0440Y0540R180 S1      
327P1V8_PLL0_PEX2   C3385 -1          A01X+102020Y+112260X0280Y0320R180 S1      
327P1V8_PLL0_PEX2   C3384 -1          A01X+102460Y+111993X0120Y0150R270 S1      
327P1V8_PLL0_PEX2   L122  -1          A01X+102915Y+115981X0440Y0540R180 S1      
327P1V8_PLL0_PEX2   C3386 -1          A01X+102460Y+115773X0120Y0150R270 S1      
327P1V8_PLL0_PEX2   C3411 -1          A01X+102020Y+116040X0280Y0320R180 S1      
327P1V8_PLL0_PEX2   L120  -1          A01X+102915Y+117241X0440Y0540R180 S1      
327P1V8_PLL0_PEX2   C3401 -1          A01X+102020Y+117300X0280Y0320R180 S1      
327P1V8_PLL0_PEX2   L124  -1          A01X+102915Y+114721X0440Y0540R180 S1      
327P1V8_PLL0_PEX2   C3381 -1          A01X+102020Y+114780X0280Y0320R180 S1      
327P1V8_PLL0_PEX2   C3382 -1          A01X+102460Y+114513X0120Y0150R270 S1      
317P1V8_PLL0_PEX2   VIA   -    MD0100PA00X+101730Y+117256X0200Y         S0      
317P1V8_PLL0_PEX2   VIA   -    MD0100PA00X+102316Y+117444X0200Y         S0      
317P1V8_PLL0_PEX2   VIA   -    MD0100PA00X+101730Y+115996X0200Y         S0      
317P1V8_PLL0_PEX2   VIA   -    MD0100PA00X+102314Y+115996X0200Y         S0      
317P1V8_PLL0_PEX2   VIA   -    MD0100PA00X+101730Y+114736X0200Y         S0      
317P1V8_PLL0_PEX2   VIA   -    MD0100PA00X+102314Y+114736X0200Y         S0      
317P1V8_PLL0_PEX2   VIA   -    MD0100PA00X+101730Y+113476X0200Y         S0      
317P1V8_PLL0_PEX2   VIA   -    MD0100PA00X+102314Y+113476X0200Y         S0      
317P1V8_PLL0_PEX2   VIA   -    MD0100PA00X+101730Y+112216X0200Y         S0      
317P1V8_PLL0_PEX2   VIA   -    MD0100PA00X+102314Y+112216X0200Y         S0      
327P1V8_PLL0_PEX2   C3383 -1          A01X+102020Y+111000X0280Y0320R180 S1      
327P1V8_PLL0_PEX2   L128  -1          A01X+102915Y+110941X0440Y0540R180 S1      
327P1V8_PLL0_PEX2   C3400 -1          A01X+102460Y+110733X0120Y0150R270 S1      
317P1V8_PLL0_PEX2   VIA   -    M      A01X+102314Y+110956X0200Y         S2      
017P1V8_PLL0_PEX2   VIA   -    M      A18X+102314Y+110956X0260Y         S2      
017P1V8_PLL0_PEX2         -    MD0100PA00X+102314Y+110956                       
317P1V8_PLL0_PEX2   VIA   -    MD0100PA00X+101730Y+110956X0200Y         S0      
327P1V8_PLL0_PEX2   C3412 -1          A01X+102029Y+103300X0120Y0150R090 S1      
327P1V8_PLL0_PEX2   C3363 -1          A01X+103184Y+102986X0280Y0320R180 S1      
327P1V8_PLL0_PEX2   L123  -1          A01X+104079Y+102927X0440Y0540R180 S1      
327P1V8_PLL0_PEX2   C3366 -1          A01X+103625Y+102719X0120Y0150R270 S1      
317P1V8_PLL0_PEX2   VIA   -    MD0100PA00X+103479Y+102943X0200Y         S0      
317P1V8_PLL0_PEX2   VIA   -    MD0100PA00X+102894Y+102943X0200Y         S0      
317P1V8_PLL0_PEX2   VIA   -    M      A01X+102514Y+103067X0200Y    R090 S2      
017P1V8_PLL0_PEX2   VIA   -    M      A18X+102514Y+103067X0260Y    R090 S2      
017P1V8_PLL0_PEX2         -    MD0100PA00X+102514Y+103067                       
327P1V8_PLL0_PEX2   C3399 -1          A01X+103184Y+101726X0280Y0320R180 S1      
327P1V8_PLL0_PEX2   C3368 -1          A01X+103625Y+101459X0120Y0150R270 S1      
327P1V8_PLL0_PEX2   L125  -1          A01X+104079Y+101667X0440Y0540R180 S1      
317P1V8_PLL0_PEX2   VIA   -    MD0100PA00X+103479Y+101683X0200Y         S0      
317P1V8_PLL0_PEX2   VIA   -    MD0100PA00X+102894Y+101683X0200Y         S0      
327P1V8_PLL0_PEX2   C3414 -1          A01X+102021Y+100976X0120Y0150     S1      
327P1V8_PLL0_PEX2   C3413 -1          A01X+101754Y+100535X0280Y0320R270 S1      
327P1V8_PLL0_PEX2   L129  -1          A01X+101813Y+101430X0440Y0540R270 S1      
317P1V8_PLL0_PEX2   VIA   -    MD0100PA00X+101520Y+100966X0200Y         S0      
317P1V8_PLL0_PEX2   VIA   -    MD0100PA00X+101800Y+100966X0200Y         S0      
317P1V8_PLL0_PEX2   VIA   -    MD0100PA00X+094159Y+090091X0200Y         S0      
317P1V8_PLL0_PEX2   VIA   -    MD0100PA00X+097144Y+093883X0200Y         S0      
317P1V8_PLL0_PEX2   VIA   -    MD0100PA00X+103082Y+093842X0200Y    R270 S0      
317P1V8_PLL0_PEX2   VIA   -    MD0100PA00X+102732Y+093832X0200Y    R270 S0      
327P1V8_PLL0_PEX2   C4427 -1          A18X+102699Y+093382X0198Y0197     S2      
317P1V8_PLL0_PEX2   VIA   -    MD0100PA00X+103302Y+093582X0200Y    R270 S0      
317P1V8_PLL0_PEX2   VIA   -    MD0100PA00X+103302Y+093302X0200Y    R270 S0      
317m1091            VIA   -    M      A01X+034812Y+118018X0200Y         S2      
017m1091            VIA   -    M      A18X+034812Y+118018X0260Y         S2      
017m1091                  -    MD0100PA00X+034812Y+118018                       
327m1091            R3885 -1          A01X+035041Y+117824X0198Y0197R270 S1      
327m1091            R3882 -2          A01X+035444Y+118206X0198Y0197R270 S1      
327m1091            R3883 -2   M      A01X+035044Y+118206X0198Y0197R270 S1      
317m1092            VIA   -    M      A01X+145453Y+078478X0200Y    R180 S2      
017m1092            VIA   -    M      A18X+145453Y+078478X0260Y    R180 S2      
017m1092                  -    MD0100PA00X+145453Y+078478                       
327m1092            U345  -6          A01X+145898Y+078478X0160Y0540R270 S1      
327m1092            R4688 -1          A01X+144058Y+078250X0198Y0197R180 S1      
327m1093            VIA   -           A01X+092982Y+070977X0300Y         S1      
327m1093            R5494 -2   M      A01X+092506Y+070977X0198Y0197R270 S1      
327m1093            Q56   -C          A01X+091520Y+070977X0320Y0360R090 S1      
327m1093            R5492 -2   M      A01X+092106Y+070977X0198Y0197R270 S1      
327m1094            C3409 -1          A01X+103551Y+112831X0280Y0320R090 S1      
327m1094            R4584 -2          A01X+104178Y+112773X0198Y0197R270 S1      
317m1094            VIA   -           A01X+103910Y+112729X0200Y         S2      
017m1094            VIA   -           A18X+103910Y+112729X0260Y         S2      
017m1094                  -     D0100PA00X+103910Y+112729                       
317m1095            VIA   -    MD0100PA00X+090484Y+091804X0200Y         S0      
317m1095            VIA   -    MD0100PA00X+102468Y+075648X0200Y         S0      
317m1095            VIA   -    M      A01X+104439Y+086121X0200Y         S2      
017m1095            VIA   -    M      A18X+104439Y+086121X0260Y         S2      
017m1095                  -    MD0100PA00X+104439Y+086121                       
327m1095            R4536 -1          A01X+090370Y+091268X0198Y0197R270 S1      
317m1095            VIA   -    MD0100PA00X+137045Y+085507X0180Y         S0      
327m1095            U6    -P18        A01X+136887Y+085664X0160Y         S1      
327m1096            C3410 -1          A01X+103551Y+111571X0280Y0320R090 S1      
327m1096            R4585 -2          A01X+104178Y+111513X0198Y0197R270 S1      
317m1096            VIA   -           A01X+103910Y+111469X0200Y         S2      
017m1096            VIA   -           A18X+103910Y+111469X0260Y         S2      
017m1096                  -     D0100PA00X+103910Y+111469                       
317m1097            VIA   -    M      A01X+145310Y+082650X0200Y    R180 S2      
017m1097            VIA   -    M      A18X+145310Y+082650X0260Y    R180 S2      
017m1097                  -    MD0100PA00X+145310Y+082650                       
327m1097            R4625 -1          A01X+144058Y+082650X0198Y0197R180 S1      
327m1097            U343  -6          A01X+145898Y+082878X0160Y0540R270 S1      
327m1098            C2624 -1   M      A01X+092707Y+038133X0198Y0197R090 S1      
327m1098            R5439 -1   M      A01X+092307Y+038133X0198Y0197R090 S1      
327m1098            U112  -17         A01X+092331Y+037275X0100Y0290R180 S1      
327m1098            R1009 -2   M      A01X+093107Y+038133X0198Y0197R270 S1      
317m1098            VIA   -    M      A01X+092995Y+037682X0200Y         S2      
017m1098            VIA   -    M      A18X+092995Y+037682X0260Y         S2      
017m1098                  -    MD0100PA00X+092995Y+037682                       
317m1098            VIA   -    MD0100PA00X+087216Y+035996X0200Y         S0      
317m1098            VIA   -    MD0100PA00X+084838Y+083546X0200Y         S0      
327m1098            R5722 -1          A18X+085368Y+083546X0198Y0197R180 S2      
327m1099            C3380 -1          A01X+103551Y+115351X0280Y0320R090 S1      
327m1099            R4580 -2          A01X+104178Y+115293X0198Y0197R270 S1      
317m1099            VIA   -           A01X+103910Y+115249X0200Y         S2      
017m1099            VIA   -           A18X+103910Y+115249X0260Y         S2      
017m1099                  -     D0100PA00X+103910Y+115249                       
327m1100            VIA   -    M      A18X+131464Y+087464X0260Y         S2      
327m1100            R4173 -2          A18X+129958Y+087180X0198Y0197R180 S2      
327m1100            U6    -H4         A01X+132478Y+087554X0160Y         S1      
317m1100            VIA   -    MD0100PA00X+132320Y+087711X0180Y         S0      
327SGPIO_BIC_DOUT   VIA   -    M      A18X+088175Y+083309X0260Y         S2      
327SGPIO_BIC_DOUT   U5    -D12        A01X+089239Y+084687X0160Y    R180 S1      
317SGPIO_BIC_DOUT   VIA   -    MD0100PA00X+089082Y+084529X0180Y    R270 S0      
327SGPIO_BIC_DOUT   R5528 -2   M      A18X+087592Y+081662X0198Y0197R270 S2      
327SGPIO_BIC_DOUT   R5527 -2          A18X+087592Y+080646X0198Y0197R270 S2      
327m1101            C3398 -1          A01X+104715Y+101037X0280Y0320R090 S1      
327m1101            R4583 -2          A01X+105342Y+100980X0198Y0197R270 S1      
317m1101            VIA   -           A01X+105074Y+100935X0200Y         S2      
017m1101            VIA   -           A18X+105074Y+100935X0260Y         S2      
017m1101                  -     D0100PA00X+105074Y+100935                       
317m1102            VIA   -    M      A01X+145454Y+083134X0200Y    R180 S2      
017m1102            VIA   -    M      A18X+145454Y+083134X0260Y    R180 S2      
017m1102                  -    MD0100PA00X+145454Y+083134                       
327m1102            R4624 -1          A01X+144058Y+083050X0198Y0197R180 S1      
327m1102            U343  -5          A01X+145898Y+083134X0160Y0540R270 S1      
317m1103            VIA   -    M      A01X+145025Y+078734X0200Y    R180 S2      
017m1103            VIA   -    M      A18X+145025Y+078734X0260Y    R180 S2      
017m1103                  -    MD0100PA00X+145025Y+078734                       
327m1103            U345  -5          A01X+145898Y+078734X0160Y0540R270 S1      
327m1103            R4687 -1          A01X+144058Y+078650X0198Y0197R180 S1      
317m1104            VIA   -    M      A01X+066176Y+038211X0200Y    R180 S2      
017m1104            VIA   -    M      A18X+066176Y+038211X0260Y    R180 S2      
017m1104                  -    MD0100PA00X+066176Y+038211                       
327m1104            J22   -A70        A01X+065647Y+038207X0140Y0480R270 S1      
327m1104            R2466 -1          A01X+070319Y+065382X0198Y0197R270 S1      
317m1104            VIA   -    MD0100PA00X+070539Y+065579X0200Y         S0      
317m1105            VIA   -    MD0080PA00X+110226Y+121545X0160Y    R180 S0      
317m1105            VIA   -    M      A01X+102198Y+121817X0200Y    R315 S2      
017m1105            VIA   -    M      A18X+102198Y+121817X0260Y    R315 S2      
017m1105                  -    MD0100PA00X+102198Y+121817                       
327m1105            PEX2  -M13        A01X+110413Y+121358X0180Y         S1      
327m1105            R4362 -2          A01X+101993Y+121612X0198Y0197R045 S1      
327m1106            C3397 -1          A01X+103551Y+114091X0280Y0320R090 S1      
327m1106            R4582 -2          A01X+104178Y+114033X0198Y0197R270 S1      
317m1106            VIA   -           A01X+103910Y+113989X0200Y         S2      
017m1106            VIA   -           A18X+103910Y+113989X0260Y         S2      
017m1106                  -     D0100PA00X+103910Y+113989                       
327m1107            PEX0  -AV29       A01X+024980Y+111634X0180Y         S1      
317m1107            VIA   -    MD0080PA00X+025167Y+111821X0160Y         S0      
317m1107            VIA   -    MD0100PA00X+141802Y+076534X0200Y         S0      
327m1107            R4617 -1          A01X+141560Y+076534X0198Y0197R180 S1      
317m1107            VIA   -    MD0100PA00X+011910Y+075505X0200Y         S0      
317m1107            VIA   -    M      A01X+015584Y+099786X0200Y         S2      
017m1107            VIA   -    M      A18X+015584Y+099786X0260Y         S2      
017m1107                  -    MD0100PA00X+015584Y+099786                       
327m1107            R3954 -1          A01X+015584Y+099511X0198Y0197R270 S1      
327SGPIO_BIC_CLK    VIA   -    M      A01X+087919Y+082136X0300Y    R270 S1      
327SGPIO_BIC_CLK    U5    -B14        A01X+088609Y+084057X0160Y    R180 S1      
327SGPIO_BIC_CLK    R5536 -2          A01X+087592Y+080646X0198Y0197R090 S1      
327SGPIO_BIC_CLK    R5537 -2   M      A01X+087592Y+081346X0198Y0197R270 S1      
327m1108            C3394 -1          A18X+110226Y+115397X0120Y0150R090 S2      
327m1108            C3395 -1          A18X+110226Y+115695X0120Y0150R270 S2      
317m1108            VIA   -    MD0080PA00X+110226Y+115561X0160Y         S0      
327m1108            PEX2  -AG13       A01X+110413Y+115748X0180Y         S1      
327m1108            L125  -2          A01X+104827Y+101667X0440Y0540R180 S1      
327m1108            R4583 -1          A01X+105342Y+101295X0198Y0197R270 S1      
327m1108            C3393 -1          A01X+105397Y+101757X0280Y0320R270 S1      
317m1108            VIA   -    M      A01X+105620Y+101235X0200Y         S2      
017m1108            VIA   -    M      A18X+105620Y+101235X0260Y         S2      
017m1108                  -    MD0100PA00X+105620Y+101235                       
317m1108            VIA   -    MD0100PA00X+105070Y+101235X0200Y         S0      
327m1109            VIA   -    M      A01X+129576Y+087778X0300Y         S1      
327m1109            U6    -G1         A01X+131533Y+087869X0160Y         S1      
327m1109            R4172 -2          A01X+129107Y+087778X0198Y0197     S1      
327m1110            C3376 -1          A18X+109772Y+116683X0120Y0150     S2      
327m1110            C3377 -1   M      A18X+109772Y+117057X0120Y0150     S2      
317m1110            VIA   -    MD0080PA00X+109852Y+117057X0160Y         S0      
327m1110            PEX2  -AD12       A01X+110039Y+116870X0180Y         S1      
317m1110            VIA   -    M      A01X+104455Y+115549X0200Y         S2      
017m1110            VIA   -    M      A18X+104455Y+115549X0260Y         S2      
017m1110                  -    MD0100PA00X+104455Y+115549                       
317m1110            VIA   -    MD0100PA00X+103905Y+115549X0200Y         S0      
327m1110            R4580 -1          A01X+104178Y+115608X0198Y0197R270 S1      
327m1110            C3375 -1          A01X+104233Y+116071X0280Y0320R270 S1      
327m1110            L122  -2          A01X+103663Y+115981X0440Y0540R180 S1      
317m1111            VIA   -    MD0080PA00X+025167Y+121171X0160Y    R270 S0      
327m1111            PEX0  -M29        A01X+024980Y+121358X0180Y         S1      
317m1111            VIA   -    M      A01X+036643Y+118524X0200Y         S2      
017m1111            VIA   -    M      A18X+036643Y+118524X0260Y         S2      
017m1111                  -    MD0100PA00X+036643Y+118524                       
327m1111            R3884 -1          A01X+036373Y+118524X0198Y0197R270 S1      
327m1112            C3407 -1          A18X+109922Y+114813X0120Y0150     S2      
327m1112            C3408 -1          A18X+110226Y+114649X0120Y0150R090 S2      
317m1112            VIA   -    MD0080PA00X+110226Y+114813X0160Y         S0      
327m1112            PEX2  -AJ13       A01X+110413Y+115000X0180Y         S1      
317m1112            VIA   -    M      A01X+104455Y+111769X0200Y         S2      
017m1112            VIA   -    M      A18X+104455Y+111769X0260Y         S2      
017m1112                  -    MD0100PA00X+104455Y+111769                       
317m1112            VIA   -    MD0100PA00X+103905Y+111769X0200Y         S0      
327m1112            R4585 -1          A01X+104178Y+111828X0198Y0197R270 S1      
327m1112            C3406 -1          A01X+104233Y+112291X0280Y0320R270 S1      
327m1112            L127  -2          A01X+103663Y+112201X0440Y0540R180 S1      
317m1113            VIA   -    MD0080PA00X+024793Y+121171X0160Y    R270 S0      
327m1113            R3883 -1          A01X+035044Y+118520X0198Y0197R270 S1      
317m1113            VIA   -    M      A01X+034843Y+118722X0200Y         S2      
017m1113            VIA   -    M      A18X+034843Y+118722X0260Y         S2      
017m1113                  -    MD0100PA00X+034843Y+118722                       
327m1113            PEX0  -M28        A01X+024606Y+121358X0180Y         S1      
327HP_NIC6_EN       PU51  -11         A01X+141941Y+048974X0110Y0240R090 S1      
317HP_NIC6_EN       VIA   -    M      A01X+141582Y+048216X0200Y    R180 S2      
017HP_NIC6_EN       VIA   -    M      A18X+141582Y+048216X0260Y    R180 S2      
017HP_NIC6_EN             -    MD0100PA00X+141582Y+048216                       
327HP_NIC6_EN       U39   -D          A01X+150810Y+045941X0400Y0560     S1      
327HP_NIC6_EN       R350  -2   M      A01X+151766Y+045538X0198Y0197R090 S1      
317HP_NIC6_EN       VIA   -    MD0100PA00X+152020Y+045592X0200Y         S0      
317HP_NIC6_EN       VIA   -    MD0100PA00X+143148Y+047004X0200Y    R180 S0      
317HP_NIC6_EN       VIA   -    MD0100PA00X+143595Y+064218X0200Y         S0      
327HP_NIC6_EN       R958  -1          A01X+143595Y+063939X0198Y0197R270 S1      
317HP_NIC6_EN       VIA   -    MD0100PA00X+139708Y+052773X0200Y    R180 S0      
327HP_NIC6_EN       R4453 -1          A01X+139966Y+052773X0198Y0197     S1      
327HP_NIC6_EN       C2882 -1          A01X+141264Y+047898X0198Y0197R180 S1      
327HP_NIC6_EN       R6042 -1          A01X+143148Y+046763X0198Y0197R270 S1      
327m1114            C3371 -1          A18X+110227Y+118035X0120Y0150R090 S2      
327m1114            C3370 -1          A18X+110227Y+118320X0120Y0150R270 S2      
317m1114            VIA   -    MD0080PA00X+110226Y+118179X0160Y    R270 S0      
327m1114            PEX2  -AA13       A01X+110413Y+117992X0180Y         S1      
327m1114            L120  -2          A01X+103663Y+117241X0440Y0540R180 S1      
327m1114            C3369 -1          A01X+104233Y+117331X0280Y0320R270 S1      
327m1114            R4578 -1          A01X+104178Y+116868X0198Y0197R270 S1      
317m1114            VIA   -    MD0100PA00X+103905Y+116809X0200Y         S0      
317m1114            VIA   -    M      A01X+104455Y+116809X0200Y         S2      
017m1114            VIA   -    M      A18X+104455Y+116809X0260Y         S2      
017m1114                  -    MD0100PA00X+104455Y+116809                       
317I2C0_PEX0_SCL    VIA   -    MD0080PA00X+027411Y+121171X0160Y         S0      
327I2C0_PEX0_SCL    PEX0  -M35        A01X+027224Y+121358X0180Y         S1      
317I2C0_PEX0_SCL    VIA   -    M      A01X+036179Y+118731X0200Y         S2      
017I2C0_PEX0_SCL    VIA   -    M      A18X+036179Y+118731X0260Y         S2      
017I2C0_PEX0_SCL          -    MD0100PA00X+036179Y+118731                       
327I2C0_PEX0_SCL    R3881 -1          A01X+035976Y+118520X0198Y0197R270 S1      
317m1115            VIA   -    M      A01X+086992Y+033372X0200Y         S2      
017m1115            VIA   -    M      A18X+086992Y+033372X0260Y         S2      
017m1115                  -    MD0100PA00X+086992Y+033372                       
327m1115            R4260 -2          A01X+088040Y+033734X0198Y0197R180 S1      
327m1115            R4266 -1   M      A01X+087566Y+033734X0198Y0197R180 S1      
327m1115            U330  -21         A01X+085599Y+032977X0160Y0540R270 S1      
317m1116            VIA   -    M      A01X+056489Y+121817X0200Y    R315 S2      
017m1116            VIA   -    M      A18X+056489Y+121817X0260Y    R315 S2      
017m1116                  -    MD0100PA00X+056489Y+121817                       
327m1116            R4361 -2          A01X+056284Y+121612X0198Y0197R045 S1      
327m1116            PEX1  -M13        A01X+064705Y+121358X0180Y         S1      
317m1116            VIA   -    MD0080PA00X+064518Y+121545X0160Y    R180 S0      
327m1117            VIA   -    M      A18X+023739Y+143724X0160Y0041     S2      
327m1117            R6292 -1   M      A01X+041378Y+152330X0198Y0197R180 S1      
317m1117            VIA   -    MD0100PA00X+041375Y+151689X0200Y         S0      
327m1117            U353  -6          A01X+041093Y+153442X0100Y0290R180 S1      
317m1117            VIA   -    MD0100PA00X+021612Y+144003X0200Y         S0      
327m1117            R5453 -1          A01X+021419Y+143221X0180Y0200R090 S1      
327m1118            VIA   -    M      A18X+086961Y+084143X0260Y         S2      
327m1118            R5533 -2   M      A18X+084588Y+083546X0198Y0197R180 S2      
327m1118            U5    -D13        A01X+088924Y+084687X0160Y    R180 S1      
317m1118            VIA   -    MD0100PA00X+088767Y+084529X0180Y    R270 S0      
317m1118            VIA   -    MD0100PA00X+082995Y+082979X0200Y         S0      
327m1118            R5532 -2   M      A01X+083311Y+082979X0198Y0197R090 S1      
327m1118            R4891 -2          A01X+083311Y+083352X0198Y0197R270 S1      
317I2C0_PEX0_SDA    VIA   -    MD0080PA00X+028533Y+121171X0160Y         S0      
327I2C0_PEX0_SDA    PEX0  -M39        A01X+028720Y+121358X0180Y         S1      
327I2C0_PEX0_SDA    R3882 -1          A01X+035444Y+118520X0198Y0197R270 S1      
317I2C0_PEX0_SDA    VIA   -    M      A01X+035708Y+118520X0200Y         S2      
017I2C0_PEX0_SDA    VIA   -    M      A18X+035708Y+118520X0260Y         S2      
017I2C0_PEX0_SDA          -    MD0100PA00X+035708Y+118520                       
317m1119            VIA   -    M      A01X+087041Y+034279X0200Y         S2      
017m1119            VIA   -    M      A18X+087041Y+034279X0260Y         S2      
017m1119                  -    MD0100PA00X+087041Y+034279                       
327m1119            R4264 -1          A01X+088040Y+034134X0198Y0197     S1      
327m1119            U330  -22         A01X+085599Y+033232X0160Y0540R270 S1      
327BIC_PECI         VIA   -    M      A18X+086522Y+085331X0260Y         S2      
327BIC_PECI         R4861 -2          A18X+085688Y+085192X0198Y0197R180 S2      
327BIC_PECI         U5    -H14        A01X+088609Y+085946X0160Y    R180 S1      
317BIC_PECI         VIA   -    MD0100PA00X+088452Y+085789X0180Y    R270 S0      
327m1120            VIA   -    M      A18X+025169Y+143616X0160Y0041     S2      
327m1120            R6291 -1   M      A01X+041713Y+152330X0198Y0197     S1      
317m1120            VIA   -    MD0100PA00X+041715Y+151689X0200Y         S0      
327m1120            U353  -7          A01X+041290Y+153442X0100Y0290R180 S1      
317m1120            VIA   -    MD0100PA00X+021952Y+144003X0200Y         S0      
327m1120            R5451 -1          A01X+022154Y+143211X0180Y0200R090 S1      
327m1121            C3391 -1          A18X+109772Y+116245X0120Y0150     S2      
327m1121            C3392 -1   M      A18X+109772Y+115935X0120Y0150     S2      
317m1121            VIA   -    MD0080PA00X+109852Y+115935X0160Y         S0      
327m1121            PEX2  -AF12       A01X+110039Y+116122X0180Y         S1      
317m1121            VIA   -    M      A01X+104455Y+114289X0200Y         S2      
017m1121            VIA   -    M      A18X+104455Y+114289X0260Y         S2      
017m1121                  -    MD0100PA00X+104455Y+114289                       
317m1121            VIA   -    MD0100PA00X+103905Y+114289X0200Y         S0      
327m1121            C3390 -1          A01X+104233Y+114811X0280Y0320R270 S1      
327m1121            R4582 -1          A01X+104178Y+114348X0198Y0197R270 S1      
327m1121            L124  -2          A01X+103663Y+114721X0440Y0540R180 S1      
327m1122            R3648 -1          A01X+141108Y+086800X0198Y0197R180 S1      
317m1122            VIA   -    MD0100PA00X+055785Y+074460X0200Y         S0      
327m1122            U440  -3   M      A01X+055396Y+074460X0140Y0440R270 S1      
317m1122            VIA   -    MD0100PA00X+141350Y+086800X0200Y         S0      
317m1122            VIA   -    M      A01X+051328Y+078329X0200Y         S2      
017m1122            VIA   -    M      A18X+051328Y+078329X0260Y         S2      
017m1122                  -    MD0100PA00X+051328Y+078329                       
327m1122            C4496 -1          A01X+055261Y+073856X0198Y0197     S1      
317m1123            VIA   -    M      A01X+087400Y+034492X0200Y         S2      
017m1123            VIA   -    M      A18X+087400Y+034492X0260Y         S2      
017m1123                  -    MD0100PA00X+087400Y+034492                       
327m1123            R4263 -1          A01X+088040Y+034534X0198Y0197     S1      
327m1123            U330  -23         A01X+085599Y+033488X0160Y0540R270 S1      
327m1124            C3405 -1          A18X+109772Y+115561X0120Y0150     S2      
327m1124            C3404 -1   M      A18X+109772Y+115187X0120Y0150     S2      
317m1124            VIA   -    MD0080PA00X+109852Y+115187X0160Y         S0      
327m1124            PEX2  -AH12       A01X+110039Y+115374X0180Y         S1      
317m1124            VIA   -    M      A01X+104455Y+113029X0200Y         S2      
017m1124            VIA   -    M      A18X+104455Y+113029X0260Y         S2      
017m1124                  -    MD0100PA00X+104455Y+113029                       
317m1124            VIA   -    MD0100PA00X+103905Y+113029X0200Y         S0      
327m1124            R4584 -1          A01X+104178Y+113088X0198Y0197R270 S1      
327m1124            C3403 -1          A01X+104233Y+113551X0280Y0320R270 S1      
327m1124            L126  -2          A01X+103663Y+113461X0440Y0540R180 S1      
327USB2_BIC_R_DN    VIA   -    M      A01X+040550Y+152433X0160Y0041R270 S1      
327USB2_BIC_R_DN    R5449 -1          A01X+041149Y+150127X0180Y0200R090 S1      
327USB2_BIC_R_DN    U353  -3          A01X+040503Y+153442X0100Y0290R180 S1      
327m1125            C3373 -1          A18X+109772Y+118180X0120Y0150     S2      
327m1125            C3374 -1   M      A18X+109772Y+117800X0120Y0150     S2      
327m1125            L121  -2          A01X+103663Y+118501X0440Y0540R180 S1      
327m1125            C3372 -1          A01X+104233Y+118591X0280Y0320R270 S1      
327m1125            R4579 -1          A01X+104178Y+118128X0198Y0197R270 S1      
317m1125            VIA   -    MD0100PA00X+103905Y+118069X0200Y         S0      
317m1125            VIA   -    M      A01X+104455Y+118069X0200Y         S2      
017m1125            VIA   -    M      A18X+104455Y+118069X0260Y         S2      
017m1125                  -    MD0100PA00X+104455Y+118069                       
317m1125            VIA   -    MD0080PA00X+109852Y+117805X0160Y    R270 S0      
327m1125            PEX2  -AB12       A01X+110039Y+117618X0180Y         S1      
327FM_CLK_EN        VIA   -    M      A01X+129580Y+088578X0300Y         S1      
327FM_CLK_EN        U6    -F1         A01X+131533Y+088184X0160Y         S1      
327FM_CLK_EN        R4168 -1          A01X+129107Y+088578X0198Y0197R180 S1      
317m1126            VIA   -    MD0100PA00X+122944Y+033258X0200Y         S0      
327m1126            U36   -2          A01X+123445Y+033258X0220Y0530R090 S1      
317m1126            VIA   -    M      A01X+140825Y+039804X0200Y         S2      
017m1126            VIA   -    M      A18X+140825Y+039804X0260Y         S2      
017m1126                  -    MD0100PA00X+140825Y+039804                       
317m1126            VIA   -    MD0100PA00X+141350Y+087200X0200Y         S0      
327m1126            R3647 -2          A01X+141108Y+087200X0198Y0197     S1      
327m1127            U5    -A11        A01X+089554Y+083742X0160Y    R180 S1      
317m1127            VIA   -    MD0100PA00X+089397Y+083585X0180Y    R270 S0      
317m1127            VIA   -    M      A01X+095571Y+083399X0200Y         S2      
017m1127            VIA   -    M      A18X+095571Y+083399X0280Y         S2      
017m1127                  -    MD0100PA00X+095571Y+083399                       
327m1127            R4893 -2          A01X+095868Y+083450X0198Y0197R090 S1      
327USB2_BIC_R_DP    VIA   -    M      A01X+041402Y+150934X0160Y0041R315 S1      
327USB2_BIC_R_DP    R5447 -1          A01X+041884Y+150118X0180Y0200R090 S1      
327USB2_BIC_R_DP    U353  -4          A01X+040700Y+153442X0100Y0290R180 S1      
317m1128            VIA   -    M      A01X+141800Y+076100X0200Y         S2      
017m1128            VIA   -    M      A18X+141800Y+076100X0260Y         S2      
017m1128                  -    MD0100PA00X+141800Y+076100                       
327m1128            R4618 -2          A01X+141558Y+076100X0198Y0197     S1      
327m1128            U344  -1          A01X+144198Y+075647X0240Y0540R270 S1      
327m1128            R4638 -1   M      A01X+142042Y+076100X0198Y0197     S1      
317m1129            VIA   -    MD0100PA00X+132320Y+084877X0180Y         S0      
327m1129            U6    -T4         A01X+132478Y+085034X0160Y         S1      
327m1129            R4670 -2          A01X+141558Y+068100X0198Y0197     S1      
327m1129            R4711 -2          A01X+142042Y+068100X0198Y0197R180 S1      
317m1129            VIA   -    MD0100PA00X+141800Y+068100X0200Y         S0      
317m1129            VIA   -    M      A01X+134030Y+068624X0200Y         S2      
017m1129            VIA   -    M      A18X+134030Y+068624X0260Y         S2      
017m1129                  -    MD0100PA00X+134030Y+068624                       
317m1130            VIA   -    MD0080PA00X+018996Y+121358X0160Y    R180 S0      
327m1130            PEX0  -M13        A01X+018996Y+121358X0180Y         S1      
327m1130            R4360 -2          A01X+010575Y+121612X0198Y0197R045 S1      
317m1130            VIA   -    M      A01X+010780Y+121817X0200Y    R315 S2      
017m1130            VIA   -    M      A18X+010780Y+121817X0260Y    R315 S2      
017m1130                  -    MD0100PA00X+010780Y+121817                       
327HSC_TIMER_R_N    U6    -P3         A01X+132163Y+085664X0160Y         S1      
317HSC_TIMER_R_N    VIA   -    MD0100PA00X+132006Y+085507X0180Y         S0      
317HSC_TIMER_R_N    VIA   -    M      A01X+129677Y+082878X0300Y         S1      
017HSC_TIMER_R_N    VIA   -    M      A18X+129677Y+082878X0200Y         S1      
017HSC_TIMER_R_N          -    MD0100PA00X+129677Y+082878                       
327HSC_TIMER_R_N    R5911 -1          A01X+129108Y+081950X0198Y0197R180 S1      
327HSC_TIMER_R_N    R5910 -2   M      A01X+129108Y+082350X0198Y0197     S1      
317JTAG_BIC_TDO     VIA   -    M      A01X+099405Y+081087X0200Y         S2      
017JTAG_BIC_TDO     VIA   -    M      A18X+099405Y+081087X0280Y         S2      
017JTAG_BIC_TDO           -    MD0100PA00X+099405Y+081087                       
327JTAG_BIC_TDO     U294  -12         A01X+099582Y+080630X0140Y0590     S1      
327JTAG_BIC_TDO     R5642 -2          A01X+099405Y+081377X0198Y0197R270 S1      
327m1131            R5445 -1          A01X+039362Y+151960X0180Y0200R090 S1      
327m1131            U353  -1          A01X+040109Y+153442X0100Y0290R180 S1      
317m1132            VIA   -    MD0100PA00X+141000Y+076100X0200Y         S0      
327m1132            R4617 -2          A01X+141245Y+076534X0198Y0197R180 S1      
327m1132            R4618 -1   M      A01X+141242Y+076100X0198Y0197     S1      
317m1132            VIA   -    M      A01X+142700Y+084650X0200Y         S2      
017m1132            VIA   -    M      A18X+142700Y+084650X0260Y         S2      
017m1132                  -    MD0100PA00X+142700Y+084650                       
327m1132            R4610 -1          A01X+142942Y+084650X0198Y0197     S1      
327m1133            R6415 -2          A18X+129104Y+088180X0198Y0197R180 S2      
327m1133            VIA   -    M      A18X+130750Y+088000X0260Y         S2      
327m1133            R4170 -1   M      A18X+129958Y+087980X0198Y0197     S2      
327m1133            U6    -G4         A01X+132478Y+087869X0160Y         S1      
317m1133            VIA   -    MD0100PA00X+132320Y+088026X0180Y         S0      
327HSC_UV_R_N       R6778 -2          A01X+073218Y+163448X0198Y0197R180 S1      
327HSC_UV_R_N       R6777 -2   M      A01X+073219Y+163003X0198Y0197R180 S1      
327HSC_UV_R_N       R498  -2   M      A01X+073217Y+162516X0198Y0197R090 S1      
317HSC_UV_R_N       VIA   -    M      A01X+072960Y+162516X0200Y         S2      
017HSC_UV_R_N       VIA   -    M      A18X+072960Y+162516X0260Y         S2      
017HSC_UV_R_N             -    MD0100PA00X+072960Y+162516                       
327HSC_UV_R_N       U5    -R14        A01X+088609Y+088151X0160Y    R180 S1      
317HSC_UV_R_N       VIA   -    MD0100PA00X+088458Y+088635X0180Y    R270 S0      
317HSC_UV_R_N       VIA   -    MD0100PA00X+090917Y+099419X0200Y         S0      
327HSC_UV_R_N       U6    -L3         A01X+132163Y+086609X0160Y         S1      
317HSC_UV_R_N       VIA   -    MD0100PA00X+132006Y+086766X0180Y         S0      
317HSC_UV_R_N       VIA   -    MD0100PA00X+089970Y+128387X0200Y         S0      
327m1134            R5444 -1          A01X+040090Y+151971X0180Y0200R090 S1      
327m1134            U353  -2          A01X+040306Y+153442X0100Y0290R180 S1      
327m1135            C3416 -1          A18X+109922Y+117431X0120Y0150     S2      
327m1135            C3417 -1   M      A18X+110226Y+117431X0120Y0150R090 S2      
317m1135            VIA   -    MD0080PA00X+110226Y+117431X0160Y    R270 S0      
327m1135            PEX2  -AC13       A01X+110413Y+117244X0180Y         S1      
327m1135            C3415 -1          A01X+104233Y+111031X0280Y0320R270 S1      
327m1135            R4586 -1          A01X+104178Y+110568X0198Y0197R270 S1      
327m1135            L128  -2          A01X+103663Y+110941X0440Y0540R180 S1      
317m1135            VIA   -    M      A01X+104455Y+110509X0200Y         S2      
017m1135            VIA   -    M      A18X+104455Y+110509X0260Y         S2      
017m1135                  -    MD0100PA00X+104455Y+110509                       
317m1135            VIA   -    MD0100PA00X+103905Y+110509X0200Y         S0      
317m1136            VIA   -    M      A01X+143774Y+073099X0200Y    R180 S2      
017m1136            VIA   -    M      A18X+143774Y+073099X0260Y    R180 S2      
017m1136                  -    MD0100PA00X+143774Y+073099                       
327m1136            R4648 -1          A01X+142358Y+072500X0198Y0197R180 S1      
327m1136            U344  -10         A01X+144198Y+073304X0160Y0540R270 S1      
317SSD8_LED         VIA   -    M      A01X+086992Y+030537X0200Y         S2      
017SSD8_LED         VIA   -    M      A18X+086992Y+030537X0260Y         S2      
017SSD8_LED               -    MD0100PA00X+086992Y+030537                       
327SSD8_LED         U330  -13         A01X+085599Y+030890X0240Y0540R270 S1      
327SSD8_LED         R4268 -1          A01X+087240Y+030537X0198Y0197     S1      
327BOARD_ID1        VIA   -    M      A18X+089762Y+090241X0260Y         S2      
327BOARD_ID1        R4551 -1          A18X+089929Y+090876X0198Y0197R270 S2      
327BOARD_ID1        R4554 -2   M      A18X+090329Y+090876X0198Y0197R090 S2      
327BOARD_ID1        U5    -P11        A01X+089554Y+087836X0160Y    R180 S1      
317BOARD_ID1        VIA   -    MD0100PA00X+089397Y+087994X0180Y    R270 S0      
317m1137            VIA   -    M      A01X+090634Y+037252X0200Y    R090 S2      
017m1137            VIA   -    M      A18X+090634Y+037252X0260Y    R090 S2      
017m1137                  -    MD0100PA00X+090634Y+037252                       
327m1137            U112  -22         A01X+091184Y+036916X0100Y0290R090 S1      
327m1137            R5440 -2          A01X+090234Y+037437X0198Y0197     S1      
327m1137            R5441 -1   M      A01X+090234Y+037037X0198Y0197R180 S1      
327m1137            R1021 -2   M      A01X+090234Y+036637X0198Y0197     S1      
327m1138            C3388 -1          A18X+110226Y+116395X0120Y0150R090 S2      
327m1138            C3389 -1   M      A18X+110226Y+116683X0120Y0150R270 S2      
317m1138            VIA   -    MD0080PA00X+110226Y+116683X0160Y         S0      
327m1138            PEX2  -AE13       A01X+110413Y+116496X0180Y         S1      
317m1138            VIA   -    MD0100PA00X+105070Y+102495X0200Y         S0      
317m1138            VIA   -    M      A01X+105620Y+102495X0200Y         S2      
017m1138            VIA   -    M      A18X+105620Y+102495X0260Y         S2      
017m1138                  -    MD0100PA00X+105620Y+102495                       
327m1138            R4581 -1          A01X+105342Y+102555X0198Y0197R270 S1      
327m1138            C3387 -1          A01X+105397Y+103017X0280Y0320R270 S1      
327m1138            L123  -2          A01X+104827Y+102927X0440Y0540R180 S1      
317m1139            VIA   -    M      A01X+142900Y+072900X0200Y    R180 S2      
017m1139            VIA   -    M      A18X+142900Y+072900X0260Y    R180 S2      
017m1139                  -    MD0100PA00X+142900Y+072900                       
327m1139            U344  -9          A01X+144198Y+073560X0160Y0540R270 S1      
327m1139            R4647 -1          A01X+142358Y+072900X0198Y0197R180 S1      
317m1140            VIA   -    M      A01X+133800Y+056250X0200Y    R180 S2      
017m1140            VIA   -    M      A18X+133800Y+056250X0260Y    R180 S2      
017m1140                  -    MD0100PA00X+133800Y+056250                       
327m1140            R4836 -1          A01X+133258Y+056250X0198Y0197R180 S1      
327m1140            U350  -9          A01X+135098Y+056910X0160Y0540R270 S1      
327RST_PEX_SYS_N    U6    -G3         A01X+132163Y+087869X0160Y         S1      
317RST_PEX_SYS_N    VIA   -    MD0100PA00X+132006Y+088026X0180Y         S0      
317RST_PEX_SYS_N    VIA   -    M      A01X+129113Y+089227X0200Y         S2      
017RST_PEX_SYS_N    VIA   -    M      A18X+129113Y+089227X0260Y         S2      
017RST_PEX_SYS_N          -    MD0100PA00X+129113Y+089227                       
327RST_PEX_SYS_N    R4169 -1          A01X+129200Y+089492X0198Y0197R090 S1      
327m1141            C3060 -1          A18X+018505Y+114813X0120Y0150     S2      
327m1141            C3059 -1          A18X+018809Y+114649X0120Y0150R090 S2      
317m1141            VIA   -    MD0080PA00X+018809Y+114813X0160Y         S0      
327m1141            PEX0  -AJ13       A01X+018996Y+115000X0180Y         S1      
317m1141            VIA   -    M      A01X+013038Y+111769X0200Y         S2      
017m1141            VIA   -    M      A18X+013038Y+111769X0260Y         S2      
017m1141                  -    MD0100PA00X+013038Y+111769                       
317m1141            VIA   -    MD0100PA00X+012488Y+111769X0200Y         S0      
327m1141            L95   -2          A01X+012245Y+112201X0440Y0540R180 S1      
327m1141            R4565 -1          A01X+012760Y+111828X0198Y0197R270 S1      
327m1141            C3058 -1          A01X+012815Y+112291X0280Y0320R270 S1      
317m1142            VIA   -    M      A01X+134674Y+056449X0200Y    R180 S2      
017m1142            VIA   -    M      A18X+134674Y+056449X0260Y    R180 S2      
017m1142                  -    MD0100PA00X+134674Y+056449                       
327m1142            R4837 -1          A01X+133258Y+055850X0198Y0197R180 S1      
327m1142            U350  -10         A01X+135098Y+056654X0160Y0540R270 S1      
327BOARD_ID2        VIA   -    M      A01X+087915Y+089653X0300Y    R090 S1      
327BOARD_ID2        R4555 -2          A01X+084863Y+090951X0198Y0197R270 S1      
327BOARD_ID2        R4552 -1   M      A01X+085263Y+090951X0198Y0197R090 S1      
327BOARD_ID2        U5    -R13        A01X+088924Y+088151X0160Y    R180 S1      
317CLK_25M_BIC      VIA   -    M      A01X+093836Y+080886X0200Y    R090 S2      
017CLK_25M_BIC      VIA   -    M      A18X+093836Y+080886X0260Y    R090 S2      
017CLK_25M_BIC            -    MD0100PA00X+093836Y+080886                       
327CLK_25M_BIC      R4860 -1          A18X+092179Y+081346X0198Y0197R270 S2      
327CLK_25M_BIC      OSC2  -3          A01X+093836Y+080489X0400Y0480R180 S1      
317m1143            VIA   -    M      A01X+039174Y+155583X0200Y         S2      
017m1143            VIA   -    M      A18X+039174Y+155583X0260Y         S2      
017m1143                  -    MD0100PA00X+039174Y+155583                       
327m1143            R5458 -2   M      A01X+038759Y+155170X0198Y0197     S1      
327m1143            R5460 -1   M      A01X+038759Y+155570X0198Y0197R180 S1      
327m1143            R5459 -2          A01X+038759Y+155970X0198Y0197     S1      
327m1143            U353  -22         A01X+039750Y+154982X0100Y0290R090 S1      
317m1144            VIA   -    MD0080PA00X+018435Y+117805X0160Y    R270 S0      
327m1144            PEX0  -AB12       A01X+018622Y+117618X0180Y         S1      
317m1144            VIA   -    MD0100PA00X+012476Y+118069X0200Y         S0      
317m1144            VIA   -    M      A01X+013100Y+118027X0200Y         S2      
017m1144            VIA   -    M      A18X+013100Y+118027X0260Y         S2      
017m1144                  -    MD0100PA00X+013100Y+118027                       
327m1144            L89   -2          A01X+012245Y+118501X0440Y0540R180 S1      
327m1144            R4559 -1          A01X+012760Y+118128X0198Y0197R270 S1      
327m1144            C3024 -1          A01X+012815Y+118591X0280Y0320R270 S1      
327m1144            C3025 -1          A18X+018355Y+118180X0120Y0150     S2      
327m1144            C3026 -1   M      A18X+018355Y+117800X0120Y0150     S2      
327m1145            R3640 -1          A01X+141108Y+090000X0198Y0197R180 S1      
317m1145            VIA   -    M      A01X+055775Y+075085X0200Y         S2      
017m1145            VIA   -    M      A18X+055775Y+075085X0260Y         S2      
017m1145                  -    MD0100PA00X+055775Y+075085                       
327m1145            U440  -1   M      A01X+055396Y+074972X0140Y0440R270 S1      
317m1145            VIA   -    MD0100PA00X+056237Y+072159X0200Y         S0      
317m1145            VIA   -    MD0100PA00X+141350Y+090000X0200Y         S0      
317m1145            VIA   -    MD0100PA00X+102294Y+069142X0200Y         S0      
327m1145            C4497 -1          A01X+054463Y+074651X0198Y0197     S1      
327BOARD_ID0        VIA   -    M      A01X+087966Y+090157X0300Y    R090 S1      
327BOARD_ID0        U5    -T13        A01X+088924Y+088466X0160Y    R180 S1      
327BOARD_ID0        R4550 -1          A01X+086063Y+090951X0198Y0197R090 S1      
327BOARD_ID0        R4553 -2   M      A01X+085663Y+090951X0198Y0197R270 S1      
317m1146            VIA   -    M      A01X+094961Y+079605X0200Y         S2      
017m1146            VIA   -    M      A18X+094961Y+079605X0260Y         S2      
017m1146                  -    MD0100PA00X+094961Y+079605                       
327m1146            OSC2  -1          A01X+094348Y+079819X0400Y0480R180 S1      
327m1146            R4859 -2          A01X+094961Y+079250X0198Y0197R180 S1      
327m1147            C3057 -1          A18X+018355Y+115561X0120Y0150     S2      
327m1147            C3056 -1   M      A18X+018355Y+115187X0120Y0150     S2      
317m1147            VIA   -    MD0080PA00X+018435Y+115187X0160Y         S0      
327m1147            PEX0  -AH12       A01X+018622Y+115374X0180Y         S1      
317m1147            VIA   -           A01X+013038Y+113029X0200Y         S2      
017m1147            VIA   -           A18X+013038Y+113029X0260Y         S2      
017m1147                  -     D0100PA00X+013038Y+113029                       
317m1147            VIA   -    MD0100PA00X+012488Y+113029X0200Y         S0      
327m1147            L94   -2          A01X+012245Y+113461X0440Y0540R180 S1      
327m1147            R4564 -1          A01X+012760Y+113088X0198Y0197R270 S1      
327m1147            C3055 -1          A01X+012815Y+113551X0280Y0320R270 S1      
327PWR_EN_P3V3      VIA   -    M      A18X+130400Y+088400X0260Y         S2      
327PWR_EN_P3V3      R4166 -1          A18X+129958Y+088380X0198Y0197     S2      
327PWR_EN_P3V3      U6    -F4         A01X+132478Y+088184X0160Y         S1      
317PWR_EN_P3V3      VIA   -    MD0100PA00X+132320Y+088341X0180Y         S0      
327JTAG_PLD_TDI     R4299 -1          A18X+100643Y+081696X0198Y0197R180 S2      
317JTAG_PLD_TDI     VIA   -    M      A01X+100605Y+081097X0200Y         S2      
017JTAG_PLD_TDI     VIA   -    M      A18X+100605Y+081097X0280Y         S2      
017JTAG_PLD_TDI           -    MD0100PA00X+100605Y+081097                       
327JTAG_PLD_TDI     U294  -8          A01X+100605Y+080630X0140Y0590     S1      
317m1148            VIA   -    M      A01X+039174Y+154053X0200Y         S2      
017m1148            VIA   -    M      A18X+039174Y+154053X0260Y         S2      
017m1148                  -    MD0100PA00X+039174Y+154053                       
327m1148            U353  -25         A01X+039750Y+154392X0100Y0290R090 S1      
327m1148            R5448 -2          A01X+038759Y+153970X0198Y0197     S1      
327m1149            R4563 -2          A01X+013925Y+100980X0198Y0197R270 S1      
317m1149            VIA   -           A01X+013657Y+100935X0200Y         S2      
017m1149            VIA   -           A18X+013657Y+100935X0260Y         S2      
017m1149                  -     D0100PA00X+013657Y+100935                       
327m1149            C3050 -1          A01X+013298Y+101037X0280Y0320R090 S1      
317m1150            VIA   -    M      A01X+042670Y+154195X0200Y         S2      
017m1150            VIA   -    M      A18X+042670Y+154195X0260Y         S2      
017m1150                  -    MD0100PA00X+042670Y+154195                       
327m1150            U353  -10         A01X+041649Y+154195X0100Y0290R090 S1      
327m1150            Y8    -1          A01X+043407Y+156062X0360Y0400R090 S1      
327m1150            C3635 -1   M      A01X+043165Y+155016X0198Y0197     S1      
327LM75_1_A2        R5607 -1          A01X+177642Y+163473X0198Y0197R090 S1      
327LM75_1_A2        R5601 -1   M      A01X+177242Y+163473X0198Y0197R090 S1      
327LM75_1_A2        U329  -5          A01X+177382Y+162522X0240Y0520     S1      
317LM75_1_A2        VIA   -    M      A01X+177382Y+163124X0200Y    R180 S2      
017LM75_1_A2        VIA   -    M      A18X+177382Y+163124X0260Y    R180 S2      
017LM75_1_A2              -    MD0100PA00X+177382Y+163124                       
327m1151            R4560 -2          A01X+012760Y+115293X0198Y0197R270 S1      
327m1151            C3032 -1          A01X+012133Y+115351X0280Y0320R090 S1      
317m1151            VIA   -           A01X+012492Y+115249X0200Y         S2      
017m1151            VIA   -           A18X+012492Y+115249X0260Y         S2      
017m1151                  -     D0100PA00X+012492Y+115249                       
327m1152            U346  -23         A01X+146502Y+070952X0160Y0540R270 S1      
317m1152            VIA   -    MD0100PA00X+147400Y+070700X0200Y         S0      
327m1152            U345  -23         A01X+148202Y+079502X0160Y0540R270 S1      
317m1152            VIA   -    M      A01X+149517Y+079667X0200Y         S2      
017m1152            VIA   -    M      A18X+149517Y+079667X0260Y         S2      
017m1152                  -    MD0100PA00X+149517Y+079667                       
317m1152            VIA   -    MD0100PA00X+083543Y+097778X0200Y         S0      
317m1152            VIA   -    MD0100PA00X+081903Y+112814X0200Y         S0      
327m1152            R3938 -1          A01X+081084Y+113713X0198Y0197R090 S1      
317m1153            VIA   -    M      A01X+157594Y+038211X0200Y    R180 S2      
017m1153            VIA   -    M      A18X+157594Y+038211X0260Y    R180 S2      
017m1153                  -    MD0100PA00X+157594Y+038211                       
327m1153            J26   -A70        A01X+157064Y+038207X0140Y0480R270 S1      
327m1153            R2470 -1          A01X+161736Y+065382X0198Y0197R270 S1      
317m1153            VIA   -    MD0100PA00X+161736Y+065632X0200Y         S0      
317JTAG_PLD_TCK     VIA   -    M      A01X+099705Y+077883X0200Y         S2      
017JTAG_PLD_TCK     VIA   -    M      A18X+099705Y+077883X0280Y         S2      
017JTAG_PLD_TCK           -    MD0100PA00X+099705Y+077883                       
327JTAG_PLD_TCK     R4301 -1          A01X+099599Y+077155X0198Y0197R270 S1      
327JTAG_PLD_TCK     U294  -3          A01X+099582Y+078330X0140Y0590     S1      
327JTAG_BIC_TDI_R   R5067 -2          A01X+100670Y+081382X0198Y0197R270 S1      
327JTAG_BIC_TDI_R   R5643 -1   M      A01X+101070Y+081698X0198Y0197R270 S1      
317JTAG_BIC_TDI_R   VIA   -    M      A01X+097898Y+081762X0200Y         S2      
017JTAG_BIC_TDI_R   VIA   -    M      A18X+097898Y+081762X0280Y         S2      
017JTAG_BIC_TDI_R         -    MD0100PA00X+097898Y+081762                       
317JTAG_BIC_TDI_R   VIA   -    MD0100PA00X+089192Y+079960X0200Y    R090 S0      
327JTAG_BIC_TDI_R   R5279 -1          A01X+089192Y+080332X0198Y0197R090 S1      
317m1154            VIA   -    M      A01X+039174Y+155073X0200Y         S2      
017m1154            VIA   -    M      A18X+039174Y+155073X0260Y         S2      
017m1154                  -    MD0100PA00X+039174Y+155073                       
327m1154            R5457 -1          A01X+038759Y+154770X0198Y0197R180 S1      
327m1154            U353  -23         A01X+039750Y+154785X0100Y0290R090 S1      
327LM75_1_A1        R5606 -1          A01X+176442Y+163473X0198Y0197R090 S1      
327LM75_1_A1        R5600 -1   M      A01X+176842Y+163473X0198Y0197R090 S1      
327LM75_1_A1        U329  -6          A01X+176882Y+162522X0240Y0520     S1      
317LM75_1_A1        VIA   -    M      A01X+176842Y+163224X0200Y    R180 S2      
017LM75_1_A1        VIA   -    M      A18X+176842Y+163224X0260Y    R180 S2      
017LM75_1_A1              -    MD0100PA00X+176842Y+163224                       
327m1155            C3069 -1          A18X+018505Y+117431X0120Y0150     S2      
327m1155            C3068 -1   M      A18X+018809Y+117431X0120Y0150R090 S2      
317m1155            VIA   -    MD0080PA00X+018809Y+117431X0160Y    R270 S0      
327m1155            PEX0  -AC13       A01X+018996Y+117244X0180Y         S1      
327m1155            C3067 -1          A01X+012815Y+111031X0280Y0320R270 S1      
327m1155            R4566 -1          A01X+012760Y+110568X0198Y0197R270 S1      
327m1155            L96   -2          A01X+012245Y+110941X0440Y0540R180 S1      
317m1155            VIA   -    MD0100PA00X+012488Y+110509X0200Y         S0      
317m1155            VIA   -    M      A01X+013038Y+110509X0200Y         S2      
017m1155            VIA   -    M      A18X+013038Y+110509X0260Y         S2      
017m1155                  -    MD0100PA00X+013038Y+110509                       
317m1156            VIA   -    M      A01X+040040Y+156102X0200Y         S2      
017m1156            VIA   -    M      A18X+040040Y+156102X0260Y         S2      
017m1156                  -    MD0100PA00X+040040Y+156102                       
327m1156            R5454 -2          A01X+040146Y+156343X0198Y0197R270 S1      
327m1156            U353  -19         A01X+040503Y+155341X0100Y0290R180 S1      
317IOEXP_DBV2_A2    VIA   -    M      A01X+129160Y+077144X0200Y         S2      
017IOEXP_DBV2_A2    VIA   -    M      A18X+129160Y+077144X0260Y         S2      
017IOEXP_DBV2_A2          -    MD0100PA00X+129160Y+077144                       
327IOEXP_DBV2_A2    U324  -3          A01X+129825Y+077144X0160Y0540R270 S1      
327IOEXP_DBV2_A2    R4234 -1          A01X+128509Y+076858X0198Y0197R180 S1      
327IOEXP_DBV2_A2    R4244 -2   M      A01X+128509Y+077258X0198Y0197     S1      
327LM75_1_A0        R5605 -1          A01X+175642Y+163473X0198Y0197R090 S1      
327LM75_1_A0        R5599 -1   M      A01X+176042Y+163473X0198Y0197R090 S1      
327LM75_1_A0        U329  -7          A01X+176382Y+162522X0240Y0520     S1      
317LM75_1_A0        VIA   -    M      A01X+176204Y+163151X0200Y    R180 S2      
017LM75_1_A0        VIA   -    M      A18X+176204Y+163151X0260Y    R180 S2      
017LM75_1_A0              -    MD0100PA00X+176204Y+163151                       
327m1157            R4564 -2          A01X+012760Y+112773X0198Y0197R270 S1      
327m1157            C3061 -1          A01X+012133Y+112831X0280Y0320R090 S1      
317m1157            VIA   -           A01X+012492Y+112729X0200Y         S2      
017m1157            VIA   -           A18X+012492Y+112729X0260Y         S2      
017m1157                  -     D0100PA00X+012492Y+112729                       
327m1158            U346  -22         A01X+146502Y+070696X0160Y0540R270 S1      
317m1158            VIA   -    M      A01X+146996Y+070696X0200Y         S2      
017m1158            VIA   -    M      A18X+146996Y+070696X0260Y         S2      
017m1158                  -    MD0100PA00X+146996Y+070696                       
317m1158            VIA   -    MD0100PA00X+148696Y+079246X0200Y         S0      
317m1158            VIA   -    MD0100PA00X+081945Y+113453X0200Y         S0      
317m1158            VIA   -    MD0100PA00X+082896Y+097778X0200Y         S0      
327m1158            R3937 -1          A01X+081884Y+113713X0198Y0197R090 S1      
327m1158            U345  -22         A01X+148202Y+079246X0160Y0540R270 S1      
317m1159            VIA   -    M      A01X+042254Y+153436X0200Y    R090 S2      
017m1159            VIA   -    M      A18X+042254Y+153436X0260Y    R090 S2      
017m1159                  -    MD0100PA00X+042254Y+153436                       
327m1159            U353  -8          A01X+041649Y+153801X0100Y0290R090 S1      
327m1159            R5455 -2          A01X+042404Y+153709X0198Y0197R180 S1      
317IOEXP_DBV2_A1    VIA   -    M      A01X+129160Y+077658X0200Y         S2      
017IOEXP_DBV2_A1    VIA   -    M      A18X+129160Y+077658X0260Y         S2      
017IOEXP_DBV2_A1          -    MD0100PA00X+129160Y+077658                       
327IOEXP_DBV2_A1    U324  -2          A01X+129825Y+077399X0160Y0540R270 S1      
327IOEXP_DBV2_A1    R4235 -1          A01X+128509Y+078058X0198Y0197R180 S1      
327IOEXP_DBV2_A1    R4245 -2   M      A01X+128509Y+077658X0198Y0197     S1      
327m1160            C3040 -1          A18X+018809Y+116395X0120Y0150R090 S2      
327m1160            C3041 -1   M      A18X+018809Y+116683X0120Y0150R270 S2      
317m1160            VIA   -    MD0080PA00X+018809Y+116683X0160Y         S0      
327m1160            PEX0  -AE13       A01X+018996Y+116496X0180Y         S1      
317m1160            VIA   -    MD0100PA00X+013653Y+102495X0200Y         S0      
317m1160            VIA   -    M      A01X+014203Y+102495X0200Y         S2      
017m1160            VIA   -    M      A18X+014203Y+102495X0260Y         S2      
017m1160                  -    MD0100PA00X+014203Y+102495                       
327m1160            R4561 -1          A01X+013925Y+102555X0198Y0197R270 S1      
327m1160            L91   -2          A01X+013410Y+102927X0440Y0540R180 S1      
327m1160            C3039 -1          A01X+013980Y+103017X0280Y0320R270 S1      
317m1161            VIA   -    M      A01X+039174Y+154563X0200Y         S2      
017m1161            VIA   -    M      A18X+039174Y+154563X0260Y         S2      
017m1161                  -    MD0100PA00X+039174Y+154563                       
327m1161            R5450 -2          A01X+038759Y+154370X0198Y0197     S1      
327m1161            U353  -24         A01X+039750Y+154588X0100Y0290R090 S1      
327IOEXP_DBV2_A0    VIA   -    M      A01X+133434Y+076888X0300Y         S1      
327IOEXP_DBV2_A0    R4236 -1          A01X+133922Y+077368X0198Y0197     S1      
327IOEXP_DBV2_A0    R4246 -2   M      A01X+133922Y+076968X0198Y0197R180 S1      
327IOEXP_DBV2_A0    U324  -21         A01X+132128Y+076888X0160Y0540R270 S1      
327SMB_LM75_1_SCL   U329  -2          A01X+176382Y+160436X0240Y0520     S1      
317SMB_LM75_1_SCL   VIA   -    M      A01X+176504Y+159951X0200Y    R180 S2      
017SMB_LM75_1_SCL   VIA   -    M      A18X+176504Y+159951X0260Y    R180 S2      
017SMB_LM75_1_SCL         -    MD0100PA00X+176504Y+159951                       
327SMB_LM75_1_SCL   R5603 -2          A01X+176507Y+159634X0198Y0197R090 S1      
327m1162            R4566 -2          A01X+012760Y+110253X0198Y0197R270 S1      
327m1162            C3073 -1          A01X+012133Y+110311X0280Y0320R090 S1      
317m1162            VIA   -           A01X+012492Y+110209X0200Y         S2      
017m1162            VIA   -           A18X+012492Y+110209X0260Y         S2      
017m1162                  -     D0100PA00X+012492Y+110209                       
327m1163            R3941 -1          A01X+080787Y+117112X0198Y0197     S1      
317m1163            VIA   -    M      A01X+081151Y+115754X0200Y         S2      
017m1163            VIA   -    M      A18X+081151Y+115754X0260Y         S2      
017m1163                  -    MD0100PA00X+081151Y+115754                       
327m1163            U314  -6   M      A01X+081266Y+114684X0170Y0460     S1      
327m1163            R3938 -2   M      A01X+081084Y+114028X0198Y0197R090 S1      
327m1163            R3934 -1          A01X+080284Y+114028X0198Y0197R270 S1      
327m1163            R3940 -2   M      A01X+080684Y+114028X0198Y0197R090 S1      
317m1164            VIA   -    MD0100PA00X+132636Y+084877X0180Y         S0      
327m1164            U6    -T5         A01X+132793Y+085034X0160Y         S1      
317m1164            VIA   -    M      A01X+135093Y+068704X0200Y         S2      
017m1164            VIA   -    M      A18X+135093Y+068704X0260Y         S2      
017m1164                  -    MD0100PA00X+135093Y+068704                       
327m1164            R4677 -1          A01X+141558Y+068900X0198Y0197R180 S1      
327m1164            R4664 -2   M      A01X+141558Y+068500X0198Y0197     S1      
327m1164            R4710 -2          A01X+142042Y+068500X0198Y0197R180 S1      
317m1164            VIA   -    MD0100PA00X+141800Y+068500X0200Y         S0      
327PWR_EN_PEX       VIA   -    M      A01X+130138Y+088978X0300Y         S1      
327PWR_EN_PEX       U6    -E1         A01X+131533Y+088499X0160Y         S1      
327PWR_EN_PEX       R6178 -2   M      A01X+129107Y+088977X0198Y0197     S1      
317PWR_EN_PEX       VIA   -    MD0100PA00X+128218Y+089885X0200Y         S0      
327PWR_EN_PEX       R3059 -2   M      A01X+143567Y+100152X0198Y0197     S1      
327PWR_EN_PEX       R3068 -1          A01X+144004Y+100152X0198Y0197     S1      
317PWR_EN_PEX       VIA   -    MD0100PA00X+143567Y+100537X0200Y         S0      
317PWR_EN_PEX       VIA   -    MD0100PA00X+129284Y+097524X0200Y         S0      
327JTAG_BIC_TMS_R   R4894 -1          A18X+089192Y+082042X0198Y0197R270 S2      
327JTAG_BIC_TMS_R   R5284 -2   M      A18X+089192Y+081662X0198Y0197R270 S2      
317JTAG_BIC_TMS_R   VIA   -    MD0100PA00X+091103Y+079660X0200Y    R090 S0      
317JTAG_BIC_TMS_R   VIA   -    M      A01X+099999Y+076457X0200Y         S2      
017JTAG_BIC_TMS_R   VIA   -    M      A18X+099999Y+076457X0280Y         S2      
017JTAG_BIC_TMS_R         -    MD0100PA00X+099999Y+076457                       
327JTAG_BIC_TMS_R   R5644 -1   M      A01X+099999Y+076840X0198Y0197R090 S1      
327JTAG_BIC_TMS_R   R5066 -2          A01X+100399Y+077155X0198Y0197R090 S1      
317m1165            VIA   -    M      A01X+129160Y+078158X0200Y         S2      
017m1165            VIA   -    M      A18X+129160Y+078158X0260Y         S2      
017m1165                  -    MD0100PA00X+129160Y+078158                       
327m1165            R4238 -2          A01X+128509Y+078458X0198Y0197     S1      
327m1165            U324  -1          A01X+129825Y+077695X0240Y0540R270 S1      
327SMB_LM75_1_SDA   U329  -1          A01X+175882Y+160436X0240Y0520     S1      
317SMB_LM75_1_SDA   VIA   -    M      A01X+175995Y+159903X0200Y    R180 S2      
017SMB_LM75_1_SDA   VIA   -    M      A18X+175995Y+159903X0260Y    R180 S2      
017SMB_LM75_1_SDA         -    MD0100PA00X+175995Y+159903                       
327SMB_LM75_1_SDA   R5602 -2          A01X+176107Y+159634X0198Y0197R090 S1      
327m1166            R4562 -2          A01X+012760Y+114033X0198Y0197R270 S1      
327m1166            C3049 -1          A01X+012133Y+114091X0280Y0320R090 S1      
317m1166            VIA   -           A01X+012492Y+113989X0200Y         S2      
017m1166            VIA   -           A18X+012492Y+113989X0260Y         S2      
017m1166                  -     D0100PA00X+012492Y+113989                       
327m1167            U314  -7   M      A01X+081522Y+114684X0170Y0460     S1      
327m1167            R3942 -1          A01X+081802Y+117112X0198Y0197R180 S1      
317m1167            VIA   -    M      A01X+081796Y+115740X0200Y         S2      
017m1167            VIA   -    M      A18X+081796Y+115740X0260Y         S2      
017m1167                  -    MD0100PA00X+081796Y+115740                       
327m1167            R3939 -2   M      A01X+081484Y+114028X0198Y0197R090 S1      
327m1167            R3933 -1          A01X+082284Y+114028X0198Y0197R270 S1      
327m1167            R3937 -2   M      A01X+081884Y+114028X0198Y0197R090 S1      
327m1168            R3632 -1          A01X+141108Y+088000X0198Y0197R180 S1      
327m1168            C4498 -1          A01X+069316Y+069707X0198Y0197R090 S1      
327m1168            U439  -3   M      A01X+069979Y+069709X0140Y0440R270 S1      
317m1168            VIA   -    MD0100PA00X+070368Y+069709X0200Y         S0      
317m1168            VIA   -    MD0100PA00X+116612Y+071847X0200Y         S0      
317m1168            VIA   -    M      A01X+141780Y+087950X0200Y         S2      
017m1168            VIA   -    M      A18X+141780Y+087950X0260Y         S2      
017m1168                  -    MD0100PA00X+141780Y+087950                       
327JTAG_BIC_TCK_R   R4895 -1          A18X+089587Y+082042X0198Y0197R270 S2      
327JTAG_BIC_TCK_R   R5282 -2   M      A18X+089992Y+080646X0198Y0197R270 S2      
317JTAG_BIC_TCK_R   VIA   -    MD0100PA00X+090787Y+079557X0200Y    R090 S0      
327JTAG_BIC_TCK_R   R5283 -2          A18X+098988Y+076878X0198Y0197     S2      
317JTAG_BIC_TCK_R   VIA   -    M      A01X+098436Y+077756X0200Y         S2      
017JTAG_BIC_TCK_R   VIA   -    M      A18X+098436Y+077756X0280Y         S2      
017JTAG_BIC_TCK_R         -    MD0100PA00X+098436Y+077756                       
327JTAG_BIC_TCK_R   R5645 -1          A01X+098799Y+076840X0198Y0197R090 S1      
317m1169            VIA   -    M      A01X+039530Y+156102X0200Y         S2      
017m1169            VIA   -    M      A18X+039530Y+156102X0260Y         S2      
017m1169                  -    MD0100PA00X+039530Y+156102                       
327m1169            U353  -20         A01X+040306Y+155341X0100Y0290R180 S1      
327m1169            R5452 -2          A01X+039746Y+156343X0198Y0197R270 S1      
327m1170            R4565 -2          A01X+012760Y+111513X0198Y0197R270 S1      
327m1170            C3062 -1          A01X+012133Y+111571X0280Y0320R090 S1      
317m1170            VIA   -           A01X+012492Y+111469X0200Y         S2      
017m1170            VIA   -           A18X+012492Y+111469X0260Y         S2      
017m1170                  -     D0100PA00X+012492Y+111469                       
317m1171            VIA   -    MD0080PA00X+070876Y+121171X0160Y    R270 S0      
327m1171            PEX1  -M29        A01X+070689Y+121358X0180Y         S1      
317m1171            VIA   -    M      A01X+082352Y+118524X0200Y         S2      
017m1171            VIA   -    M      A18X+082352Y+118524X0260Y         S2      
017m1171                  -    MD0100PA00X+082352Y+118524                       
327m1171            R3932 -1          A01X+082082Y+118524X0198Y0197R270 S1      
327SSD2_LED         VIA   -    M      A01X+081998Y+032465X0300Y         S1      
327SSD2_LED         R4304 -2          A01X+081505Y+032537X0198Y0197     S1      
327SSD2_LED         U330  -6          A01X+083296Y+032465X0160Y0540R270 S1      
327m1172            R6844 -1          A01X+042465Y+154637X0198Y0197     S1      
317m1172            VIA   -    M      A01X+042145Y+154462X0200Y    R090 S2      
017m1172            VIA   -    M      A18X+042145Y+154462X0260Y    R090 S2      
017m1172                  -    MD0100PA00X+042145Y+154462                       
327m1172            U353  -11         A01X+041649Y+154392X0100Y0290R090 S1      
327LM75_0_A2        U328  -5          A01X+008369Y+161872X0240Y0520     S1      
317LM75_0_A2        VIA   -    M      A01X+008369Y+162474X0200Y    R180 S2      
017LM75_0_A2        VIA   -    M      A18X+008369Y+162474X0260Y    R180 S2      
017LM75_0_A2              -    MD0100PA00X+008369Y+162474                       
327LM75_0_A2        R5592 -1          A01X+008629Y+162823X0198Y0197R090 S1      
327LM75_0_A2        R5590 -1   M      A01X+008229Y+162823X0198Y0197R090 S1      
327m1173            R4559 -2          A01X+012760Y+117813X0198Y0197R270 S1      
327m1173            C3031 -1          A01X+012133Y+117871X0280Y0320R090 S1      
317m1173            VIA   -           A01X+012492Y+117769X0200Y         S2      
017m1173            VIA   -           A18X+012492Y+117769X0260Y         S2      
017m1173                  -     D0100PA00X+012492Y+117769                       
317m1174            VIA   -    MD0080PA00X+070502Y+121171X0160Y    R270 S0      
327m1174            PEX1  -M28        A01X+070315Y+121358X0180Y         S1      
327m1174            R3931 -1          A01X+080753Y+118520X0198Y0197R270 S1      
317m1174            VIA   -    M      A01X+080552Y+118722X0200Y         S2      
017m1174            VIA   -    M      A18X+080552Y+118722X0260Y         S2      
017m1174                  -    MD0100PA00X+080552Y+118722                       
327JTAG_PLD_TDO     VIA   -    M      A18X+099838Y+080598X0280Y         S2      
327JTAG_PLD_TDO     R4298 -1          A18X+100243Y+080148X0198Y0197R180 S2      
317JTAG_PLD_TDO     VIA   -    MD0100PA00X+099838Y+081097X0200Y         S0      
327JTAG_PLD_TDO     U294  -11         A01X+099838Y+080630X0140Y0590     S1      
317SSD5_LED         VIA   -    M      A01X+081746Y+031337X0200Y         S2      
017SSD5_LED         VIA   -    M      A18X+081746Y+031337X0260Y         S2      
017SSD5_LED               -    MD0100PA00X+081746Y+031337                       
327SSD5_LED         R4307 -2          A01X+081505Y+031337X0198Y0197     S1      
327SSD5_LED         U330  -9          A01X+083296Y+031697X0160Y0540R270 S1      
317m1175            VIA   -    M      A01X+040550Y+156102X0200Y         S2      
017m1175            VIA   -    M      A18X+040550Y+156102X0260Y         S2      
017m1175                  -    MD0100PA00X+040550Y+156102                       
327m1175            R5443 -1          A01X+040546Y+156343X0198Y0197R090 S1      
327m1175            U353  -18         A01X+040700Y+155341X0100Y0290R180 S1      
327LM75_0_A1        U328  -6          A01X+007869Y+161872X0240Y0520     S1      
317LM75_0_A1        VIA   -    M      A01X+007829Y+162574X0200Y    R180 S2      
017LM75_0_A1        VIA   -    M      A18X+007829Y+162574X0260Y    R180 S2      
017LM75_0_A1              -    MD0100PA00X+007829Y+162574                       
327LM75_0_A1        R5589 -1   M      A01X+007829Y+162823X0198Y0197R090 S1      
327LM75_0_A1        R5593 -1          A01X+007429Y+162823X0198Y0197R090 S1      
327m1176            R4558 -2          A01X+012760Y+116553X0198Y0197R270 S1      
327m1176            C3030 -1          A01X+012133Y+116611X0280Y0320R090 S1      
317m1176            VIA   -           A01X+012492Y+116509X0200Y         S2      
017m1176            VIA   -           A18X+012492Y+116509X0260Y         S2      
017m1176                  -     D0100PA00X+012492Y+116509                       
327m1177            R3930 -1          A01X+079542Y+120334X0198Y0197R090 S1      
327m1177            VIA   -    M      A18X+079059Y+120220X0260Y         S2      
317m1177            VIA   -    MD0100PA00X+079453Y+119577X0200Y         S0      
327m1177            PEX1  -N38        A01X+074055Y+120984X0180Y         S1      
317m1177            VIA   -    MD0080PA00X+074242Y+120797X0160Y         S0      
317JTAG_PLD_TMS     VIA   -    M      A01X+101270Y+077673X0200Y         S2      
017JTAG_PLD_TMS     VIA   -    M      A18X+101270Y+077673X0280Y         S2      
017JTAG_PLD_TMS           -    MD0100PA00X+101270Y+077673                       
327JTAG_PLD_TMS     U294  -6          A01X+100349Y+078330X0140Y0590     S1      
327JTAG_PLD_TMS     R4300 -1          A01X+100799Y+077155X0198Y0197R270 S1      
317SSD7_LED         VIA   -    M      A01X+081746Y+030537X0200Y         S2      
017SSD7_LED         VIA   -    M      A18X+081746Y+030537X0260Y         S2      
017SSD7_LED               -    MD0100PA00X+081746Y+030537                       
327SSD7_LED         R4309 -2          A01X+081505Y+030537X0198Y0197     S1      
327SSD7_LED         U330  -11         A01X+083296Y+031185X0160Y0540R270 S1      
317m1178            VIA   -    MD0100PA00X+132636Y+086137X0180Y         S0      
327m1178            U6    -M5         A01X+132793Y+086294X0160Y         S1      
317m1178            VIA   -    MD0100PA00X+088863Y+091524X0200Y         S0      
317m1178            VIA   -    M      A01X+105391Y+085547X0200Y         S2      
017m1178            VIA   -    M      A18X+105391Y+085547X0260Y         S2      
017m1178                  -    MD0100PA00X+105391Y+085547                       
327m1178            R4542 -1          A01X+088863Y+091266X0198Y0197R270 S1      
317m1179            VIA   -    M      A01X+095602Y+070691X0200Y    R180 S2      
017m1179            VIA   -    M      A18X+095602Y+070691X0260Y    R180 S2      
017m1179                  -    MD0100PA00X+095602Y+070691                       
327m1179            U325  -4          A01X+095402Y+071116X0220Y0530R180 S1      
327m1179            R4249 -1          A01X+095355Y+070441X0198Y0197R270 S1      
327m1179            R4251 -1   M      A01X+095755Y+070441X0198Y0197R270 S1      
327LM75_0_A0        U328  -7          A01X+007369Y+161872X0240Y0520     S1      
327LM75_0_A0        R5595 -1          A01X+006629Y+162823X0198Y0197R090 S1      
327LM75_0_A0        R5594 -1   M      A01X+007029Y+162823X0198Y0197R090 S1      
317LM75_0_A0        VIA   -    M      A01X+007191Y+162501X0200Y    R180 S2      
017LM75_0_A0        VIA   -    M      A18X+007191Y+162501X0260Y    R180 S2      
017LM75_0_A0              -    MD0100PA00X+007191Y+162501                       
327m1180            C3029 -1          A18X+018355Y+116683X0120Y0150     S2      
327m1180            C3028 -1   M      A18X+018355Y+117057X0120Y0150     S2      
317m1180            VIA   -    MD0080PA00X+018435Y+117057X0160Y         S0      
327m1180            PEX0  -AD12       A01X+018622Y+116870X0180Y         S1      
327m1180            C3027 -1          A01X+012815Y+116071X0280Y0320R270 S1      
327m1180            L90   -2          A01X+012245Y+115981X0440Y0540R180 S1      
327m1180            R4560 -1          A01X+012760Y+115608X0198Y0197R270 S1      
317m1180            VIA   -    MD0100PA00X+012488Y+115549X0200Y         S0      
317m1180            VIA   -    M      A01X+013038Y+115549X0200Y         S2      
017m1180            VIA   -    M      A18X+013038Y+115549X0260Y         S2      
017m1180                  -    MD0100PA00X+013038Y+115549                       
317m1181            VIA   -    M      A01X+143315Y+074584X0200Y    R180 S2      
017m1181            VIA   -    M      A18X+143315Y+074584X0260Y    R180 S2      
017m1181                  -    MD0100PA00X+143315Y+074584                       
327m1181            R4643 -1          A01X+142358Y+074500X0198Y0197R180 S1      
327m1181            U344  -5          A01X+144198Y+074584X0160Y0540R270 S1      
327m1182            PEX1  -L39        A01X+074429Y+121732X0180Y         S1      
317m1182            VIA   -    MD0080PA00X+074242Y+121545X0160Y         S0      
327m1182            R3929 -1          A01X+080360Y+120340X0198Y0197R090 S1      
327m1182            VIA   -    M      A18X+079678Y+120630X0260Y         S2      
317m1182            VIA   -    MD0100PA00X+080445Y+119981X0200Y         S0      
317SSD3_LED         VIA   -    M      A01X+081710Y+031960X0200Y         S2      
017SSD3_LED         VIA   -    M      A18X+081710Y+031960X0260Y         S2      
017SSD3_LED               -    MD0100PA00X+081710Y+031960                       
327SSD3_LED         R4305 -2          A01X+081505Y+032137X0198Y0197     S1      
327SSD3_LED         U330  -7          A01X+083296Y+032209X0160Y0540R270 S1      
317m1183            VIA   -    MD0100PA00X+137045Y+084562X0180Y         S0      
327m1183            U6    -U18        A01X+136887Y+084719X0160Y         S1      
317m1183            VIA   -    MD0100PA00X+089263Y+091524X0200Y         S0      
317m1183            VIA   -    M      A01X+105250Y+084120X0200Y         S2      
017m1183            VIA   -    M      A18X+105250Y+084120X0260Y         S2      
017m1183                  -    MD0100PA00X+105250Y+084120                       
327m1183            R4540 -1          A01X+089263Y+091266X0198Y0197R270 S1      
317m1184            VIA   -    M      A01X+095776Y+072534X0200Y         S2      
017m1184            VIA   -    M      A18X+095776Y+072534X0260Y         S2      
017m1184                  -    MD0100PA00X+095776Y+072534                       
327m1184            U325  -2          A01X+095776Y+072080X0220Y0530R180 S1      
327m1184            R4250 -1          A01X+095595Y+072846X0198Y0197R090 S1      
317SMB_LM75_0_SCL   VIA   -    MD0100PA00X+175839Y+157790X0200Y         S0      
327SMB_LM75_0_SCL   R5588 -2          A01X+176300Y+158192X0198Y0197R270 S1      
317SMB_LM75_0_SCL   VIA   -    M      A01X+007491Y+159301X0200Y    R180 S2      
017SMB_LM75_0_SCL   VIA   -    M      A18X+007491Y+159301X0260Y    R180 S2      
017SMB_LM75_0_SCL         -    MD0100PA00X+007491Y+159301                       
327SMB_LM75_0_SCL   U328  -2          A01X+007369Y+159786X0240Y0520     S1      
317SMB_LM75_0_SCL   VIA   -    MD0100PA00X+039589Y+145002X0200Y         S0      
327m1185            C3043 -1          A18X+018355Y+116245X0120Y0150     S2      
327m1185            C3044 -1   M      A18X+018355Y+115935X0120Y0150     S2      
317m1185            VIA   -    MD0080PA00X+018435Y+115935X0160Y         S0      
327m1185            PEX0  -AF12       A01X+018622Y+116122X0180Y         S1      
327m1185            R4562 -1          A01X+012760Y+114348X0198Y0197R270 S1      
327m1185            C3042 -1          A01X+012815Y+114811X0280Y0320R270 S1      
327m1185            L92   -2          A01X+012245Y+114721X0440Y0540R180 S1      
317m1185            VIA   -    MD0100PA00X+012447Y+114300X0200Y         S0      
317m1185            VIA   -    M      A01X+013043Y+114496X0200Y         S2      
017m1185            VIA   -    M      A18X+013043Y+114496X0260Y         S2      
017m1185                  -    MD0100PA00X+013043Y+114496                       
327m1186            U314  -2          A01X+081522Y+116397X0170Y0460     S1      
317m1186            VIA   -    M      A01X+081504Y+116777X0200Y         S2      
017m1186            VIA   -    M      A18X+081504Y+116777X0260Y         S2      
017m1186                  -    MD0100PA00X+081504Y+116777                       
327m1186            R3942 -2   M      A01X+081487Y+117112X0198Y0197R180 S1      
327m1186            R3928 -2          A01X+082083Y+117514X0198Y0197R270 S1      
327m1186            R4015 -2   M      A01X+081683Y+117514X0198Y0197R270 S1      
327m1187            U348  -23         A01X+137402Y+067802X0160Y0540R270 S1      
317m1187            VIA   -    MD0100PA00X+138300Y+067550X0200Y         S0      
317m1187            VIA   -    MD0100PA00X+124540Y+100370X0200Y         S0      
317m1187            VIA   -    MD0100PA00X+126392Y+113473X0200Y         S0      
327m1187            R3983 -1          A01X+126392Y+113713X0198Y0197R090 S1      
317m1187            VIA   -    M      A01X+138529Y+072240X0200Y         S2      
017m1187            VIA   -    M      A18X+138529Y+072240X0260Y         S2      
017m1187                  -    MD0100PA00X+138529Y+072240                       
327m1187            U347  -23         A01X+137402Y+072502X0160Y0540R270 S1      
317SSD6_LED         VIA   -    M      A01X+082248Y+030937X0200Y         S2      
017SSD6_LED         VIA   -    M      A18X+082248Y+030937X0260Y         S2      
017SSD6_LED               -    MD0100PA00X+082248Y+030937                       
327SSD6_LED         R4308 -2          A01X+081505Y+030937X0198Y0197     S1      
327SSD6_LED         U330  -10         A01X+083296Y+031441X0160Y0540R270 S1      
317m1188            VIA   -    MD0100PA00X+136730Y+084877X0180Y         S0      
327m1188            U6    -T17        A01X+136572Y+085034X0160Y         S1      
327m1188            R4539 -1          A01X+089663Y+091266X0198Y0197R270 S1      
317m1188            VIA   -    MD0100PA00X+089655Y+091804X0200Y         S0      
317m1188            VIA   -    MD0100PA00X+103834Y+075648X0200Y         S0      
317m1188            VIA   -    M      A01X+104909Y+085603X0200Y         S2      
017m1188            VIA   -    M      A18X+104909Y+085603X0260Y         S2      
017m1188                  -    MD0100PA00X+104909Y+085603                       
327SMB_LM75_0_SDA   U328  -1          A01X+006869Y+159786X0240Y0520     S1      
327SMB_LM75_0_SDA   R5587 -2          A01X+007094Y+158984X0198Y0197R090 S1      
317SMB_LM75_0_SDA   VIA   -    M      A01X+006982Y+159253X0200Y    R180 S2      
017SMB_LM75_0_SDA   VIA   -    M      A18X+006982Y+159253X0260Y    R180 S2      
017SMB_LM75_0_SDA         -    MD0100PA00X+006982Y+159253                       
327m1189            R4561 -2          A01X+013925Y+102240X0198Y0197R270 S1      
317m1189            VIA   -           A01X+013657Y+102195X0200Y         S2      
017m1189            VIA   -           A18X+013657Y+102195X0260Y         S2      
017m1189                  -     D0100PA00X+013657Y+102195                       
327m1189            C3048 -1          A01X+013298Y+102297X0280Y0320R090 S1      
327P0V8_PEX3_PWM1   PU11  -1          A01X+138258Y+100785X0070Y0240     S1      
317P0V8_PEX3_PWM1   VIA   -    M      A01X+138152Y+099628X0200Y    R090 S2      
017P0V8_PEX3_PWM1   VIA   -    M      A18X+138152Y+099628X0260Y    R090 S2      
017P0V8_PEX3_PWM1         -    MD0100PA00X+138152Y+099628                       
327P0V8_PEX3_PWM1   PU14  -34         A01X+139595Y+111023X0090Y0240R180 S1      
317P0V8_PEX3_PWM1   VIA   -    MD0100PA00X+139675Y+110479X0200Y         S0      
327SSD4_LED         VIA   -    M      A01X+081998Y+031737X0300Y         S1      
327SSD4_LED         R4306 -2          A01X+081505Y+031737X0198Y0197     S1      
327SSD4_LED         U330  -8          A01X+083296Y+031953X0160Y0540R270 S1      
317m1190            VIA   -    MD0100PA00X+137045Y+084247X0180Y         S0      
327m1190            U6    -V18        A01X+136887Y+084404X0160Y         S1      
317m1190            VIA   -    MD0100PA00X+091263Y+091804X0200Y         S0      
317m1190            VIA   -    M      A01X+104082Y+084134X0200Y         S2      
017m1190            VIA   -    M      A18X+104082Y+084134X0260Y         S2      
017m1190                  -    MD0100PA00X+104082Y+084134                       
327m1190            R4541 -1          A18X+091129Y+091191X0198Y0197R090 S2      
327m1191            C3047 -1          A18X+018809Y+115695X0120Y0150R270 S2      
327m1191            C3046 -1          A18X+018809Y+115397X0120Y0150R090 S2      
317m1191            VIA   -    MD0080PA00X+018809Y+115561X0160Y         S0      
327m1191            PEX0  -AG13       A01X+018996Y+115748X0180Y         S1      
327m1191            R4563 -1          A01X+013925Y+101295X0198Y0197R270 S1      
327m1191            C3045 -1          A01X+013980Y+101757X0280Y0320R270 S1      
327m1191            L93   -2          A01X+013410Y+101667X0440Y0540R180 S1      
317m1191            VIA   -    M      A01X+014203Y+101235X0200Y         S2      
017m1191            VIA   -    M      A18X+014203Y+101235X0260Y         S2      
017m1191                  -    MD0100PA00X+014203Y+101235                       
317m1191            VIA   -    MD0100PA00X+013653Y+101235X0200Y         S0      
327m1192            U314  -3          A01X+081266Y+116397X0170Y0460     S1      
317m1192            VIA   -    M      A01X+081002Y+116777X0200Y         S2      
017m1192            VIA   -    M      A18X+081002Y+116777X0260Y         S2      
017m1192                  -    MD0100PA00X+081002Y+116777                       
327m1192            R3941 -2   M      A01X+081102Y+117112X0198Y0197     S1      
327m1192            R3926 -2          A01X+080750Y+117509X0198Y0197R270 S1      
327m1192            R4016 -2   M      A01X+081150Y+117509X0198Y0197R270 S1      
317m1193            VIA   -    MD0100PA00X+137896Y+072246X0200Y         S0      
317m1193            VIA   -    MD0100PA00X+124811Y+100470X0200Y         S0      
317m1193            VIA   -    MD0100PA00X+127579Y+113473X0200Y         S0      
327m1193            R3982 -1          A01X+127592Y+113713X0198Y0197R090 S1      
327m1193            U347  -22         A01X+137402Y+072246X0160Y0540R270 S1      
327m1193            U348  -22         A01X+137402Y+067546X0160Y0540R270 S1      
317m1193            VIA   -    M      A01X+137896Y+067546X0200Y         S2      
017m1193            VIA   -    M      A18X+137896Y+067546X0260Y         S2      
017m1193                  -    MD0100PA00X+137896Y+067546                       
317SSD9_PWRDIS_R    VIA   -    MD0100PA00X+123829Y+031730X0200Y         S0      
317SSD9_PWRDIS_R    VIA   -    MD0100PA00X+132500Y+078800X0200Y         S0      
327SSD9_PWRDIS_R    R4120 -2          A01X+132500Y+079042X0198Y0197R270 S1      
317SSD9_PWRDIS_R    VIA   -    MD0100PA00X+117804Y+031219X0200Y         S0      
327SSD9_PWRDIS_R    R6207 -2          A01X+111364Y+011449X0198Y0197R180 S1      
317SSD9_PWRDIS_R    VIA   -    MD0100PA00X+111155Y+011208X0200Y         S0      
317SSD9_PWRDIS_R    VIA   -    M      A01X+107241Y+009996X0200Y         S2      
017SSD9_PWRDIS_R    VIA   -    M      A18X+107241Y+009996X0260Y         S2      
017SSD9_PWRDIS_R          -    MD0100PA00X+107241Y+009996                       
327SSD9_PWRDIS_R    J39   -B12        A01X+107663Y+009996X0150Y0500R090 S1      
327SSD0_LED         VIA   -    M      A01X+082020Y+033215X0300Y         S1      
327SSD0_LED         R4302 -2          A01X+081505Y+033337X0198Y0197     S1      
327SSD0_LED         U330  -4          A01X+083296Y+032977X0160Y0540R270 S1      
317m1194            VIA   -    MD0100PA00X+136730Y+085192X0180Y         S0      
327m1194            U6    -R17        A01X+136572Y+085349X0160Y         S1      
317m1194            VIA   -    MD0100PA00X+090063Y+091524X0200Y         S0      
317m1194            VIA   -    M      A01X+105036Y+083779X0200Y         S2      
017m1194            VIA   -    M      A18X+105036Y+083779X0260Y         S2      
017m1194                  -    MD0100PA00X+105036Y+083779                       
317m1194            VIA   -    MD0100PA00X+103562Y+075581X0200Y         S0      
327m1194            R4538 -1          A01X+090020Y+091268X0198Y0197R270 S1      
327JTAG_BIC_EN      VIA   -    M      A18X+088612Y+083230X0280Y         S2      
327JTAG_BIC_EN      R4898 -2          A18X+088387Y+082356X0198Y0197R270 S2      
327JTAG_BIC_EN      U5    -C12        A01X+089239Y+084372X0160Y    R180 S1      
317JTAG_BIC_EN      VIA   -    MD0100PA00X+089082Y+084214X0180Y    R270 S0      
317m1195            VIA   -    MD0100PA00X+009350Y+154777X0200Y         S0      
317m1195            VIA   -    MD0100PA00X+084838Y+083946X0200Y         S0      
327m1195            R5770 -1          A18X+085368Y+083946X0198Y0197R180 S2      
327m1195            R5531 -2   M      A18X+084588Y+083946X0198Y0197R180 S2      
327m1195            R5530 -2          A18X+084384Y+084349X0198Y0197R180 S2      
317m1195            VIA   -    MD0100PA00X+086333Y+100939X0200Y         S0      
327m1195            R6181 -1   M      A01X+042146Y+156658X0198Y0197R270 S1      
317m1195            VIA   -    MD0100PA00X+090870Y+131630X0200Y         S0      
317m1195            VIA   -    M      A01X+076040Y+144028X0200Y         S2      
017m1195            VIA   -    M      A18X+076040Y+144028X0260Y         S2      
017m1195                  -    MD0100PA00X+076040Y+144028                       
327m1195            R6757 -1          A01X+001085Y+153855X0198Y0197R090 S1      
317m1195            VIA   -    MD0100PA00X+000695Y+153855X0200Y         S0      
327m1196            C3023 -1          A18X+018810Y+118035X0120Y0150R090 S2      
327m1196            C3022 -1          A18X+018810Y+118320X0120Y0150R270 S2      
327m1196            PEX0  -AA13       A01X+018996Y+117992X0180Y         S1      
317m1196            VIA   -    MD0080PA00X+018809Y+118179X0160Y    R270 S0      
327m1196            C3021 -1          A01X+012815Y+117331X0280Y0320R270 S1      
327m1196            R4558 -1          A01X+012760Y+116868X0198Y0197R270 S1      
327m1196            L88   -2          A01X+012245Y+117241X0440Y0540R180 S1      
317m1196            VIA   -    M      A01X+013043Y+117016X0200Y         S2      
017m1196            VIA   -    M      A18X+013043Y+117016X0260Y         S2      
017m1196                  -    MD0100PA00X+013043Y+117016                       
317m1196            VIA   -    MD0100PA00X+012447Y+116820X0200Y         S0      
327m1197            VIA   -    M      A01X+129986Y+086231X0300Y         S1      
327m1197            U6    -M1         A01X+131533Y+086294X0160Y         S1      
327m1197            R4163 -2          A01X+129108Y+085950X0198Y0197     S1      
327m1198            R4121 -2          A01X+132100Y+080642X0198Y0197R270 S1      
317m1198            VIA   -    M      A01X+132100Y+080400X0200Y         S2      
017m1198            VIA   -    M      A18X+132100Y+080400X0260Y         S2      
017m1198                  -    MD0100PA00X+132100Y+080400                       
317m1198            VIA   -    MD0100PA00X+123220Y+031696X0200Y         S0      
317m1198            VIA   -    MD0100PA00X+118171Y+031013X0200Y         S0      
317m1198            VIA   -    MD0100PA00X+107246Y+009524X0200Y         S0      
327m1198            J39   -B10        A01X+107663Y+009524X0150Y0500R090 S1      
327SSD1_LED         VIA   -    M      A01X+082598Y+032721X0300Y         S1      
327SSD1_LED         R4303 -2          A01X+081505Y+032937X0198Y0197     S1      
327SSD1_LED         U330  -5          A01X+083296Y+032721X0160Y0540R270 S1      
317m1199            VIA   -    MD0100PA00X+131691Y+085507X0180Y         S0      
327m1199            U6    -P2         A01X+131848Y+085664X0160Y         S1      
317m1199            VIA   -    MD0100PA00X+090863Y+091804X0200Y         S0      
317m1199            VIA   -    M      A01X+104604Y+084122X0200Y         S2      
017m1199            VIA   -    M      A18X+104604Y+084122X0260Y         S2      
017m1199                  -    MD0100PA00X+104604Y+084122                       
317m1199            VIA   -    MD0100PA00X+103868Y+077675X0200Y         S0      
327m1199            R4543 -1          A18X+090729Y+091191X0198Y0197R090 S2      
327m1200            VIA   -    M      A01X+095369Y+069658X0300Y         S1      
327m1200            U327  -1          A01X+093241Y+069688X0220Y0530R180 S1      
327m1200            R4249 -2          A01X+095355Y+070126X0198Y0197R270 S1      
327m1201            R4571 -2          A01X+059634Y+102240X0198Y0197R270 S1      
327m1201            C3222 -1          A01X+059007Y+102297X0280Y0320R090 S1      
317m1201            VIA   -           A01X+059366Y+102195X0200Y         S2      
017m1201            VIA   -           A18X+059366Y+102195X0260Y         S2      
017m1201                  -     D0100PA00X+059366Y+102195                       
317m1202            VIA   -    M      A01X+143753Y+074328X0200Y    R180 S2      
017m1202            VIA   -    M      A18X+143753Y+074328X0260Y    R180 S2      
017m1202                  -    MD0100PA00X+143753Y+074328                       
327m1202            R4644 -1          A01X+142358Y+074100X0198Y0197R180 S1      
327m1202            U344  -6          A01X+144198Y+074328X0160Y0540R270 S1      
317m1203            VIA   -    M      A01X+082331Y+118024X0200Y         S2      
017m1203            VIA   -    M      A18X+082331Y+118024X0260Y         S2      
017m1203                  -    MD0100PA00X+082331Y+118024                       
327m1203            R3927 -2          A01X+081685Y+118205X0198Y0197R270 S1      
327m1203            R3932 -2   M      A01X+082082Y+118209X0198Y0197R270 S1      
327m1203            R3928 -1          A01X+082083Y+117829X0198Y0197R270 S1      
327m1204            U315  -5          A01X+126689Y+114684X0240Y0460     S1      
317m1204            VIA   -    M      A01X+126672Y+114267X0200Y         S2      
017m1204            VIA   -    M      A18X+126672Y+114267X0260Y         S2      
017m1204                  -    MD0100PA00X+126672Y+114267                       
327m1204            R3984 -2          A01X+125592Y+114028X0198Y0197R090 S1      
317SSD8_PWRDIS_R    VIA   -    M      A01X+097004Y+009996X0200Y         S2      
017SSD8_PWRDIS_R    VIA   -    M      A18X+097004Y+009996X0260Y         S2      
017SSD8_PWRDIS_R          -    MD0100PA00X+097004Y+009996                       
327SSD8_PWRDIS_R    J38   -B12        A01X+097427Y+009996X0150Y0500R090 S1      
327SSD8_PWRDIS_R    R6206 -2          A01X+101128Y+011449X0198Y0197R180 S1      
317SSD8_PWRDIS_R    VIA   -    MD0100PA00X+100919Y+011208X0200Y         S0      
317SSD8_PWRDIS_R    VIA   -    MD0100PA00X+108562Y+033982X0200Y         S0      
327SSD8_PWRDIS_R    R4116 -2          A01X+131300Y+080642X0198Y0197R270 S1      
317SSD8_PWRDIS_R    VIA   -    MD0100PA00X+131300Y+080400X0200Y         S0      
317SSD8_PWRDIS_R    VIA   -    MD0100PA00X+122260Y+036925X0200Y         S0      
317m1205            VIA   -    M      A01X+082263Y+034807X0200Y         S2      
017m1205            VIA   -    M      A18X+082263Y+034807X0260Y         S2      
017m1205                  -    MD0100PA00X+082263Y+034807                       
327m1205            R4261 -2          A01X+080705Y+034637X0198Y0197     S1      
327m1205            R4267 -1   M      A01X+081190Y+034637X0198Y0197     S1      
327m1205            U330  -2          A01X+083296Y+033488X0160Y0540R270 S1      
327m1206            C3247 -1          A01X+057842Y+110311X0280Y0320R090 S1      
327m1206            R4576 -2          A01X+058469Y+110253X0198Y0197R270 S1      
317m1206            VIA   -           A01X+058201Y+110209X0200Y         S2      
017m1206            VIA   -           A18X+058201Y+110209X0260Y         S2      
017m1206                  -     D0100PA00X+058201Y+110209                       
327m1207            U315  -6   M      A01X+126974Y+114684X0170Y0460     S1      
327m1207            R3979 -1          A01X+125992Y+114028X0198Y0197R270 S1      
327m1207            R3983 -2   M      A01X+126392Y+114028X0198Y0197R090 S1      
327m1207            R3986 -2   M      A01X+126792Y+114028X0198Y0197R090 S1      
327m1207            R3987 -1          A01X+126495Y+117112X0198Y0197     S1      
317m1207            VIA   -    M      A01X+126859Y+115754X0200Y         S2      
017m1207            VIA   -    M      A18X+126859Y+115754X0260Y         S2      
017m1207                  -    MD0100PA00X+126859Y+115754                       
327m1208            VIA   -    M      A01X+129594Y+085550X0300Y         S1      
327m1208            U6    -P1         A01X+131533Y+085664X0160Y         S1      
327m1208            R4164 -2          A01X+129108Y+085550X0198Y0197     S1      
317m1209            VIA   -    MD0100PA00X+097009Y+009524X0200Y         S0      
327m1209            J38   -B10        A01X+097427Y+009524X0150Y0500R090 S1      
317m1209            VIA   -    M      A01X+109255Y+034032X0200Y         S2      
017m1209            VIA   -    M      A18X+109255Y+034032X0260Y         S2      
017m1209                  -    MD0100PA00X+109255Y+034032                       
327m1209            R4117 -2          A01X+131700Y+080642X0198Y0197R270 S1      
317m1209            VIA   -    MD0100PA00X+131700Y+080400X0200Y         S0      
317m1209            VIA   -    MD0100PA00X+122912Y+036936X0200Y         S0      
317m1210            VIA   -    M      A01X+095595Y+073418X0200Y         S2      
017m1210            VIA   -    M      A18X+095595Y+073418X0260Y         S2      
017m1210                  -    MD0100PA00X+095595Y+073418                       
327m1210            R4250 -2          A01X+095595Y+073161X0198Y0197R090 S1      
327m1210            R5479 -2          A01X+094756Y+070520X0198Y0197R090 S1      
327m1210            U358  -2   M      A01X+094609Y+071215X0220Y0560     S1      
327m1211            R4570 -2          A01X+058469Y+115293X0198Y0197R270 S1      
327m1211            C3206 -1          A01X+057842Y+115351X0280Y0320R090 S1      
317m1211            VIA   -           A01X+058201Y+115249X0200Y         S2      
017m1211            VIA   -           A18X+058201Y+115249X0260Y         S2      
017m1211                  -     D0100PA00X+058201Y+115249                       
327m1212            R3988 -1          A01X+127510Y+117112X0198Y0197R180 S1      
317m1212            VIA   -    M      A01X+127505Y+115740X0200Y         S2      
017m1212            VIA   -    M      A18X+127505Y+115740X0260Y         S2      
017m1212                  -    MD0100PA00X+127505Y+115740                       
327m1212            U315  -7   M      A01X+127230Y+114684X0170Y0460     S1      
327m1212            R3978 -1          A01X+127992Y+114028X0198Y0197R270 S1      
327m1212            R3982 -2   M      A01X+127592Y+114028X0198Y0197R090 S1      
327m1212            R3985 -2   M      A01X+127192Y+114028X0198Y0197R090 S1      
327m1213            R4575 -2          A01X+058469Y+111513X0198Y0197R270 S1      
327m1213            C3236 -1          A01X+057842Y+111571X0280Y0320R090 S1      
317m1213            VIA   -           A01X+058201Y+111469X0200Y         S2      
017m1213            VIA   -           A18X+058201Y+111469X0260Y         S2      
017m1213                  -     D0100PA00X+058201Y+111469                       
317m1214            VIA   -    M      A01X+080521Y+118018X0200Y         S2      
017m1214            VIA   -    M      A18X+080521Y+118018X0260Y         S2      
017m1214                  -    MD0100PA00X+080521Y+118018                       
327m1214            R3926 -1          A01X+080750Y+117824X0198Y0197R270 S1      
327m1214            R3925 -2          A01X+081153Y+118206X0198Y0197R270 S1      
327m1214            R3931 -2   M      A01X+080753Y+118206X0198Y0197R270 S1      
327m1215            U315  -2          A01X+127230Y+116397X0170Y0460     S1      
317m1215            VIA   -    M      A01X+127212Y+116777X0200Y         S2      
017m1215            VIA   -    M      A18X+127212Y+116777X0260Y         S2      
017m1215                  -    MD0100PA00X+127212Y+116777                       
327m1215            R3973 -2          A01X+127791Y+117514X0198Y0197R270 S1      
327m1215            R4017 -2   M      A01X+127391Y+117514X0198Y0197R270 S1      
327m1215            R3988 -2   M      A01X+127195Y+117112X0198Y0197R180 S1      
327m1216            VIA   -           A18X+041003Y+155542X0260Y         S2      
327m1216            C3634 -1          A18X+041646Y+154720X0198Y0197     S2      
327m1216            R5442 -2          A18X+041582Y+155620X0198Y0197R090 S2      
317m1216            VIA   -    MD0100PA00X+041815Y+155247X0200Y    R090 S0      
327m1216            U353  -14         A01X+041649Y+154982X0100Y0290R090 S1      
327m1216            C3631 -1          A18X+039694Y+154720X0198Y0197R180 S2      
327m1216            C3632 -1          A18X+040405Y+155352X0198Y0197R090 S2      
317m1216            VIA   -    M      A01X+039937Y+155586X0200Y    R090 S2      
017m1216            VIA   -    M      A18X+039937Y+155586X0260Y    R090 S2      
017m1216                  -    MD0100PA00X+039937Y+155586                       
327m1216            U353  -21         A01X+040109Y+155341X0100Y0290R180 S1      
327m1216            C3628 -1          A18X+041646Y+154122X0198Y0197     S2      
327m1216            VIA   -           A18X+041542Y+153228X0260Y         S2      
317m1216            VIA   -    MD0100PA00X+041962Y+153998X0200Y    R090 S0      
327m1216            U353  -9          A01X+041649Y+153998X0100Y0290R090 S1      
327m1216            C3627 -1          A18X+039694Y+154070X0198Y0197R180 S2      
327m1216            C3629 -1          A18X+040998Y+153391X0198Y0197R270 S2      
327m1216            C3633 -1          A18X+040416Y+153391X0198Y0197R270 S2      
327m1216            C3630 -1          A18X+039694Y+153520X0198Y0197R180 S2      
317m1216            VIA   -    MD0100PA00X+040896Y+153115X0200Y    R090 S0      
327m1216            U353  -5          A01X+040896Y+153442X0100Y0290R180 S1      
327m1216            U353  -28         A01X+039750Y+153801X0100Y0290R090 S1      
327m1216            U353  -27         A01X+039750Y+153998X0100Y0290R090 S1      
317m1216            VIA   -    MD0100PA00X+039439Y+153529X0200Y    R090 S0      
317m1216            VIA   -    MD0100PA00X+039439Y+153779X0200Y    R090 S0      
327m1217            R4568 -2          A01X+058469Y+116553X0198Y0197R270 S1      
327m1217            C3204 -1          A01X+057842Y+116611X0280Y0320R090 S1      
317m1217            VIA   -           A01X+058201Y+116509X0200Y         S2      
017m1217            VIA   -           A18X+058201Y+116509X0260Y         S2      
017m1217                  -     D0100PA00X+058201Y+116509                       
317I2C0_PEX1_SCL    VIA   -    MD0080PA00X+073120Y+121171X0160Y         S0      
327I2C0_PEX1_SCL    PEX1  -M35        A01X+072933Y+121358X0180Y         S1      
327I2C0_PEX1_SCL    R3927 -1          A01X+081685Y+118520X0198Y0197R270 S1      
317I2C0_PEX1_SCL    VIA   -    M      A01X+081888Y+118731X0200Y         S2      
017I2C0_PEX1_SCL    VIA   -    M      A18X+081888Y+118731X0260Y         S2      
017I2C0_PEX1_SCL          -    MD0100PA00X+081888Y+118731                       
327P0V8_PEX3_PWM2   PU15  -34         A01X+142808Y+111023X0090Y0240R180 S1      
317P0V8_PEX3_PWM2   VIA   -    MD0100PA00X+142888Y+110479X0200Y         S0      
317P0V8_PEX3_PWM2   VIA   -    M      A01X+138919Y+099257X0200Y    R090 S2      
017P0V8_PEX3_PWM2   VIA   -    M      A18X+138919Y+099257X0260Y    R090 S2      
017P0V8_PEX3_PWM2         -    MD0100PA00X+138919Y+099257                       
327P0V8_PEX3_PWM2   PU11  -2          A01X+138416Y+100785X0070Y0240     S1      
327m1218            R4569 -2          A01X+058469Y+117813X0198Y0197R270 S1      
327m1218            C3205 -1          A01X+057842Y+117871X0280Y0320R090 S1      
317m1218            VIA   -           A01X+058201Y+117769X0200Y         S2      
017m1218            VIA   -           A18X+058201Y+117769X0260Y         S2      
017m1218                  -     D0100PA00X+058201Y+117769                       
317I2C0_PEX1_SDA    VIA   -    MD0080PA00X+074242Y+121171X0160Y         S0      
327I2C0_PEX1_SDA    PEX1  -M39        A01X+074429Y+121358X0180Y         S1      
327I2C0_PEX1_SDA    R3925 -1          A01X+081153Y+118520X0198Y0197R270 S1      
317I2C0_PEX1_SDA    VIA   -    M      A01X+081417Y+118520X0200Y         S2      
017I2C0_PEX1_SDA    VIA   -    M      A18X+081417Y+118520X0260Y         S2      
017I2C0_PEX1_SDA          -    MD0100PA00X+081417Y+118520                       
327m1219            U315  -3          A01X+126974Y+116397X0170Y0460     S1      
317m1219            VIA   -    M      A01X+126710Y+116777X0200Y         S2      
017m1219            VIA   -    M      A18X+126710Y+116777X0260Y         S2      
017m1219                  -    MD0100PA00X+126710Y+116777                       
327m1219            R3971 -2          A01X+126459Y+117509X0198Y0197R270 S1      
327m1219            R4018 -2   M      A01X+126859Y+117509X0198Y0197R270 S1      
327m1219            R3987 -2   M      A01X+126810Y+117112X0198Y0197     S1      
327m1220            R4573 -2          A01X+059634Y+100980X0198Y0197R270 S1      
327m1220            C3224 -1          A01X+059007Y+101037X0280Y0320R090 S1      
317m1220            VIA   -           A01X+059366Y+100935X0200Y         S2      
017m1220            VIA   -           A18X+059366Y+100935X0260Y         S2      
017m1220                  -     D0100PA00X+059366Y+100935                       
327m1221            J40   -B10        A01X+117900Y+009524X0150Y0500R090 S1      
317m1221            VIA   -    MD0100PA00X+123490Y+031694X0200Y         S0      
317m1221            VIA   -    M      A01X+126662Y+032246X0200Y         S2      
017m1221            VIA   -    M      A18X+126662Y+032246X0260Y         S2      
017m1221                  -    MD0100PA00X+126662Y+032246                       
317m1221            VIA   -    MD0100PA00X+132100Y+078800X0200Y         S0      
327m1221            R4125 -2          A01X+132100Y+079042X0198Y0197R270 S1      
317m1221            VIA   -    MD0100PA00X+117482Y+009524X0200Y         S0      
327m1222            VIA   -    M      A01X+089165Y+090077X0300Y    R090 S1      
327m1222            R4542 -2          A01X+088863Y+090951X0198Y0197R270 S1      
327m1222            U5    -T11        A01X+089554Y+088466X0160Y    R180 S1      
327JTAG_BIC_TMS     VIA   -    M      A18X+089384Y+083245X0280Y         S2      
327JTAG_BIC_TMS     U5    -B11        A01X+089554Y+084057X0160Y    R180 S1      
317JTAG_BIC_TMS     VIA   -    MD0100PA00X+089397Y+083899X0180Y         S0      
327JTAG_BIC_TMS     R4894 -2          A18X+089192Y+082356X0198Y0197R270 S2      
327m1223            R4572 -2          A01X+058469Y+114033X0198Y0197R270 S1      
327m1223            C3223 -1          A01X+057842Y+114091X0280Y0320R090 S1      
317m1223            VIA   -           A01X+058201Y+113989X0200Y         S2      
017m1223            VIA   -           A18X+058201Y+113989X0260Y         S2      
017m1223                  -     D0100PA00X+058201Y+113989                       
317m1224            VIA   -    M      A01X+128040Y+118024X0200Y         S2      
017m1224            VIA   -    M      A18X+128040Y+118024X0260Y         S2      
017m1224                  -    MD0100PA00X+128040Y+118024                       
327m1224            R3972 -2          A01X+127393Y+118205X0198Y0197R270 S1      
327m1224            R3977 -2   M      A01X+127790Y+118209X0198Y0197R270 S1      
327m1224            R3973 -1          A01X+127791Y+117829X0198Y0197R270 S1      
327SSD10_PWRDIS_R   J40   -B12        A01X+117900Y+009996X0150Y0500R090 S1      
317SSD10_PWRDIS_R   VIA   -    M      A01X+117477Y+009996X0200Y         S2      
017SSD10_PWRDIS_R   VIA   -    M      A18X+117477Y+009996X0260Y         S2      
017SSD10_PWRDIS_R         -    MD0100PA00X+117477Y+009996                       
327SSD10_PWRDIS_R   R6208 -2          A01X+121600Y+011449X0198Y0197R180 S1      
317SSD10_PWRDIS_R   VIA   -    MD0100PA00X+121392Y+011208X0200Y         S0      
317SSD10_PWRDIS_R   VIA   -    MD0100PA00X+126333Y+030900X0200Y         S0      
327SSD10_PWRDIS_R   R4124 -2          A18X+131950Y+081642X0198Y0197R090 S2      
317SSD10_PWRDIS_R   VIA   -    MD0100PA00X+131900Y+081162X0200Y         S0      
327m1225            VIA   -    M      A18X+090659Y+090084X0260Y         S2      
327m1225            R4543 -2          A18X+090729Y+090876X0198Y0197R090 S2      
327m1225            U5    -N11        A01X+089554Y+087521X0160Y    R180 S1      
317m1225            VIA   -    MD0100PA00X+089397Y+087679X0180Y    R270 S0      
327JTAG_BIC_TCK     VIA   -    M      A18X+089884Y+083191X0280Y         S2      
317JTAG_BIC_TCK     VIA   -    MD0100PA00X+089712Y+084529X0180Y    R270 S0      
327JTAG_BIC_TCK     U5    -D10        A01X+089869Y+084687X0160Y    R180 S1      
327JTAG_BIC_TCK     R4895 -2          A18X+089587Y+082356X0198Y0197R270 S2      
327m1226            R4574 -2          A01X+058469Y+112773X0198Y0197R270 S1      
327m1226            C3235 -1          A01X+057842Y+112831X0280Y0320R090 S1      
317m1226            VIA   -           A01X+058201Y+112729X0200Y         S2      
017m1226            VIA   -           A18X+058201Y+112729X0260Y         S2      
017m1226                  -     D0100PA00X+058201Y+112729                       
317m1227            VIA   -    M      A01X+126230Y+118018X0200Y         S2      
017m1227            VIA   -    M      A18X+126230Y+118018X0260Y         S2      
017m1227                  -    MD0100PA00X+126230Y+118018                       
327m1227            R3971 -1          A01X+126459Y+117824X0198Y0197R270 S1      
327m1227            R3970 -2          A01X+126862Y+118206X0198Y0197R270 S1      
327m1227            R3976 -2   M      A01X+126462Y+118206X0198Y0197R270 S1      
327m1228            J41   -B10        A01X+128136Y+009524X0150Y0500R090 S1      
317m1228            VIA   -    M      A01X+134401Y+027905X0200Y         S2      
017m1228            VIA   -    M      A18X+134401Y+027905X0260Y         S2      
017m1228                  -    MD0100PA00X+134401Y+027905                       
317m1228            VIA   -    MD0100PA00X+127718Y+009524X0200Y         S0      
327m1228            R4129 -2          A18X+133750Y+081642X0198Y0197R090 S2      
317m1228            VIA   -    MD0100PA00X+133500Y+081162X0200Y         S0      
327m1229            VIA   -    M      A01X+092766Y+082101X0300Y    R270 S1      
327m1229            R3286 -1   M      A01X+093192Y+081146X0198Y0197R090 S1      
327m1229            D7    -C          A01X+093212Y+080621X0240Y0280R090 S1      
327m1229            U5    -A2         A01X+092389Y+083742X0160Y    R180 S1      
317m1230            VIA   -    MD0080PA00X+116585Y+121171X0160Y    R270 S0      
327m1230            PEX2  -M29        A01X+116398Y+121358X0180Y         S1      
317m1230            VIA   -    M      A01X+128060Y+118524X0200Y         S2      
017m1230            VIA   -    M      A18X+128060Y+118524X0260Y         S2      
017m1230                  -    MD0100PA00X+128060Y+118524                       
327m1230            R3977 -1          A01X+127790Y+118524X0198Y0197R270 S1      
317PRSNT_NIC6_R_N   VIA   -    MD0100PA00X+145143Y+067325X0200Y         S0      
317PRSNT_NIC6_R_N   VIA   -    MD0100PA00X+138305Y+086137X0180Y         S0      
327PRSNT_NIC6_R_N   U5    -R1         A01X+092704Y+088151X0160Y    R180 S1      
317PRSNT_NIC6_R_N   VIA   -    MD0100PA00X+092861Y+088309X0180Y    R270 S0      
317PRSNT_NIC6_R_N   VIA   -    MD0100PA00X+098379Y+076565X0200Y         S0      
327PRSNT_NIC6_R_N   U6    -M22        A01X+138147Y+086294X0160Y         S1      
317PRSNT_NIC6_R_N   VIA   -    MD0100PA00X+156155Y+066546X0200Y         S0      
327PRSNT_NIC6_R_N   C4004 -1          A01X+149850Y+044866X0198Y0197R270 S1      
327PRSNT_NIC6_R_N   R349  -1   M      A01X+149850Y+045251X0198Y0197R090 S1      
327PRSNT_NIC6_R_N   U39   -G   M      A01X+150436Y+045075X0400Y0560     S1      
317PRSNT_NIC6_R_N   VIA   -    M      A01X+151664Y+045871X0200Y         S2      
017PRSNT_NIC6_R_N   VIA   -    M      A18X+151664Y+045871X0260Y         S2      
017PRSNT_NIC6_R_N         -    MD0100PA00X+151664Y+045871                       
317m1231            VIA   -    M      A01X+077216Y+033258X0200Y         S2      
017m1231            VIA   -    M      A18X+077216Y+033258X0260Y         S2      
017m1231                  -    MD0100PA00X+077216Y+033258                       
327m1231            U26   -2          A01X+077736Y+033258X0220Y0530R090 S1      
317m1231            VIA   -    MD0100PA00X+141350Y+088800X0200Y         S0      
317m1231            VIA   -    MD0100PA00X+082389Y+070342X0200Y         S0      
327m1231            R3631 -2          A01X+141108Y+088800X0198Y0197     S1      
327SSD11_PWRDIS_R   J41   -B12        A01X+128136Y+009996X0150Y0500R090 S1      
317SSD11_PWRDIS_R   VIA   -    M      A01X+127713Y+009996X0200Y         S2      
017SSD11_PWRDIS_R   VIA   -    M      A18X+127713Y+009996X0260Y         S2      
017SSD11_PWRDIS_R         -    MD0100PA00X+127713Y+009996                       
327SSD11_PWRDIS_R   R6209 -2          A01X+131836Y+011449X0198Y0197R180 S1      
317SSD11_PWRDIS_R   VIA   -    MD0100PA00X+131628Y+011208X0200Y         S0      
317SSD11_PWRDIS_R   VIA   -    MD0100PA00X+134010Y+027912X0200Y         S0      
317SSD11_PWRDIS_R   VIA   -    MD0100PA00X+127157Y+028118X0200Y         S0      
317SSD11_PWRDIS_R   VIA   -    MD0100PA00X+132900Y+078800X0200Y         S0      
327SSD11_PWRDIS_R   R4128 -2          A01X+132900Y+079042X0198Y0197R270 S1      
327m1232            C3217 -1          A18X+064060Y+116250X0120Y0150     S2      
327m1232            C3218 -1   M      A18X+064060Y+115935X0120Y0150     S2      
317m1232            VIA   -    MD0080PA00X+064144Y+115935X0160Y         S0      
327m1232            PEX1  -AF12       A01X+064331Y+116122X0180Y         S1      
317m1232            VIA   -    M      A01X+058747Y+114289X0200Y         S2      
017m1232            VIA   -    M      A18X+058747Y+114289X0260Y         S2      
017m1232                  -    MD0100PA00X+058747Y+114289                       
317m1232            VIA   -    MD0100PA00X+058197Y+114289X0200Y         S0      
327m1232            L108  -2          A01X+057954Y+114721X0440Y0540R180 S1      
327m1232            C3216 -1          A01X+058524Y+114811X0280Y0320R270 S1      
327m1232            R4572 -1          A01X+058469Y+114348X0198Y0197R270 S1      
317m1233            VIA   -    MD0080PA00X+116210Y+121171X0160Y    R270 S0      
327m1233            PEX2  -M28        A01X+116024Y+121358X0180Y         S1      
327m1233            R3976 -1          A01X+126462Y+118520X0198Y0197R270 S1      
317m1233            VIA   -    M      A01X+126260Y+118722X0200Y         S2      
017m1233            VIA   -    M      A18X+126260Y+118722X0260Y         S2      
017m1233                  -    MD0100PA00X+126260Y+118722                       
317m1234            VIA   -    MD0100PA00X+140476Y+110690X0200Y    R090 S0      
327m1234            PU14  -38         A01X+140304Y+111023X0090Y0240R180 S1      
327m1234            PU11  -30         A01X+138258Y+102675X0070Y0240     S1      
317m1234            VIA   -    M      A01X+138593Y+103866X0200Y    R090 S2      
017m1234            VIA   -    M      A18X+138593Y+103866X0260Y    R090 S2      
017m1234                  -    MD0100PA00X+138593Y+103866                       
327m1235            C3214 -1          A18X+064518Y+116425X0120Y0150R090 S2      
327m1235            C3215 -1          A18X+064518Y+116725X0120Y0150R270 S2      
317m1235            VIA   -    MD0080PA00X+064518Y+116683X0160Y         S0      
327m1235            PEX1  -AE13       A01X+064705Y+116496X0180Y         S1      
327m1235            C3213 -1          A01X+059689Y+103017X0280Y0320R270 S1      
327m1235            L107  -2          A01X+059119Y+102927X0440Y0540R180 S1      
327m1235            R4571 -1          A01X+059634Y+102555X0198Y0197R270 S1      
317m1235            VIA   -    MD0100PA00X+059361Y+102495X0200Y         S0      
317m1235            VIA   -    M      A01X+059911Y+102495X0200Y         S2      
017m1235            VIA   -    M      A18X+059911Y+102495X0260Y         S2      
017m1235                  -    MD0100PA00X+059911Y+102495                       
327m1236            PEX2  -N38        A01X+119764Y+120984X0180Y         S1      
317m1236            VIA   -    MD0080PA00X+119951Y+120797X0160Y         S0      
327m1236            R3975 -1          A01X+125602Y+119238X0198Y0197R180 S1      
327m1236            VIA   -    M      A18X+124606Y+120511X0260Y         S2      
317m1236            VIA   -    MD0100PA00X+125530Y+119606X0200Y         S0      
317m1237            VIA   -    M      A01X+138300Y+058132X0200Y         S2      
017m1237            VIA   -    M      A18X+138300Y+058132X0260Y         S2      
017m1237                  -    MD0100PA00X+138300Y+058132                       
327m1237            U350  -21         A01X+137402Y+058190X0160Y0540R270 S1      
327m1237            R4845 -2          A01X+138551Y+057719X0198Y0197R180 S1      
327m1237            R4829 -1   M      A01X+138551Y+058132X0198Y0197     S1      
327P0V8_PEX2_PWM2   PU13  -34         A01X+136249Y+111023X0090Y0240R180 S1      
317P0V8_PEX2_PWM2   VIA   -    MD0100PA00X+136329Y+110479X0200Y         S0      
327P0V8_PEX2_PWM2   PU11  -7          A01X+139203Y+100785X0070Y0240     S1      
317P0V8_PEX2_PWM2   VIA   -    M      A01X+139203Y+100438X0200Y    R090 S2      
017P0V8_PEX2_PWM2   VIA   -    M      A18X+139203Y+100438X0260Y    R090 S2      
017P0V8_PEX2_PWM2         -    MD0100PA00X+139203Y+100438                       
317m1238            VIA   -    MD0100PA00X+076527Y+015737X0200Y         S0      
327m1238            R5561 -1   M      A01X+076861Y+014775X0198Y0197R090 S1      
327m1238            R6067 -1          A01X+077542Y+013090X0198Y0197R270 S1      
327m1238            PU61  -11         A01X+078835Y+022506X0110Y0240     S1      
327m1238            C2891 -1          A01X+078274Y+023286X0198Y0197R090 S1      
317m1238            VIA   -    M      A01X+078677Y+022865X0200Y    R090 S2      
017m1238            VIA   -    M      A18X+078677Y+022865X0260Y    R090 S2      
017m1238                  -    MD0100PA00X+078677Y+022865                       
327m1239            C3234 -1          A18X+064214Y+114813X0120Y0150     S2      
327m1239            C3233 -1          A18X+064518Y+114731X0120Y0150R090 S2      
317m1239            VIA   -    MD0080PA00X+064518Y+114813X0160Y         S0      
327m1239            R4575 -1          A01X+058469Y+111828X0198Y0197R270 S1      
327m1239            L111  -2          A01X+057954Y+112201X0440Y0540R180 S1      
327m1239            C3232 -1          A01X+058524Y+112291X0280Y0320R270 S1      
317m1239            VIA   -    MD0100PA00X+058197Y+111769X0200Y         S0      
317m1239            VIA   -    M      A01X+058747Y+111769X0200Y         S2      
017m1239            VIA   -    M      A18X+058747Y+111769X0260Y         S2      
017m1239                  -    MD0100PA00X+058747Y+111769                       
327m1239            PEX1  -AJ13       A01X+064705Y+115000X0180Y         S1      
327m1240            R3974 -1          A01X+126054Y+120345X0198Y0197R090 S1      
317m1240            VIA   -    MD0100PA00X+126154Y+119981X0200Y         S0      
327m1240            VIA   -    M      A18X+125824Y+120312X0260Y         S2      
327m1240            PEX2  -L39        A01X+120138Y+121732X0180Y         S1      
317m1240            VIA   -    MD0080PA00X+119951Y+121545X0160Y         S0      
317m1241            VIA   -    M      A01X+134300Y+059046X0200Y    R180 S2      
017m1241            VIA   -    M      A18X+134300Y+059046X0260Y    R180 S2      
017m1241                  -    MD0100PA00X+134300Y+059046                       
327m1241            U350  -2          A01X+135098Y+058702X0160Y0540R270 S1      
327m1241            R4828 -1          A01X+132458Y+059050X0198Y0197R180 S1      
327m1241            R4844 -2   M      A01X+132942Y+059050X0198Y0197R180 S1      
327m1242            C3221 -1          A18X+064518Y+115725X0120Y0150R270 S2      
327m1242            C3220 -1          A18X+064518Y+115445X0120Y0150R090 S2      
327m1242            PEX1  -AG13       A01X+064705Y+115748X0180Y         S1      
317m1242            VIA   -    MD0080PA00X+064518Y+115561X0160Y         S0      
327m1242            R4573 -1          A01X+059634Y+101295X0198Y0197R270 S1      
327m1242            C3219 -1          A01X+059689Y+101757X0280Y0320R270 S1      
327m1242            L109  -2          A01X+059119Y+101667X0440Y0540R180 S1      
317m1242            VIA   -    M      A01X+059911Y+101235X0200Y         S2      
017m1242            VIA   -    M      A18X+059911Y+101235X0260Y         S2      
017m1242                  -    MD0100PA00X+059911Y+101235                       
317m1242            VIA   -    MD0100PA00X+059361Y+101235X0200Y         S0      
317I2C0_PEX2_SCL    VIA   -    MD0080PA00X+118829Y+121171X0160Y         S0      
327I2C0_PEX2_SCL    PEX2  -M35        A01X+118642Y+121358X0180Y         S1      
327I2C0_PEX2_SCL    R3972 -1          A01X+127393Y+118520X0198Y0197R270 S1      
317I2C0_PEX2_SCL    VIA   -    M      A01X+127596Y+118723X0200Y         S2      
017I2C0_PEX2_SCL    VIA   -    M      A18X+127596Y+118723X0260Y         S2      
017I2C0_PEX2_SCL          -    MD0100PA00X+127596Y+118723                       
317m1243            VIA   -    M      A01X+134052Y+058613X0200Y    R180 S2      
017m1243            VIA   -    M      A18X+134052Y+058613X0260Y    R180 S2      
017m1243                  -    MD0100PA00X+134052Y+058613                       
327m1243            U350  -3          A01X+135098Y+058446X0160Y0540R270 S1      
327m1243            R4827 -1          A01X+132458Y+058650X0198Y0197R180 S1      
327m1243            R4843 -2   M      A01X+132942Y+058650X0198Y0197R180 S1      
327m1244            VIA   -    M      A01X+129949Y+086844X0300Y         S1      
327m1244            U6    -K1         A01X+131533Y+086924X0160Y         S1      
327m1244            R4162 -1          A01X+129108Y+086700X0198Y0197R180 S1      
327HP_NIC1_EN       PU48  -11         A01X+038099Y+048048X0110Y0240R270 S1      
317HP_NIC1_EN       VIA   -    MD0100PA00X+034505Y+045433X0200Y         S0      
327HP_NIC1_EN       R4448 -1          A01X+039824Y+037348X0198Y0197R090 S1      
327HP_NIC1_EN       R906  -1   M      A01X+044375Y+042460X0198Y0197R180 S1      
317HP_NIC1_EN       VIA   -    MD0100PA00X+033540Y+054472X0200Y         S0      
317HP_NIC1_EN       VIA   -    MD0100PA00X+033708Y+055138X0200Y         S0      
327HP_NIC1_EN       R95   -2          A01X+032328Y+055014X0198Y0197R270 S1      
327HP_NIC1_EN       U14   -D   M      A01X+033268Y+055138X0400Y0560R180 S1      
317HP_NIC1_EN       VIA   -    M      A01X+038513Y+048738X0200Y         S2      
017HP_NIC1_EN       VIA   -    M      A18X+038513Y+048738X0260Y         S2      
017HP_NIC1_EN             -    MD0100PA00X+038513Y+048738                       
327HP_NIC1_EN       C2879 -1   M      A01X+038809Y+048738X0198Y0197     S1      
327HP_NIC1_EN       R5854 -1          A01X+034745Y+045433X0198Y0197     S1      
327m1245            VIA   -    M      A01X+077354Y+015486X0300Y         S1      
327m1245            R5561 -2          A01X+076861Y+015090X0198Y0197R090 S1      
327m1245            R5560 -2   M      A01X+076861Y+015486X0198Y0197R270 S1      
327m1245            U370  -D          A01X+078326Y+016196X0400Y0560     S1      
327m1246            C3231 -1          A18X+064060Y+115561X0120Y0150     S2      
327m1246            C3230 -1   M      A18X+064060Y+115187X0120Y0150     S2      
317m1246            VIA   -    MD0080PA00X+064144Y+115187X0160Y         S0      
327m1246            C3229 -1          A01X+058524Y+113551X0280Y0320R270 S1      
327m1246            R4574 -1          A01X+058469Y+113088X0198Y0197R270 S1      
327m1246            L110  -2          A01X+057954Y+113461X0440Y0540R180 S1      
317m1246            VIA   -    MD0100PA00X+058197Y+113029X0200Y         S0      
317m1246            VIA   -    M      A01X+058747Y+113029X0200Y         S2      
017m1246            VIA   -    M      A18X+058747Y+113029X0260Y         S2      
017m1246                  -    MD0100PA00X+058747Y+113029                       
327m1246            PEX1  -AH12       A01X+064331Y+115374X0180Y         S1      
317I2C0_PEX2_SDA    VIA   -    MD0080PA00X+119951Y+121171X0160Y         S0      
327I2C0_PEX2_SDA    PEX2  -M39        A01X+120138Y+121358X0180Y         S1      
327I2C0_PEX2_SDA    R3970 -1          A01X+126862Y+118520X0198Y0197R270 S1      
317I2C0_PEX2_SDA    VIA   -    M      A01X+127126Y+118520X0200Y         S2      
017I2C0_PEX2_SDA    VIA   -    M      A18X+127126Y+118520X0260Y         S2      
017I2C0_PEX2_SDA          -    MD0100PA00X+127126Y+118520                       
317m1247            VIA   -    M      A01X+134300Y+063696X0200Y    R180 S2      
017m1247            VIA   -    M      A18X+134300Y+063696X0260Y    R180 S2      
017m1247                  -    MD0100PA00X+134300Y+063696                       
327m1247            U349  -2          A01X+135098Y+063352X0160Y0540R270 S1      
327m1247            R4808 -1          A01X+132458Y+063700X0198Y0197R180 S1      
327m1247            R4825 -2   M      A01X+132942Y+063700X0198Y0197R180 S1      
327m1248            R4133 -2          A01X+134100Y+080642X0198Y0197R270 S1      
317m1248            VIA   -    MD0100PA00X+134100Y+080400X0200Y         S0      
327m1248            J42   -B10        A01X+143136Y+009524X0150Y0500R090 S1      
317m1248            VIA   -    M      A01X+139027Y+041758X0200Y         S2      
017m1248            VIA   -    M      A18X+139027Y+041758X0260Y         S2      
017m1248                  -    MD0100PA00X+139027Y+041758                       
317m1248            VIA   -    MD0100PA00X+146954Y+041680X0200Y         S0      
317m1248            VIA   -    MD0100PA00X+142718Y+009524X0200Y         S0      
317m1249            VIA   -    M      A01X+139104Y+081203X0200Y         S2      
017m1249            VIA   -    M      A18X+139104Y+081203X0260Y         S2      
017m1249                  -    MD0100PA00X+139104Y+081203                       
327m1249            R5779 -1          A01X+139054Y+080925X0198Y0197R270 S1      
327m1249            U6    -U12        A01X+134998Y+084719X0160Y         S1      
317m1249            VIA   -    MD0100PA00X+135155Y+084562X0180Y         S0      
317m1250            VIA   -    M      A01X+078719Y+014872X0200Y         S2      
017m1250            VIA   -    M      A18X+078719Y+014872X0260Y         S2      
017m1250                  -    MD0100PA00X+078719Y+014872                       
327m1250            U370  -G          A01X+077952Y+015330X0400Y0560     S1      
327m1250            R5562 -1          A01X+079006Y+014691X0198Y0197R270 S1      
327m1251            C3243 -1          A18X+064195Y+117490X0120Y0150     S2      
327m1251            C3242 -1   M      A18X+064518Y+117431X0120Y0150R090 S2      
317m1251            VIA   -    MD0080PA00X+064518Y+117431X0160Y    R270 S0      
327m1251            PEX1  -AC13       A01X+064705Y+117244X0180Y         S1      
327m1251            C3241 -1          A01X+058524Y+111031X0280Y0320R270 S1      
327m1251            L112  -2          A01X+057954Y+110941X0440Y0540R180 S1      
327m1251            R4576 -1          A01X+058469Y+110568X0198Y0197R270 S1      
317m1251            VIA   -    M      A01X+058747Y+110509X0200Y         S2      
017m1251            VIA   -    M      A18X+058747Y+110509X0260Y         S2      
017m1251                  -    MD0100PA00X+058747Y+110509                       
317m1251            VIA   -    MD0100PA00X+058197Y+110509X0200Y         S0      
317m1252            VIA   -    M      A01X+137896Y+062799X0200Y         S2      
017m1252            VIA   -    M      A18X+137896Y+062799X0260Y         S2      
017m1252                  -    MD0100PA00X+137896Y+062799                       
327m1252            U349  -21         A01X+137402Y+062840X0160Y0540R270 S1      
327m1252            R4809 -1          A01X+138551Y+062369X0198Y0197     S1      
327m1252            R4826 -2   M      A01X+138551Y+062782X0198Y0197R180 S1      
327m1253            R3624 -1          A01X+141108Y+088400X0198Y0197R180 S1      
327m1253            C4499 -1          A01X+068873Y+070351X0198Y0197R270 S1      
317m1253            VIA   -    MD0100PA00X+070360Y+070221X0200Y         S0      
327m1253            U439  -1   M      A01X+069979Y+070221X0140Y0440R270 S1      
317m1253            VIA   -    M      A01X+141350Y+088400X0200Y         S2      
017m1253            VIA   -    M      A18X+141350Y+088400X0260Y         S2      
017m1253                  -    MD0100PA00X+141350Y+088400                       
317m1253            VIA   -    MD0100PA00X+116377Y+071335X0200Y         S0      
327m1254            J43   -B10        A01X+153372Y+009524X0150Y0500R090 S1      
317m1254            VIA   -    MD0100PA00X+140297Y+039018X0200Y         S0      
317m1254            VIA   -    MD0100PA00X+134500Y+080400X0200Y         S0      
327m1254            R4137 -2          A01X+134500Y+080642X0198Y0197R270 S1      
317m1254            VIA   -    MD0100PA00X+152954Y+009524X0200Y         S0      
317m1254            VIA   -    M      A01X+159447Y+035098X0200Y         S2      
017m1254            VIA   -    M      A18X+159447Y+035098X0260Y         S2      
017m1254                  -    MD0100PA00X+159447Y+035098                       
327m1255            VIA   -    M      A01X+090169Y+082570X0300Y    R270 S1      
327m1255            U5    -A8         A01X+090499Y+083742X0160Y    R180 S1      
327m1255            R5296 -1          A01X+089992Y+080646X0198Y0197R270 S1      
327m1256            PU58  -11         A01X+068599Y+022506X0110Y0240     S1      
327m1256            R6066 -1          A01X+067306Y+013090X0198Y0197R270 S1      
327m1256            R5558 -1   M      A01X+066624Y+014775X0198Y0197R090 S1      
317m1256            VIA   -    MD0100PA00X+066290Y+015737X0200Y         S0      
327m1256            C2890 -1          A01X+068038Y+023286X0198Y0197R090 S1      
317m1256            VIA   -    M      A01X+068441Y+022865X0200Y    R090 S2      
017m1256            VIA   -    M      A18X+068441Y+022865X0260Y    R090 S2      
017m1256                  -    MD0100PA00X+068441Y+022865                       
327m1257            C3203 -1          A18X+064060Y+116683X0120Y0150     S2      
327m1257            C3202 -1   M      A18X+064060Y+117057X0120Y0150     S2      
317m1257            VIA   -    MD0080PA00X+064144Y+117057X0160Y         S0      
327m1257            PEX1  -AD12       A01X+064331Y+116870X0180Y         S1      
317m1257            VIA   -    M      A01X+058747Y+115549X0200Y         S2      
017m1257            VIA   -    M      A18X+058747Y+115549X0260Y         S2      
017m1257                  -    MD0100PA00X+058747Y+115549                       
317m1257            VIA   -    MD0100PA00X+058197Y+115549X0200Y         S0      
327m1257            R4570 -1          A01X+058469Y+115608X0198Y0197R270 S1      
327m1257            L106  -2          A01X+057954Y+115981X0440Y0540R180 S1      
327m1257            C3201 -1          A01X+058524Y+116071X0280Y0320R270 S1      
327m1258            PEX1  -L26        A01X+069567Y+121732X0180Y         S1      
317m1258            VIA   -    MD0080PA00X+069567Y+121732X0160Y    R090 S0      
317m1258            VIA   -    MD0100PA00X+081515Y+122602X0200Y         S0      
327m1258            VIA   -    M      A18X+081240Y+122876X0260Y         S2      
327m1258            R3944 -1          A01X+081674Y+122347X0198Y0197R315 S1      
317m1259            VIA   -    M      A01X+134052Y+063263X0200Y    R180 S2      
017m1259            VIA   -    M      A18X+134052Y+063263X0260Y    R180 S2      
017m1259                  -    MD0100PA00X+134052Y+063263                       
327m1259            U349  -3          A01X+135098Y+063096X0160Y0540R270 S1      
327m1259            R4811 -1          A01X+132458Y+063300X0198Y0197R180 S1      
327m1259            R4824 -2   M      A01X+132942Y+063300X0198Y0197R180 S1      
327m1260            U6    -L7         A01X+133423Y+086609X0160Y         S1      
317m1260            VIA   -    MD0100PA00X+133265Y+086766X0180Y         S0      
317m1260            VIA   -    M      A01X+129400Y+086350X0200Y         S2      
017m1260            VIA   -    M      A18X+129400Y+086350X0260Y         S2      
017m1260                  -    MD0100PA00X+129400Y+086350                       
327m1260            R4161 -1          A01X+129108Y+086350X0198Y0197R180 S1      
327SSD12_PWRDIS_R   J42   -B12        A01X+143136Y+009996X0150Y0500R090 S1      
317SSD12_PWRDIS_R   VIA   -    M      A01X+142713Y+009996X0200Y         S2      
017SSD12_PWRDIS_R   VIA   -    M      A18X+142713Y+009996X0260Y         S2      
017SSD12_PWRDIS_R         -    MD0100PA00X+142713Y+009996                       
327SSD12_PWRDIS_R   R6210 -2          A01X+146836Y+011449X0198Y0197R180 S1      
317SSD12_PWRDIS_R   VIA   -    MD0100PA00X+146628Y+011208X0200Y         S0      
317SSD12_PWRDIS_R   VIA   -    MD0100PA00X+146831Y+040886X0200Y         S0      
317SSD12_PWRDIS_R   VIA   -    MD0100PA00X+139162Y+040990X0200Y         S0      
317SSD12_PWRDIS_R   VIA   -    MD0100PA00X+133700Y+080400X0200Y         S0      
327SSD12_PWRDIS_R   R4132 -2          A01X+133700Y+080642X0198Y0197R270 S1      
327m1261            U352  -1          A01X+083484Y+073505X0140Y0440R180 S1      
327m1261            R5416 -1          A01X+083448Y+074115X0198Y0197R090 S1      
327m1261            R5303 -1   M      A01X+083848Y+074115X0198Y0197R090 S1      
317m1261            VIA   -    M      A01X+083671Y+073875X0200Y         S2      
017m1261            VIA   -    M      A18X+083671Y+073875X0260Y         S2      
017m1261                  -    MD0100PA00X+083671Y+073875                       
317m1261            VIA   -    MD0100PA00X+090264Y+080075X0200Y    R090 S0      
327m1261            R5295 -2          A18X+089982Y+082042X0198Y0197R090 S2      
317m1262            VIA   -    MD0100PA00X+135155Y+084877X0180Y         S0      
327m1262            U6    -T12        A01X+134998Y+085034X0160Y         S1      
327m1262            R5778 -1          A01X+138634Y+080928X0198Y0197R270 S1      
317m1262            VIA   -    M      A01X+138536Y+081176X0200Y         S2      
017m1262            VIA   -    M      A18X+138536Y+081176X0260Y         S2      
017m1262                  -    MD0100PA00X+138536Y+081176                       
327m1263            C3196 -1          A18X+064518Y+118343X0120Y0150R270 S2      
327m1263            C3197 -1          A18X+064518Y+118015X0120Y0150R090 S2      
327m1263            PEX1  -AA13       A01X+064705Y+117992X0180Y         S1      
317m1263            VIA   -    MD0080PA00X+064518Y+118179X0160Y    R270 S0      
317m1263            VIA   -    M      A01X+058747Y+116809X0200Y         S2      
017m1263            VIA   -    M      A18X+058747Y+116809X0260Y         S2      
017m1263                  -    MD0100PA00X+058747Y+116809                       
317m1263            VIA   -    MD0100PA00X+058197Y+116809X0200Y         S0      
327m1263            L104  -2          A01X+057954Y+117241X0440Y0540R180 S1      
327m1263            R4568 -1          A01X+058469Y+116868X0198Y0197R270 S1      
327m1263            C3195 -1          A01X+058524Y+117331X0280Y0320R270 S1      
327m1264            PEX2  -L26        A01X+115276Y+121732X0180Y         S1      
317m1264            VIA   -    MD0080PA00X+115276Y+121732X0160Y    R090 S0      
327m1264            VIA   -    M      A18X+126949Y+122876X0260Y         S2      
317m1264            VIA   -    MD0100PA00X+127224Y+122602X0200Y         S0      
327m1264            R3945 -1          A01X+127382Y+122347X0198Y0197R315 S1      
317m1265            VIA   -    M      A01X+134300Y+072846X0200Y    R180 S2      
017m1265            VIA   -    M      A18X+134300Y+072846X0260Y    R180 S2      
017m1265                  -    MD0100PA00X+134300Y+072846                       
327m1265            U347  -2          A01X+135098Y+072502X0160Y0540R270 S1      
327m1265            R4762 -2   M      A01X+132942Y+072850X0198Y0197R180 S1      
327m1265            R4745 -1          A01X+132458Y+072850X0198Y0197R180 S1      
317m1266            VIA   -    M      A01X+141350Y+089200X0200Y         S2      
017m1266            VIA   -    M      A18X+141350Y+089200X0260Y         S2      
017m1266                  -    MD0100PA00X+141350Y+089200                       
327m1266            R3623 -2          A01X+141108Y+089200X0198Y0197     S1      
317m1266            VIA   -    MD0100PA00X+071580Y+070645X0200Y         S0      
327m1266            U21   -2          A01X+065470Y+068201X0220Y0530R180 S1      
327SSD13_PWRDIS_R   R4136 -2          A18X+134200Y+081642X0198Y0197R090 S2      
317SSD13_PWRDIS_R   VIA   -    MD0100PA00X+134300Y+081162X0200Y         S0      
327SSD13_PWRDIS_R   J43   -B12        A01X+153372Y+009996X0150Y0500R090 S1      
317SSD13_PWRDIS_R   VIA   -    M      A01X+152949Y+009996X0200Y         S2      
017SSD13_PWRDIS_R   VIA   -    M      A18X+152949Y+009996X0260Y         S2      
017SSD13_PWRDIS_R         -    MD0100PA00X+152949Y+009996                       
327SSD13_PWRDIS_R   R6211 -2          A01X+157073Y+011449X0198Y0197R180 S1      
317SSD13_PWRDIS_R   VIA   -    MD0100PA00X+156864Y+011208X0200Y         S0      
317SSD13_PWRDIS_R   VIA   -    MD0100PA00X+159625Y+037563X0200Y         S0      
317SSD13_PWRDIS_R   VIA   -    MD0100PA00X+138943Y+042159X0200Y         S0      
327m1267            PR7138-1          A18X+139829Y+102704X0198Y0197R090 S2      
327m1267            PU11  -27         A01X+138731Y+102675X0070Y0240     S1      
317m1267            VIA   -    MD0100PA00X+138781Y+103095X0200Y         S0      
327m1267            VIA   -    M      A18X+139391Y+103255X0260Y         S2      
327NIC4_PWRBRK_N    VIA   -    M      A01X+115725Y+064590X0300Y         S1      
327NIC4_PWRBRK_N    R2468 -2          A01X+116028Y+065067X0198Y0197R270 S1      
327NIC4_PWRBRK_N    R2467 -2   M      A01X+115628Y+065067X0198Y0197R270 S1      
327NIC4_PWRBRK_N    Q121  -6          A01X+115725Y+064087X0240Y0240     S1      
327m1268            VIA   -    M      A01X+067118Y+015486X0300Y         S1      
327m1268            R5558 -2          A01X+066624Y+015090X0198Y0197R090 S1      
327m1268            R5557 -2   M      A01X+066624Y+015486X0198Y0197R270 S1      
327m1268            U369  -D          A01X+068090Y+016196X0400Y0560     S1      
327m1269            C3199 -1          A18X+064064Y+118180X0120Y0150     S2      
327m1269            C3200 -1   M      A18X+064064Y+117800X0120Y0150     S2      
317m1269            VIA   -    MD0080PA00X+064144Y+117805X0160Y    R270 S0      
327m1269            PEX1  -AB12       A01X+064331Y+117618X0180Y         S1      
317m1269            VIA   -    M      A01X+058747Y+118069X0200Y         S2      
017m1269            VIA   -    M      A18X+058747Y+118069X0260Y         S2      
017m1269                  -    MD0100PA00X+058747Y+118069                       
317m1269            VIA   -    MD0100PA00X+058197Y+118069X0200Y         S0      
327m1269            L105  -2          A01X+057954Y+118501X0440Y0540R180 S1      
327m1269            R4569 -1          A01X+058469Y+118128X0198Y0197R270 S1      
327m1269            C3198 -1          A01X+058524Y+118591X0280Y0320R270 S1      
317m1270            VIA   -    M      A01X+134052Y+072413X0200Y    R180 S2      
017m1270            VIA   -    M      A18X+134052Y+072413X0260Y    R180 S2      
017m1270                  -    MD0100PA00X+134052Y+072413                       
327m1270            U347  -3          A01X+135098Y+072246X0160Y0540R270 S1      
327m1270            R4761 -2   M      A01X+132942Y+072450X0198Y0197R180 S1      
327m1270            R4746 -1          A01X+132458Y+072450X0198Y0197R180 S1      
327m1271            U352  -3          A01X+082972Y+073505X0140Y0440R180 S1      
327m1271            R5304 -1          A01X+082648Y+074115X0198Y0197R090 S1      
327m1271            R5417 -1   M      A01X+083048Y+074115X0198Y0197R090 S1      
317m1271            VIA   -    M      A01X+083048Y+073875X0200Y         S2      
017m1271            VIA   -    M      A18X+083048Y+073875X0260Y         S2      
017m1271                  -    MD0100PA00X+083048Y+073875                       
317m1271            VIA   -    MD0100PA00X+089583Y+080066X0200Y    R090 S0      
327m1271            R5296 -2          A01X+089992Y+080332X0198Y0197R270 S1      
327NIC0_PWRBRK_N    VIA   -    M      A01X+024308Y+064590X0300Y         S1      
327NIC0_PWRBRK_N    R2464 -2          A01X+024610Y+065067X0198Y0197R270 S1      
327NIC0_PWRBRK_N    Q119  -6          A01X+024308Y+064087X0240Y0240     S1      
327NIC0_PWRBRK_N    R2463 -2   M      A01X+024210Y+065067X0198Y0197R270 S1      
327m1272            J2    -B15        A01X+090330Y+026457X0150Y0530R090 S1      
317m1272            VIA   -    MD0100PA00X+089514Y+026524X0200Y         S0      
317m1272            VIA   -    M      A01X+081364Y+076200X0300Y         S1      
017m1272            VIA   -    M      A18X+081364Y+076200X0200Y         S1      
017m1272                  -    MD0100PA00X+081364Y+076200                       
327m1272            U88   -3          A01X+081604Y+085920X0110Y0280R180 S1      
317m1272            VIA   -    MD0100PA00X+087867Y+074284X0200Y         S0      
317m1273            VIA   -    M      A01X+068483Y+014872X0200Y         S2      
017m1273            VIA   -    M      A18X+068483Y+014872X0260Y         S2      
017m1273                  -    MD0100PA00X+068483Y+014872                       
327m1273            R5559 -1          A01X+068770Y+014691X0198Y0197R270 S1      
327m1273            U369  -G          A01X+067716Y+015330X0400Y0560     S1      
317m1274            VIA   -    M      A01X+137896Y+071949X0200Y         S2      
017m1274            VIA   -    M      A18X+137896Y+071949X0260Y         S2      
017m1274                  -    MD0100PA00X+137896Y+071949                       
327m1274            U347  -21         A01X+137402Y+071990X0160Y0540R270 S1      
327m1274            R4747 -1          A01X+139892Y+072200X0198Y0197     S1      
327m1274            R4763 -2   M      A01X+139408Y+072200X0198Y0197     S1      
327m1275            R5301 -1   M      A01X+085448Y+074115X0198Y0197R090 S1      
327m1275            R5414 -1          A01X+085048Y+074115X0198Y0197R090 S1      
327m1275            U351  -1          A01X+085084Y+073505X0140Y0440R180 S1      
317m1275            VIA   -    M      A01X+085448Y+073863X0200Y         S2      
017m1275            VIA   -    M      A18X+085448Y+073863X0260Y         S2      
017m1275                  -    MD0100PA00X+085448Y+073863                       
327m1275            R5293 -2          A01X+089992Y+081346X0198Y0197R270 S1      
317m1275            VIA   -    MD0100PA00X+089992Y+080896X0200Y    R090 S0      
327NIC1_PWRBRK_N    VIA   -    M      A01X+024898Y+062867X0300Y         S1      
327NIC1_PWRBRK_N    R2472 -2          A01X+025128Y+062394X0198Y0197R090 S1      
327NIC1_PWRBRK_N    Q119  -3          A01X+024898Y+063379X0240Y0240     S1      
327NIC1_PWRBRK_N    R2471 -2   M      A01X+024728Y+062394X0198Y0197R090 S1      
327m1276            PU57  -11         A01X+058363Y+022506X0110Y0240     S1      
327m1276            R6055 -1          A01X+057069Y+013090X0198Y0197R270 S1      
327m1276            R5555 -1   M      A01X+056388Y+014775X0198Y0197R090 S1      
317m1276            VIA   -    MD0100PA00X+056054Y+015737X0200Y         S0      
327m1276            C2888 -1          A01X+057801Y+023286X0198Y0197R090 S1      
317m1276            VIA   -    M      A01X+058205Y+022865X0200Y    R090 S2      
017m1276            VIA   -    M      A18X+058205Y+022865X0260Y    R090 S2      
017m1276                  -    MD0100PA00X+058205Y+022865                       
317m1277            VIA   -    M      A01X+138629Y+067249X0200Y         S2      
017m1277            VIA   -    M      A18X+138629Y+067249X0260Y         S2      
017m1277                  -    MD0100PA00X+138629Y+067249                       
327m1277            U348  -21         A01X+137402Y+067290X0160Y0540R270 S1      
327m1277            R4766 -1          A01X+139892Y+067500X0198Y0197     S1      
327m1277            R4782 -2   M      A01X+139408Y+067500X0198Y0197     S1      
317m1278            VIA   -    M      A01X+144700Y+081050X0200Y    R180 S2      
017m1278            VIA   -    M      A18X+144700Y+081050X0260Y    R180 S2      
017m1278                  -    MD0100PA00X+144700Y+081050                       
327m1278            U343  -10         A01X+145898Y+081854X0160Y0540R270 S1      
327m1278            R4629 -1          A01X+144058Y+081050X0198Y0197R180 S1      
317m1279            VIA   -    M      A01X+134674Y+061119X0200Y    R180 S2      
017m1279            VIA   -    M      A18X+134674Y+061119X0260Y    R180 S2      
017m1279                  -    MD0100PA00X+134674Y+061119                       
327m1279            R4818 -1          A01X+133258Y+060500X0198Y0197R180 S1      
327m1279            U349  -10         A01X+135098Y+061304X0160Y0540R270 S1      
317P0V8_PEX2_PWM1   VIA   -    MD0100PA00X+133116Y+110479X0200Y         S0      
327P0V8_PEX2_PWM1   PU12  -34         A01X+133036Y+111023X0090Y0240R180 S1      
317P0V8_PEX2_PWM1   VIA   -    M      A01X+139488Y+099994X0200Y    R090 S2      
017P0V8_PEX2_PWM1   VIA   -    M      A18X+139488Y+099994X0260Y    R090 S2      
017P0V8_PEX2_PWM1         -    MD0100PA00X+139488Y+099994                       
327P0V8_PEX2_PWM1   PU11  -8          A01X+139361Y+100785X0070Y0240     S1      
327m1280            U351  -3          A01X+084572Y+073505X0140Y0440R180 S1      
327m1280            R5302 -1          A01X+084248Y+074115X0198Y0197R090 S1      
327m1280            R5415 -1   M      A01X+084648Y+074115X0198Y0197R090 S1      
317m1280            VIA   -    M      A01X+084648Y+073875X0200Y         S2      
017m1280            VIA   -    M      A18X+084648Y+073875X0260Y         S2      
017m1280                  -    MD0100PA00X+084648Y+073875                       
317m1280            VIA   -    MD0100PA00X+091420Y+079746X0200Y    R090 S0      
327m1280            R5294 -2          A18X+090377Y+082042X0198Y0197R090 S2      
327NIC3_PWRBRK_N    VIA   -    M      A01X+070607Y+062867X0300Y         S1      
327NIC3_PWRBRK_N    R2474 -2          A01X+070836Y+062394X0198Y0197R090 S1      
327NIC3_PWRBRK_N    R2473 -2   M      A01X+070436Y+062394X0198Y0197R090 S1      
327NIC3_PWRBRK_N    Q120  -3          A01X+070607Y+063379X0240Y0240     S1      
317m1281            VIA   -    M      A01X+134300Y+068146X0200Y    R180 S2      
017m1281            VIA   -    M      A18X+134300Y+068146X0260Y    R180 S2      
017m1281                  -    MD0100PA00X+134300Y+068146                       
327m1281            U348  -2          A01X+135098Y+067802X0160Y0540R270 S1      
327m1281            R4781 -2   M      A01X+132942Y+068150X0198Y0197R180 S1      
327m1281            R4765 -1          A01X+132458Y+068150X0198Y0197R180 S1      
317m1282            VIA   -    M      A01X+145310Y+082110X0200Y    R180 S2      
017m1282            VIA   -    M      A18X+145310Y+082110X0260Y    R180 S2      
017m1282                  -    MD0100PA00X+145310Y+082110                       
327m1282            R4628 -1          A01X+144058Y+081450X0198Y0197R180 S1      
327m1282            U343  -9          A01X+145898Y+082110X0160Y0540R270 S1      
317m1283            VIA   -    M      A01X+133800Y+060900X0200Y    R180 S2      
017m1283            VIA   -    M      A18X+133800Y+060900X0260Y    R180 S2      
017m1283                  -    MD0100PA00X+133800Y+060900                       
327m1283            R4817 -1          A01X+133258Y+060900X0198Y0197R180 S1      
327m1283            U349  -9          A01X+135098Y+061560X0160Y0540R270 S1      
317m1284            VIA   -    M      A01X+129350Y+082750X0200Y         S2      
017m1284            VIA   -    M      A18X+129350Y+082750X0260Y         S2      
017m1284                  -    MD0100PA00X+129350Y+082750                       
327m1284            R4159 -2          A01X+129108Y+082750X0198Y0197     S1      
317m1284            VIA   -    MD0100PA00X+132006Y+083932X0180Y         S0      
327m1284            U6    -W3         A01X+132163Y+084089X0160Y         S1      
327NIC2_PWRBRK_N    VIA   -    M      A01X+070016Y+064590X0300Y         S1      
327NIC2_PWRBRK_N    Q120  -6          A01X+070016Y+064087X0240Y0240     S1      
327NIC2_PWRBRK_N    R2466 -2          A01X+070319Y+065067X0198Y0197R270 S1      
327NIC2_PWRBRK_N    R2465 -2   M      A01X+069919Y+065067X0198Y0197R270 S1      
327m1285            VIA   -    M      A01X+056882Y+015486X0300Y         S1      
327m1285            R5555 -2          A01X+056388Y+015090X0198Y0197R090 S1      
327m1285            R5554 -2   M      A01X+056388Y+015486X0198Y0197R270 S1      
327m1285            U368  -D          A01X+057854Y+016196X0400Y0560     S1      
317m1286            VIA   -    M      A01X+134052Y+067713X0200Y    R180 S2      
017m1286            VIA   -    M      A18X+134052Y+067713X0260Y    R180 S2      
017m1286                  -    MD0100PA00X+134052Y+067713                       
327m1286            U348  -3          A01X+135098Y+067546X0160Y0540R270 S1      
327m1286            R4780 -2   M      A01X+132942Y+067750X0198Y0197R180 S1      
327m1286            R4764 -1          A01X+132458Y+067750X0198Y0197R180 S1      
327SSD14_PWRDIS_R   J44   -B12        A01X+163608Y+009996X0150Y0500R090 S1      
317SSD14_PWRDIS_R   VIA   -    MD0100PA00X+140023Y+039026X0200Y         S0      
317SSD14_PWRDIS_R   VIA   -    MD0100PA00X+133700Y+078800X0200Y         S0      
327SSD14_PWRDIS_R   R4140 -2          A01X+133700Y+079042X0198Y0197R270 S1      
317SSD14_PWRDIS_R   VIA   -    MD0100PA00X+163069Y+034743X0200Y         S0      
317SSD14_PWRDIS_R   VIA   -    M      A01X+163186Y+009996X0200Y         S2      
017SSD14_PWRDIS_R   VIA   -    M      A18X+163186Y+009996X0260Y         S2      
017SSD14_PWRDIS_R         -    MD0100PA00X+163186Y+009996                       
327SSD14_PWRDIS_R   R6212 -2          A01X+167309Y+011449X0198Y0197R180 S1      
317SSD14_PWRDIS_R   VIA   -    MD0100PA00X+167100Y+011208X0200Y         S0      
317m1287            VIA   -    MD0100PA00X+137130Y+110690X0200Y    R090 S0      
327m1287            PU13  -38         A01X+136958Y+111023X0090Y0240R180 S1      
327m1287            PU11  -24         A01X+139203Y+102675X0070Y0240     S1      
317m1287            VIA   -    M      A01X+138976Y+104306X0200Y    R090 S2      
017m1287            VIA   -    M      A18X+138976Y+104306X0260Y    R090 S2      
017m1287                  -    MD0100PA00X+138976Y+104306                       
327NIC5_PWRBRK_N    VIA   -    M      A01X+116316Y+062867X0300Y         S1      
327NIC5_PWRBRK_N    R2476 -2          A01X+116545Y+062394X0198Y0197R090 S1      
327NIC5_PWRBRK_N    Q121  -3          A01X+116316Y+063379X0240Y0240     S1      
327NIC5_PWRBRK_N    R2475 -2   M      A01X+116145Y+062394X0198Y0197R090 S1      
317m1288            VIA   -    M      A01X+082294Y+086330X0200Y    R270 S2      
017m1288            VIA   -    M      A18X+082294Y+086330X0260Y    R270 S2      
017m1288                  -    MD0100PA00X+082294Y+086330                       
327m1288            R5473 -1          A01X+081603Y+086768X0198Y0197R090 S1      
327m1288            U88   -2          A01X+081801Y+085920X0110Y0280R180 S1      
317m1289            VIA   -    M      A01X+058247Y+014872X0200Y         S2      
017m1289            VIA   -    M      A18X+058247Y+014872X0260Y         S2      
017m1289                  -    MD0100PA00X+058247Y+014872                       
327m1289            U368  -G          A01X+057480Y+015330X0400Y0560     S1      
327m1289            R5556 -1          A01X+058534Y+014691X0198Y0197R270 S1      
317m1290            VIA   -    M      A01X+143400Y+071296X0200Y    R180 S2      
017m1290            VIA   -    M      A18X+143400Y+071296X0260Y    R180 S2      
017m1290                  -    MD0100PA00X+143400Y+071296                       
327m1290            R4704 -1          A01X+141558Y+071300X0198Y0197R180 S1      
327m1290            R4718 -2   M      A01X+142042Y+071300X0198Y0197R180 S1      
327m1290            U346  -2          A01X+144198Y+070952X0160Y0540R270 S1      
327m1291            R3616 -1          A01X+141108Y+089600X0198Y0197R180 S1      
327m1291            C4500 -1          A01X+048874Y+067734X0198Y0197R090 S1      
317m1291            VIA   -    MD0100PA00X+048876Y+066722X0200Y         S0      
327m1291            U438  -3   M      A01X+048876Y+067120X0140Y0440R180 S1      
317m1291            VIA   -    MD0100PA00X+116926Y+069498X0200Y         S0      
317m1291            VIA   -    M      A01X+141708Y+089600X0200Y         S2      
017m1291            VIA   -    M      A18X+141708Y+089600X0260Y         S2      
017m1291                  -    MD0100PA00X+141708Y+089600                       
327SSD15_PWRDIS_R   J45   -B12        A01X+173844Y+009996X0150Y0500R090 S1      
317SSD15_PWRDIS_R   VIA   -    M      A01X+173422Y+009996X0200Y         S2      
017SSD15_PWRDIS_R   VIA   -    M      A18X+173422Y+009996X0260Y         S2      
017SSD15_PWRDIS_R         -    MD0100PA00X+173422Y+009996                       
317SSD15_PWRDIS_R   VIA   -    MD0100PA00X+177336Y+011208X0200Y         S0      
327SSD15_PWRDIS_R   R6213 -2          A01X+177545Y+011449X0198Y0197R180 S1      
317SSD15_PWRDIS_R   VIA   -    MD0100PA00X+167032Y+035353X0200Y         S0      
317SSD15_PWRDIS_R   VIA   -    MD0100PA00X+142100Y+040762X0200Y         S0      
317SSD15_PWRDIS_R   VIA   -    MD0100PA00X+136100Y+080400X0200Y         S0      
327SSD15_PWRDIS_R   R4144 -1          A01X+136100Y+080642X0198Y0197R090 S1      
327NIC7_PWRBRK_N    VIA   -    M      A01X+162024Y+062867X0300Y         S1      
327NIC7_PWRBRK_N    R2478 -2          A01X+162254Y+062394X0198Y0197R090 S1      
327NIC7_PWRBRK_N    Q122  -3          A01X+162024Y+063379X0240Y0240     S1      
327NIC7_PWRBRK_N    R2477 -2   M      A01X+161854Y+062394X0198Y0197R090 S1      
327m1292            PU55  -11         A01X+048126Y+022506X0110Y0240     S1      
327m1292            R6054 -1          A01X+046833Y+013090X0198Y0197R270 S1      
327m1292            R5552 -1   M      A01X+046152Y+014775X0198Y0197R090 S1      
317m1292            VIA   -    MD0100PA00X+045818Y+015737X0200Y         S0      
327m1292            C2886 -1          A01X+047565Y+023286X0198Y0197R090 S1      
317m1292            VIA   -    M      A01X+047969Y+022865X0200Y    R090 S2      
017m1292            VIA   -    M      A18X+047969Y+022865X0260Y    R090 S2      
017m1292                  -    MD0100PA00X+047969Y+022865                       
317m1293            VIA   -    MD0100PA00X+035806Y+122602X0200Y         S0      
327m1293            VIA   -    M      A18X+035532Y+122876X0260Y         S2      
327m1293            R3943 -1          A01X+035965Y+122347X0198Y0197R315 S1      
327m1293            PEX0  -L26        A01X+023858Y+121732X0180Y         S1      
317m1293            VIA   -    MD0080PA00X+023858Y+121732X0160Y    R090 S0      
317m1294            VIA   -    M      A01X+143152Y+070863X0200Y    R180 S2      
017m1294            VIA   -    M      A18X+143152Y+070863X0260Y    R180 S2      
017m1294                  -    MD0100PA00X+143152Y+070863                       
327m1294            R4701 -1          A01X+141558Y+070900X0198Y0197R180 S1      
327m1294            R4717 -2   M      A01X+142042Y+070900X0198Y0197R180 S1      
327m1294            U346  -3          A01X+144198Y+070696X0160Y0540R270 S1      
327PRSNT_NIC0_R_N   C3998 -1          A01X+012724Y+044866X0198Y0197R270 S1      
327PRSNT_NIC0_R_N   R43   -1   M      A01X+012724Y+045251X0198Y0197R090 S1      
327PRSNT_NIC0_R_N   U9    -G   M      A01X+013310Y+045075X0400Y0560     S1      
317PRSNT_NIC0_R_N   VIA   -    MD0100PA00X+014538Y+045871X0200Y         S0      
317PRSNT_NIC0_R_N   VIA   -    M      A01X+023579Y+075433X0200Y         S2      
017PRSNT_NIC0_R_N   VIA   -    M      A18X+023579Y+075433X0260Y         S2      
017PRSNT_NIC0_R_N         -    MD0100PA00X+023579Y+075433                       
317PRSNT_NIC0_R_N   VIA   -    MD0100PA00X+137990Y+089286X0180Y         S0      
317PRSNT_NIC0_R_N   VIA   -    MD0100PA00X+073271Y+085389X0200Y         S0      
317PRSNT_NIC0_R_N   VIA   -    MD0100PA00X+092136Y+095125X0200Y         S0      
327PRSNT_NIC0_R_N   U5    -N4         A01X+091759Y+087521X0160Y    R180 S1      
317PRSNT_NIC0_R_N   VIA   -    MD0100PA00X+091916Y+087679X0180Y    R270 S0      
327PRSNT_NIC0_R_N   U6    -C21        A01X+137832Y+089129X0160Y         S1      
327m1295            R4141 -2          A18X+134650Y+081642X0198Y0197R090 S2      
317m1295            VIA   -    MD0100PA00X+134700Y+081162X0200Y         S0      
327m1295            J44   -B10        A01X+163608Y+009524X0150Y0500R090 S1      
317m1295            VIA   -    M      A01X+138956Y+042468X0200Y         S2      
017m1295            VIA   -    M      A18X+138956Y+042468X0260Y         S2      
017m1295                  -    MD0100PA00X+138956Y+042468                       
317m1295            VIA   -    MD0100PA00X+164162Y+037960X0200Y         S0      
317m1295            VIA   -    MD0100PA00X+163190Y+009524X0200Y         S0      
327NIC6_PWRBRK_N    VIA   -    M      A01X+161434Y+064590X0300Y         S1      
327NIC6_PWRBRK_N    R2470 -2          A01X+161736Y+065067X0198Y0197R270 S1      
327NIC6_PWRBRK_N    R2469 -2   M      A01X+161336Y+065067X0198Y0197R270 S1      
327NIC6_PWRBRK_N    Q122  -6          A01X+161434Y+064087X0240Y0240     S1      
327m1296            VIA   -    M      A01X+081128Y+086969X0300Y         S1      
327m1296            U356  -4          A01X+081480Y+087686X0160Y0360R180 S1      
327m1296            R5473 -2          A01X+081603Y+087083X0198Y0197R090 S1      
317m1297            VIA   -           A01X+011041Y+102409X0200Y         S2      
017m1297            VIA   -           A18X+011041Y+102409X0260Y         S2      
017m1297                  -     D0100PA00X+011041Y+102409                       
327m1297            R4567 -2          A01X+011138Y+102736X0198Y0197     S1      
327m1297            C3074 -1          A01X+011026Y+102066X0280Y0320R180 S1      
317m1298            VIA   -    M      A01X+147672Y+070440X0200Y    R180 S2      
017m1298            VIA   -    M      A18X+147672Y+070440X0260Y    R180 S2      
017m1298                  -    MD0100PA00X+147672Y+070440                       
327m1298            U346  -21         A01X+146502Y+070440X0160Y0540R270 S1      
327m1298            R4702 -1          A01X+148992Y+070650X0198Y0197     S1      
327m1298            R4719 -2   M      A01X+148508Y+070650X0198Y0197     S1      
327m1299            U16   -2          A01X+032027Y+033258X0220Y0530R090 S1      
317m1299            VIA   -    M      A01X+031594Y+033258X0200Y         S2      
017m1299            VIA   -    M      A18X+031594Y+033258X0260Y         S2      
017m1299                  -    MD0100PA00X+031594Y+033258                       
317m1299            VIA   -    MD0100PA00X+141350Y+090400X0200Y         S0      
327m1299            R3615 -2          A01X+141108Y+090400X0198Y0197     S1      
317m1299            VIA   -    MD0100PA00X+038096Y+073100X0200Y         S0      
327m1300            J45   -B10        A01X+173844Y+009524X0150Y0500R090 S1      
317m1300            VIA   -    MD0100PA00X+173427Y+009524X0200Y         S0      
317m1300            VIA   -    MD0100PA00X+167372Y+035388X0200Y         S0      
317m1300            VIA   -    M      A01X+141567Y+042128X0200Y         S2      
017m1300            VIA   -    M      A18X+141567Y+042128X0260Y         S2      
017m1300                  -    MD0100PA00X+141567Y+042128                       
317m1300            VIA   -    MD0100PA00X+135700Y+080400X0200Y         S0      
327m1300            R4145 -1          A01X+135700Y+080642X0198Y0197R090 S1      
327m1301            VIA   -    M      A01X+070695Y+064594X0300Y         S1      
327m1301            Q120  -5          A01X+070312Y+064087X0160Y0240     S1      
327m1301            R3307 -2          A01X+070719Y+065067X0198Y0197R270 S1      
317m1302            VIA   -    M      A01X+085192Y+095135X0200Y         S2      
017m1302            VIA   -    M      A18X+085192Y+095135X0260Y         S2      
017m1302                  -    MD0100PA00X+085192Y+095135                       
317m1302            VIA   -    MD0100PA00X+097900Y+128892X0200Y         S0      
317m1302            VIA   -    MD0100PA00X+098482Y+130330X0200Y         S0      
317m1302            VIA   -    MD0100PA00X+082390Y+088208X0200Y    R270 S0      
327m1302            U356  -2          A01X+081736Y+088553X0160Y0360R180 S1      
327m1302            R5472 -1          A18X+154815Y+141885X0198Y0197R180 S2      
327P1V8_PLL0_PEX0   R6566 -1          A01X+007505Y+082814X0198Y0197R090 S1      
327P1V8_PLL0_PEX0   R6589 -1          A01X+095790Y+085358X0198Y0197R270 S1      
327P1V8_PLL0_PEX0   C4416 -1          A01X+007015Y+082262X0400Y0500     S1      
327P1V8_PLL0_PEX0   U430  -1          A01X+006865Y+082968X0110Y0360R090 S1      
327P1V8_PLL0_PEX0   U430  -2          A01X+006865Y+083164X0110Y0360R090 S1      
327P1V8_PLL0_PEX0   U430  -3          A01X+006865Y+083361X0110Y0360R090 S1      
317P1V8_PLL0_PEX0   VIA   -    MD0100PA00X+010102Y+100966X0200Y         S0      
317P1V8_PLL0_PEX0   VIA   -    MD0100PA00X+010382Y+100966X0200Y         S0      
327P1V8_PLL0_PEX0   L97   -1          A01X+010396Y+101430X0440Y0540R270 S1      
327P1V8_PLL0_PEX0   C3065 -1          A01X+010336Y+100535X0280Y0320R270 S1      
327P1V8_PLL0_PEX0   C3066 -1          A01X+010604Y+100976X0120Y0150     S1      
317P1V8_PLL0_PEX0   VIA   -    MD0100PA00X+007435Y+082192X0200Y    R270 S0      
317P1V8_PLL0_PEX0   VIA   -    MD0100PA00X+007435Y+082472X0200Y    R270 S0      
327P1V8_PLL0_PEX0   C4417 -1          A18X+006832Y+082272X0198Y0197     S2      
317P1V8_PLL0_PEX0   VIA   -    MD0100PA00X+006865Y+082722X0200Y    R270 S0      
317P1V8_PLL0_PEX0   VIA   -    MD0100PA00X+007215Y+082732X0200Y    R270 S0      
327P1V8_PLL0_PEX0   C3016 -1          A01X+010611Y+103300X0120Y0150R090 S1      
327P1V8_PLL0_PEX0   C3018 -1          A01X+010300Y+103299X0120Y0150R090 S1      
327P1V8_PLL0_PEX0   C3017 -1          A01X+010602Y+118560X0280Y0320R180 S1      
327P1V8_PLL0_PEX0   C3038 -1          A01X+011043Y+118293X0120Y0150R270 S1      
327P1V8_PLL0_PEX0   L89   -1          A01X+011497Y+118501X0440Y0540R180 S1      
317P1V8_PLL0_PEX0   VIA   -    MD0100PA00X+010386Y+118270X0200Y         S0      
317P1V8_PLL0_PEX0   VIA   -    MD0100PA00X+010897Y+115996X0200Y         S0      
317P1V8_PLL0_PEX0   VIA   -    MD0100PA00X+010312Y+115996X0200Y         S0      
327P1V8_PLL0_PEX0   C3035 -1          A01X+010602Y+116040X0280Y0320R180 S1      
327P1V8_PLL0_PEX0   L90   -1          A01X+011497Y+115981X0440Y0540R180 S1      
317P1V8_PLL0_PEX0   VIA   -    MD0100PA00X+010897Y+117256X0200Y         S0      
317P1V8_PLL0_PEX0   VIA   -    MD0100PA00X+010312Y+117256X0200Y         S0      
327P1V8_PLL0_PEX0   C3015 -1          A01X+010602Y+117300X0280Y0320R180 S1      
327P1V8_PLL0_PEX0   L88   -1          A01X+011497Y+117241X0440Y0540R180 S1      
327P1V8_PLL0_PEX0   C3054 -1          A01X+011043Y+117033X0120Y0150R270 S1      
317P1V8_PLL0_PEX0   VIA   -    M      A01X+010897Y+114736X0200Y         S2      
017P1V8_PLL0_PEX0   VIA   -    M      A18X+010897Y+114736X0260Y         S2      
017P1V8_PLL0_PEX0         -    MD0100PA00X+010897Y+114736                       
317P1V8_PLL0_PEX0   VIA   -    MD0100PA00X+010312Y+114736X0200Y         S0      
327P1V8_PLL0_PEX0   L92   -1          A01X+011497Y+114721X0440Y0540R180 S1      
327P1V8_PLL0_PEX0   C3064 -1          A01X+011043Y+114513X0120Y0150R270 S1      
327P1V8_PLL0_PEX0   C3063 -1          A01X+010602Y+114780X0280Y0320R180 S1      
317P1V8_PLL0_PEX0   VIA   -    MD0100PA00X+010897Y+113476X0200Y         S0      
317P1V8_PLL0_PEX0   VIA   -    MD0100PA00X+010312Y+113476X0200Y         S0      
327P1V8_PLL0_PEX0   C3051 -1          A01X+010602Y+113520X0280Y0320R180 S1      
327P1V8_PLL0_PEX0   L94   -1          A01X+011497Y+113461X0440Y0540R180 S1      
327P1V8_PLL0_PEX0   C3052 -1          A01X+011043Y+113253X0120Y0150R270 S1      
317P1V8_PLL0_PEX0   VIA   -    MD0100PA00X+010897Y+112216X0200Y         S0      
317P1V8_PLL0_PEX0   VIA   -    MD0100PA00X+010312Y+112216X0200Y         S0      
327P1V8_PLL0_PEX0   C3053 -1          A01X+010602Y+112260X0280Y0320R180 S1      
327P1V8_PLL0_PEX0   L95   -1          A01X+011497Y+112201X0440Y0540R180 S1      
317P1V8_PLL0_PEX0   VIA   -    M      A01X+010897Y+110956X0200Y         S2      
017P1V8_PLL0_PEX0   VIA   -    M      A18X+010897Y+110956X0260Y         S2      
017P1V8_PLL0_PEX0         -    MD0100PA00X+010897Y+110956                       
317P1V8_PLL0_PEX0   VIA   -    MD0100PA00X+010312Y+110956X0200Y         S0      
327P1V8_PLL0_PEX0   L96   -1          A01X+011497Y+110941X0440Y0540R180 S1      
327P1V8_PLL0_PEX0   C3036 -1          A01X+011043Y+110733X0120Y0150R270 S1      
327P1V8_PLL0_PEX0   C3037 -1          A01X+010602Y+111000X0280Y0320R180 S1      
327P1V8_PLL0_PEX0   C3020 -1          A01X+012208Y+101459X0120Y0150R270 S1      
327P1V8_PLL0_PEX0   L93   -1          A01X+012662Y+101667X0440Y0540R180 S1      
317P1V8_PLL0_PEX0   VIA   -    MD0100PA00X+012062Y+101683X0200Y         S0      
327P1V8_PLL0_PEX0   C3019 -1          A01X+011767Y+101726X0280Y0320R180 S1      
317P1V8_PLL0_PEX0   VIA   -    MD0100PA00X+011477Y+101683X0200Y         S0      
317P1V8_PLL0_PEX0   VIA   -    M      A01X+012062Y+102943X0200Y         S2      
017P1V8_PLL0_PEX0   VIA   -    M      A18X+012062Y+102943X0260Y         S2      
017P1V8_PLL0_PEX0         -    MD0100PA00X+012062Y+102943                       
317P1V8_PLL0_PEX0   VIA   -    MD0100PA00X+010797Y+103067X0200Y    R090 S0      
317P1V8_PLL0_PEX0   VIA   -    MD0100PA00X+010497Y+103067X0200Y    R090 S0      
317P1V8_PLL0_PEX0   VIA   -    MD0100PA00X+010197Y+103067X0200Y    R090 S0      
317P1V8_PLL0_PEX0   VIA   -    MD0100PA00X+011097Y+103067X0200Y    R090 S0      
317P1V8_PLL0_PEX0   VIA   -    MD0100PA00X+011477Y+102943X0200Y         S0      
327P1V8_PLL0_PEX0   C3033 -1          A01X+011767Y+102986X0280Y0320R180 S1      
327P1V8_PLL0_PEX0   L91   -1          A01X+012662Y+102927X0440Y0540R180 S1      
327P1V8_PLL0_PEX0   C3034 -1          A01X+012208Y+102719X0120Y0150R270 S1      
317P1V8_PLL0_PEX0   VIA   -    MD0100PA00X+008629Y+082209X0200Y         S0      
317P1V8_PLL0_PEX0   VIA   -    MD0100PA00X+095790Y+085630X0200Y         S0      
317m1303            VIA   -    M      A01X+145100Y+079846X0200Y    R180 S2      
017m1303            VIA   -    M      A18X+145100Y+079846X0260Y    R180 S2      
017m1303                  -    MD0100PA00X+145100Y+079846                       
327m1303            R4683 -1          A01X+143258Y+079850X0198Y0197R180 S1      
327m1303            R4699 -2   M      A01X+143742Y+079850X0198Y0197R180 S1      
327m1303            U345  -2          A01X+145898Y+079502X0160Y0540R270 S1      
317m1304            VIA   -    M      A01X+081604Y+084558X0200Y    R270 S2      
017m1304            VIA   -    M      A18X+081604Y+084558X0260Y    R270 S2      
017m1304                  -    MD0100PA00X+081604Y+084558                       
327m1304            R4892 -2          A01X+081883Y+083982X0198Y0197R090 S1      
327m1304            U88   -7          A01X+081801Y+084857X0110Y0280R180 S1      
327m1305            VIA   -    M      A01X+116404Y+064594X0300Y         S1      
327m1305            Q121  -5          A01X+116020Y+064087X0160Y0240     S1      
327m1305            R3309 -2          A01X+116428Y+065067X0198Y0197R270 S1      
317m1306            VIA   -    M      A01X+081992Y+088936X0200Y    R270 S2      
017m1306            VIA   -    M      A18X+081992Y+088936X0260Y    R270 S2      
017m1306                  -    MD0100PA00X+081992Y+088936                       
327m1306            U356  -1          A01X+081992Y+088553X0160Y0360R180 S1      
327m1306            R5474 -1          A01X+081963Y+089256X0198Y0197R090 S1      
317m1307            VIA   -    M      A01X+145100Y+079346X0200Y    R180 S2      
017m1307            VIA   -    M      A18X+145100Y+079346X0260Y    R180 S2      
017m1307                  -    MD0100PA00X+145100Y+079346                       
327m1307            R4682 -1          A01X+143258Y+079450X0198Y0197R180 S1      
327m1307            R4698 -2   M      A01X+143742Y+079450X0198Y0197R180 S1      
327m1307            U345  -3          A01X+145898Y+079246X0160Y0540R270 S1      
317m1308            VIA   -    M      A01X+129767Y+083215X0200Y         S2      
017m1308            VIA   -    M      A18X+129767Y+083215X0260Y         S2      
017m1308                  -    MD0100PA00X+129767Y+083215                       
317m1308            VIA   -    MD0100PA00X+131691Y+083932X0180Y         S0      
327m1308            U6    -W2         A01X+131848Y+084089X0160Y         S1      
327m1308            R4160 -2          A01X+129108Y+083150X0198Y0197     S1      
327m1309            VIA   -           A01X+138562Y+100114X0300Y         S1      
327m1309            PU11  -3          A01X+138573Y+100785X0070Y0240     S1      
327m1310            VIA   -    M      A01X+115745Y+062870X0300Y         S1      
327m1310            Q121  -2          A01X+116020Y+063379X0160Y0240     S1      
327m1310            R3308 -2          A01X+115745Y+062394X0198Y0197R090 S1      
327m1311            VIA   -    M      A01X+046646Y+015486X0300Y         S1      
327m1311            R5552 -2          A01X+046152Y+015090X0198Y0197R090 S1      
327m1311            R5551 -2   M      A01X+046152Y+015486X0198Y0197R270 S1      
327m1311            U367  -D          A01X+047617Y+016196X0400Y0560     S1      
317P1V8_PLL0_PEX1   VIA   -    MD0100PA00X+056021Y+118516X0200Y         S0      
317P1V8_PLL0_PEX1   VIA   -    MD0100PA00X+056606Y+118516X0200Y         S0      
327P1V8_PLL0_PEX1   C3191 -1          A01X+056311Y+118560X0280Y0320R180 S1      
327P1V8_PLL0_PEX1   L105  -1          A01X+057206Y+118501X0440Y0540R180 S1      
327P1V8_PLL0_PEX1   C3212 -1          A01X+056752Y+118293X0120Y0150R270 S1      
327P1V8_PLL0_PEX1   R6573 -1          A01X+059210Y+094223X0198Y0197R090 S1      
327P1V8_PLL0_PEX1   R6591 -1          A01X+095820Y+083852X0198Y0197R090 S1      
327P1V8_PLL0_PEX1   C4421 -1          A01X+058720Y+093671X0400Y0500     S1      
327P1V8_PLL0_PEX1   U431  -1          A01X+058571Y+094377X0110Y0360R090 S1      
327P1V8_PLL0_PEX1   U431  -2          A01X+058571Y+094573X0110Y0360R090 S1      
327P1V8_PLL0_PEX1   U431  -3          A01X+058571Y+094770X0110Y0360R090 S1      
317P1V8_PLL0_PEX1   VIA   -    MD0100PA00X+059140Y+093601X0200Y    R270 S0      
317P1V8_PLL0_PEX1   VIA   -    MD0100PA00X+059140Y+093881X0200Y    R270 S0      
327P1V8_PLL0_PEX1   C4422 -1          A18X+058538Y+093681X0198Y0197     S2      
317P1V8_PLL0_PEX1   VIA   -    MD0100PA00X+058570Y+094131X0200Y    R270 S0      
317P1V8_PLL0_PEX1   VIA   -    MD0100PA00X+058920Y+094141X0200Y    R270 S0      
317P1V8_PLL0_PEX1   VIA   -    MD0100PA00X+096118Y+083852X0200Y         S0      
317P1V8_PLL0_PEX1   VIA   -    MD0100PA00X+086583Y+096160X0200Y         S0      
317P1V8_PLL0_PEX1   VIA   -    MD0100PA00X+056091Y+100966X0200Y         S0      
317P1V8_PLL0_PEX1   VIA   -    MD0100PA00X+055811Y+100966X0200Y         S0      
327P1V8_PLL0_PEX1   L113  -1          A01X+056104Y+101430X0440Y0540R270 S1      
327P1V8_PLL0_PEX1   C3239 -1          A01X+056045Y+100535X0280Y0320R270 S1      
327P1V8_PLL0_PEX1   C3240 -1          A01X+056312Y+100976X0120Y0150     S1      
327P1V8_PLL0_PEX1   C3226 -1          A01X+057916Y+101459X0120Y0150R270 S1      
327P1V8_PLL0_PEX1   L109  -1          A01X+058371Y+101667X0440Y0540R180 S1      
327P1V8_PLL0_PEX1   C3227 -1          A01X+057476Y+101726X0280Y0320R180 S1      
317P1V8_PLL0_PEX1   VIA   -    MD0100PA00X+057770Y+101683X0200Y         S0      
317P1V8_PLL0_PEX1   VIA   -    MD0100PA00X+057186Y+101683X0200Y         S0      
327P1V8_PLL0_PEX1   C3193 -1          A01X+057476Y+102986X0280Y0320R180 S1      
327P1V8_PLL0_PEX1   C3210 -1          A01X+057916Y+102719X0120Y0150R270 S1      
327P1V8_PLL0_PEX1   L107  -1          A01X+058371Y+102927X0440Y0540R180 S1      
317P1V8_PLL0_PEX1   VIA   -    MD0100PA00X+057186Y+102943X0200Y         S0      
317P1V8_PLL0_PEX1   VIA   -    MD0100PA00X+056506Y+103067X0200Y    R090 S0      
317P1V8_PLL0_PEX1   VIA   -    MD0100PA00X+056806Y+103067X0200Y    R090 S0      
317P1V8_PLL0_PEX1   VIA   -    M      A01X+057770Y+102943X0200Y         S2      
017P1V8_PLL0_PEX1   VIA   -    M      A18X+057770Y+102943X0260Y         S2      
017P1V8_PLL0_PEX1         -    MD0100PA00X+057770Y+102943                       
327P1V8_PLL0_PEX1   C3228 -1          A01X+056320Y+103300X0120Y0150R090 S1      
327P1V8_PLL0_PEX1   C3192 -1          A01X+056752Y+115773X0120Y0150R270 S1      
327P1V8_PLL0_PEX1   L106  -1          A01X+057206Y+115981X0440Y0540R180 S1      
327P1V8_PLL0_PEX1   C3207 -1          A01X+056311Y+116040X0280Y0320R180 S1      
327P1V8_PLL0_PEX1   L104  -1          A01X+057206Y+117241X0440Y0540R180 S1      
327P1V8_PLL0_PEX1   C3225 -1          A01X+056311Y+117300X0280Y0320R180 S1      
327P1V8_PLL0_PEX1   C3209 -1          A01X+056311Y+114780X0280Y0320R180 S1      
327P1V8_PLL0_PEX1   C3238 -1          A01X+056752Y+114513X0120Y0150R270 S1      
327P1V8_PLL0_PEX1   L108  -1          A01X+057206Y+114721X0440Y0540R180 S1      
327P1V8_PLL0_PEX1   C3208 -1          A01X+056752Y+113253X0120Y0150R270 S1      
327P1V8_PLL0_PEX1   L110  -1          A01X+057206Y+113461X0440Y0540R180 S1      
327P1V8_PLL0_PEX1   C3211 -1          A01X+056311Y+113520X0280Y0320R180 S1      
327P1V8_PLL0_PEX1   C3190 -1          A01X+056752Y+111993X0120Y0150R270 S1      
327P1V8_PLL0_PEX1   L111  -1          A01X+057206Y+112201X0440Y0540R180 S1      
327P1V8_PLL0_PEX1   C3189 -1          A01X+056311Y+112260X0280Y0320R180 S1      
317P1V8_PLL0_PEX1   VIA   -    MD0100PA00X+056021Y+117256X0200Y         S0      
317P1V8_PLL0_PEX1   VIA   -    MD0100PA00X+056606Y+117256X0200Y         S0      
317P1V8_PLL0_PEX1   VIA   -    MD0100PA00X+056021Y+115996X0200Y         S0      
317P1V8_PLL0_PEX1   VIA   -    MD0100PA00X+056606Y+115996X0200Y         S0      
317P1V8_PLL0_PEX1   VIA   -    MD0100PA00X+056021Y+114736X0200Y         S0      
317P1V8_PLL0_PEX1   VIA   -    MD0100PA00X+056606Y+114736X0200Y         S0      
317P1V8_PLL0_PEX1   VIA   -    M      A01X+056021Y+113476X0200Y         S2      
017P1V8_PLL0_PEX1   VIA   -    M      A18X+056021Y+113476X0260Y         S2      
017P1V8_PLL0_PEX1         -    MD0100PA00X+056021Y+113476                       
317P1V8_PLL0_PEX1   VIA   -    MD0100PA00X+056606Y+113476X0200Y         S0      
317P1V8_PLL0_PEX1   VIA   -    MD0100PA00X+056021Y+112216X0200Y         S0      
317P1V8_PLL0_PEX1   VIA   -    MD0100PA00X+056606Y+112216X0200Y         S0      
327P1V8_PLL0_PEX1   C3237 -1          A01X+056311Y+111000X0280Y0320R180 S1      
317P1V8_PLL0_PEX1   VIA   -    MD0100PA00X+056021Y+110956X0200Y         S0      
317P1V8_PLL0_PEX1   VIA   -    M      A01X+056606Y+110956X0200Y         S2      
017P1V8_PLL0_PEX1   VIA   -    M      A18X+056606Y+110956X0260Y         S2      
017P1V8_PLL0_PEX1         -    MD0100PA00X+056606Y+110956                       
327P1V8_PLL0_PEX1   C3194 -1          A01X+056752Y+110733X0120Y0150R270 S1      
327P1V8_PLL0_PEX1   L112  -1          A01X+057206Y+110941X0440Y0540R180 S1      
317m1312            VIA   -    M      A01X+149372Y+078990X0200Y    R180 S2      
017m1312            VIA   -    M      A18X+149372Y+078990X0260Y    R180 S2      
017m1312                  -    MD0100PA00X+149372Y+078990                       
327m1312            U345  -21         A01X+148202Y+078990X0160Y0540R270 S1      
327m1312            R4684 -1          A01X+150692Y+079200X0198Y0197     S1      
327m1312            R4700 -2   M      A01X+150208Y+079200X0198Y0197     S1      
317m1313            VIA   -    M      A01X+129350Y+083550X0200Y         S2      
017m1313            VIA   -    M      A18X+129350Y+083550X0260Y         S2      
017m1313                  -    MD0100PA00X+129350Y+083550                       
327m1313            R4158 -2          A01X+129108Y+083550X0198Y0197     S1      
317m1313            VIA   -    MD0100PA00X+133265Y+084877X0180Y         S0      
327m1313            U6    -T7         A01X+133423Y+085034X0160Y         S1      
327m1314            VIA   -    M      A01X+162113Y+064594X0300Y         S1      
327m1314            R3311 -2          A01X+162136Y+065067X0198Y0197R270 S1      
327m1314            Q122  -5          A01X+161729Y+064087X0160Y0240     S1      
317m1315            VIA   -    M      A01X+048011Y+014872X0200Y         S2      
017m1315            VIA   -    M      A18X+048011Y+014872X0260Y         S2      
017m1315                  -    MD0100PA00X+048011Y+014872                       
327m1315            U367  -G          A01X+047243Y+015330X0400Y0560     S1      
327m1315            R5553 -1          A01X+048298Y+014691X0198Y0197R270 S1      
317m1316            VIA   -           A01X+056748Y+102400X0200Y         S2      
017m1316            VIA   -           A18X+056748Y+102400X0260Y         S2      
017m1316                  -     D0100PA00X+056748Y+102400                       
327m1316            R4577 -2          A01X+056792Y+102693X0198Y0197     S1      
327m1316            C3248 -1          A01X+056734Y+102066X0280Y0320R180 S1      
327HP_NIC5_EN       PU49  -11         A01X+129516Y+048048X0110Y0240R270 S1      
317HP_NIC5_EN       VIA   -    MD0100PA00X+125922Y+045433X0200Y         S0      
317HP_NIC5_EN       VIA   -    MD0100PA00X+131128Y+037080X0200Y         S0      
317HP_NIC5_EN       VIA   -    MD0100PA00X+136072Y+042460X0200Y    R270 S0      
327HP_NIC5_EN       R955  -1          A01X+135792Y+042460X0198Y0197R180 S1      
327HP_NIC5_EN       R299  -2   M      A01X+123746Y+055014X0198Y0197R270 S1      
327HP_NIC5_EN       U34   -D          A01X+124686Y+055138X0400Y0560R180 S1      
317HP_NIC5_EN       VIA   -    MD0100PA00X+123494Y+055014X0200Y    R180 S0      
327HP_NIC5_EN       C2880 -1   M      A01X+130227Y+048738X0198Y0197     S1      
317HP_NIC5_EN       VIA   -    M      A01X+129930Y+048738X0200Y         S2      
017HP_NIC5_EN       VIA   -    M      A18X+129930Y+048738X0260Y         S2      
017HP_NIC5_EN             -    MD0100PA00X+129930Y+048738                       
327HP_NIC5_EN       R4449 -1          A01X+131241Y+037348X0198Y0197R090 S1      
327HP_NIC5_EN       R6031 -1          A01X+126162Y+045433X0198Y0197     S1      
327m1317            VIA   -    M      A18X+092113Y+083359X0260Y         S2      
327m1317            R4860 -2          A18X+092179Y+081662X0198Y0197R270 S2      
327m1317            U5    -D4         A01X+091759Y+084687X0160Y    R180 S1      
317m1317            VIA   -    MD0100PA00X+091916Y+084529X0180Y    R270 S0      
317m1318            VIA   -    M      A01X+082976Y+084267X0200Y    R270 S2      
017m1318            VIA   -    M      A18X+082976Y+084267X0260Y    R270 S2      
017m1318                  -    MD0100PA00X+082976Y+084267                       
327m1318            R4891 -1          A01X+083311Y+083666X0198Y0197R270 S1      
327m1318            U89   -7          A01X+083010Y+084865X0110Y0280R180 S1      
327m1319            VIA   -    M      A01X+161454Y+062870X0300Y         S1      
327m1319            Q122  -2          A01X+161729Y+063379X0160Y0240     S1      
327m1319            R3310 -2          A01X+161454Y+062394X0198Y0197R090 S1      
327m1320            PU60  -11         A01X+033126Y+022506X0110Y0240     S1      
317m1320            VIA   -    MD0100PA00X+030818Y+015737X0200Y         S0      
327m1320            C2892 -1          A01X+032565Y+023286X0198Y0197R090 S1      
317m1320            VIA   -    M      A01X+032968Y+022865X0200Y    R090 S2      
017m1320            VIA   -    M      A18X+032968Y+022865X0260Y    R090 S2      
017m1320                  -    MD0100PA00X+032968Y+022865                       
327m1320            R5879 -1          A01X+031822Y+013079X0198Y0197R270 S1      
327m1320            R5549 -1   M      A01X+031152Y+014778X0198Y0197R090 S1      
317m1321            VIA   -    M      A01X+143400Y+075196X0200Y    R180 S2      
017m1321            VIA   -    M      A18X+143400Y+075196X0260Y    R180 S2      
017m1321                  -    MD0100PA00X+143400Y+075196                       
327m1321            R4639 -1          A01X+141558Y+075300X0198Y0197R180 S1      
327m1321            R4654 -2   M      A01X+142042Y+075300X0198Y0197R180 S1      
327m1321            U344  -3          A01X+144198Y+075096X0160Y0540R270 S1      
317m1322            VIA   -    MD0100PA00X+143688Y+110690X0200Y    R090 S0      
327m1322            PU15  -38         A01X+143516Y+111023X0090Y0240R180 S1      
327m1322            PU11  -29         A01X+138416Y+102675X0070Y0240     S1      
317m1322            VIA   -    M      A01X+138478Y+103378X0200Y    R090 S2      
017m1322            VIA   -    M      A18X+138478Y+103378X0260Y    R090 S2      
017m1322                  -    MD0100PA00X+138478Y+103378                       
327m1323            VIA   -    M      A18X+090263Y+082803X0260Y         S2      
327m1323            U5    -C9         A01X+090184Y+084372X0160Y    R180 S1      
317m1323            VIA   -    MD0100PA00X+090027Y+084214X0180Y    R270 S0      
327m1323            R5294 -1          A18X+090377Y+082356X0198Y0197R090 S2      
327m1324            VIA   -    M      A01X+070036Y+062870X0300Y         S1      
327m1324            Q120  -2          A01X+070312Y+063379X0160Y0240     S1      
327m1324            R3306 -2          A01X+070036Y+062394X0198Y0197R090 S1      
317m1325            VIA   -    M      A01X+143400Y+075696X0200Y    R180 S2      
017m1325            VIA   -    M      A18X+143400Y+075696X0260Y    R180 S2      
017m1325                  -    MD0100PA00X+143400Y+075696                       
327m1325            R4640 -1          A01X+141558Y+075700X0198Y0197R180 S1      
327m1325            R4655 -2   M      A01X+142042Y+075700X0198Y0197R180 S1      
327m1325            U344  -2          A01X+144198Y+075352X0160Y0540R270 S1      
327m1326            R3605 -1          A18X+138250Y+092108X0198Y0197R090 S2      
327m1326            C4501 -1          A01X+049391Y+067736X0198Y0197R090 S1      
317m1326            VIA   -    MD0100PA00X+049607Y+066598X0200Y         S0      
327m1326            U438  -1   M      A01X+049388Y+067120X0140Y0440R180 S1      
317m1326            VIA   -    MD0100PA00X+137850Y+093050X0200Y         S0      
317m1326            VIA   -    M      A01X+049162Y+093877X0200Y         S2      
017m1326            VIA   -    M      A18X+049162Y+093877X0260Y         S2      
017m1326                  -    MD0100PA00X+049162Y+093877                       
327m1327            VIA   -    M      A01X+024987Y+064594X0300Y         S1      
327m1327            Q119  -5          A01X+024603Y+064087X0160Y0240     S1      
327m1327            R3305 -2          A01X+025010Y+065067X0198Y0197R270 S1      
327m1328            VIA   -    M      A01X+031646Y+015486X0300Y         S1      
327m1328            R5549 -2          A01X+031152Y+015092X0198Y0197R090 S1      
327m1328            R5548 -2   M      A01X+031152Y+015486X0198Y0197R270 S1      
327m1328            U366  -D          A01X+032617Y+016196X0400Y0560     S1      
317m1329            VIA   -    M      A01X+147672Y+074840X0200Y    R180 S2      
017m1329            VIA   -    M      A18X+147672Y+074840X0260Y    R180 S2      
017m1329                  -    MD0100PA00X+147672Y+074840                       
327m1329            U344  -21         A01X+146502Y+074840X0160Y0540R270 S1      
327m1329            R4641 -1          A01X+148992Y+075050X0198Y0197     S1      
327m1329            R4656 -2   M      A01X+148508Y+075050X0198Y0197     S1      
327m1330            R6296 -2          A01X+081916Y+083004X0198Y0197R180 S1      
327m1330            R4892 -1          A01X+081883Y+083667X0198Y0197R090 S1      
317m1330            VIA   -    M      A01X+081586Y+083010X0200Y    R270 S2      
017m1330            VIA   -    M      A18X+081586Y+083010X0260Y    R270 S2      
017m1330                  -    MD0100PA00X+081586Y+083010                       
317m1330            VIA   -    MD0100PA00X+088609Y+083532X0180Y         S0      
327m1330            U5    -A14        A01X+088609Y+083742X0160Y    R180 S1      
327m1331            VIA   -    M      A01X+089919Y+082127X0300Y    R270 S1      
327m1331            U5    -B9         A01X+090184Y+084057X0160Y    R180 S1      
327m1331            R5293 -1          A01X+089992Y+081662X0198Y0197R270 S1      
317m1332            VIA   -    M      A01X+033010Y+014872X0200Y         S2      
017m1332            VIA   -    M      A18X+033010Y+014872X0260Y         S2      
017m1332                  -    MD0100PA00X+033010Y+014872                       
327m1332            U366  -G          A01X+032243Y+015330X0400Y0560     S1      
327m1332            R5550 -1          A01X+033298Y+014691X0198Y0197R270 S1      
317m1333            VIA   -    M      A01X+145262Y+083646X0200Y    R180 S2      
017m1333            VIA   -    M      A18X+145262Y+083646X0260Y    R180 S2      
017m1333                  -    MD0100PA00X+145262Y+083646                       
327m1333            U343  -3          A01X+145898Y+083646X0160Y0540R270 S1      
327m1333            R4620 -1          A01X+143258Y+083850X0198Y0197R180 S1      
327m1333            R4635 -2   M      A01X+143742Y+083850X0198Y0197R180 S1      
317m1334            VIA   -    MD0100PA00X+020854Y+062159X0200Y         S0      
317m1334            VIA   -    MD0100PA00X+137050Y+093050X0200Y         S0      
317m1334            VIA   -    M      A01X+025230Y+083102X0200Y         S2      
017m1334            VIA   -    M      A18X+025230Y+083102X0260Y         S2      
017m1334                  -    MD0100PA00X+025230Y+083102                       
327m1334            R3604 -2          A18X+137450Y+092108X0198Y0197R270 S2      
327m1334            U11   -2          A18X+023745Y+061980X0220Y0530R090 S2      
317m1335            VIA   -           A01X+088556Y+054366X0200Y         S2      
017m1335            VIA   -           A18X+088556Y+054366X0260Y         S2      
017m1335                  -     D0100PA00X+088556Y+054366                       
327m1335            U117  -A9         A01X+090294Y+056404X0070Y0220R180 S1      
327m1336            VIA   -    M      A18X+089764Y+083941X0200Y         S2      
327m1336            R5295 -1          A18X+089982Y+082356X0198Y0197R090 S2      
327m1336            U5    -D9         A01X+090184Y+084687X0160Y    R180 S1      
317m1336            VIA   -    MD0100PA00X+090027Y+084529X0180Y    R270 S0      
327m1337            VIA   -    M      A01X+024328Y+062870X0300Y         S1      
327m1337            Q119  -2          A01X+024603Y+063379X0160Y0240     S1      
327m1337            R3304 -2          A01X+024328Y+062394X0198Y0197R090 S1      
327m1338            PU59  -11         A01X+022890Y+022506X0110Y0240     S1      
327m1338            R5878 -1          A01X+021597Y+013090X0198Y0197R270 S1      
327m1338            R5546 -1   M      A01X+020916Y+014775X0198Y0197R090 S1      
317m1338            VIA   -    MD0100PA00X+020582Y+015737X0200Y         S0      
327m1338            C2889 -1          A01X+022329Y+023286X0198Y0197R090 S1      
317m1338            VIA   -    M      A01X+022732Y+022865X0200Y    R090 S2      
017m1338            VIA   -    M      A18X+022732Y+022865X0260Y    R090 S2      
017m1338                  -    MD0100PA00X+022732Y+022865                       
317m1339            VIA   -    M      A01X+144900Y+084450X0200Y    R180 S2      
017m1339            VIA   -    M      A18X+144900Y+084450X0260Y    R180 S2      
017m1339                  -    MD0100PA00X+144900Y+084450                       
327m1339            U343  -2          A01X+145898Y+083902X0160Y0540R270 S1      
327m1339            R4621 -1          A01X+143258Y+084250X0198Y0197R180 S1      
327m1339            R4636 -2   M      A01X+143742Y+084250X0198Y0197R180 S1      
317m1340            VIA   -    M      A01X+129350Y+085150X0200Y         S2      
017m1340            VIA   -    M      A18X+129350Y+085150X0260Y         S2      
017m1340                  -    MD0100PA00X+129350Y+085150                       
327m1340            R4156 -1          A01X+129108Y+085150X0198Y0197R180 S1      
317m1340            VIA   -    MD0100PA00X+132320Y+085192X0180Y         S0      
327m1340            U6    -R4         A01X+132478Y+085349X0160Y         S1      
317m1341            VIA   -           A01X+088220Y+053920X0200Y         S2      
017m1341            VIA   -           A18X+088220Y+053920X0260Y         S2      
017m1341                  -     D0100PA00X+088220Y+053920                       
327m1341            U117  -A8         A01X+090097Y+056404X0070Y0220R180 S1      
327m1342            VIA   -           A01X+138632Y+099605X0300Y         S1      
327m1342            PU11  -4          A01X+138731Y+100785X0070Y0240     S1      
317m1343            VIA   -    M      A01X+149304Y+083390X0200Y    R180 S2      
017m1343            VIA   -    M      A18X+149304Y+083390X0260Y    R180 S2      
017m1343                  -    MD0100PA00X+149304Y+083390                       
327m1343            U343  -21         A01X+148202Y+083390X0160Y0540R270 S1      
327m1343            R4622 -1          A01X+150692Y+083600X0198Y0197     S1      
327m1343            R4637 -2   M      A01X+150208Y+083600X0198Y0197     S1      
327m1344            U428  -1          A01X+170997Y+115324X0140Y0520     S1      
327m1344            U428  -6          A01X+171509Y+116781X0140Y0520     S1      
317m1344            VIA   -    MD0100PA00X+129350Y+087580X0200Y         S0      
327m1344            R4174 -1          A18X+129642Y+087580X0198Y0197R180 S2      
317m1344            VIA   -    MD0100PA00X+129972Y+102414X0200Y         S0      
317m1344            VIA   -    M      A01X+171133Y+114661X0200Y         S2      
017m1344            VIA   -    M      A18X+171133Y+114661X0260Y         S2      
017m1344                  -    MD0100PA00X+171133Y+114661                       
317m1344            VIA   -    MD0100PA00X+174868Y+099399X0200Y         S0      
327m1344            R6399 -2   M      A01X+171511Y+114607X0198Y0197R180 S1      
327m1344            U428  -3   M      A01X+171509Y+115324X0140Y0520     S1      
327m1345            VIA   -    M      A01X+088014Y+054960X0300Y    R180 S1      
327m1345            R4219 -2          A01X+087249Y+054977X0198Y0197     S1      
327m1345            U117  -B4         A01X+089605Y+056699X0110Y0180R180 S1      
317m1346            VIA   -    MD0100PA00X+133917Y+110690X0200Y    R090 S0      
327m1346            PU12  -38         A01X+133745Y+111023X0090Y0240R180 S1      
317m1346            VIA   -    M      A01X+138515Y+104659X0200Y    R090 S2      
017m1346            VIA   -    M      A18X+138515Y+104659X0260Y    R090 S2      
017m1346                  -    MD0100PA00X+138515Y+104659                       
327m1346            PU11  -23         A01X+139361Y+102675X0070Y0240     S1      
327m1347            VIA   -    M      A01X+021410Y+015486X0300Y         S1      
327m1347            U365  -D          A01X+022381Y+016196X0400Y0560     S1      
327m1347            R5546 -2          A01X+020916Y+015090X0198Y0197R090 S1      
327m1347            R5545 -2   M      A01X+020916Y+015486X0198Y0197R270 S1      
327m1348            VIA   -    M      A01X+025612Y+062079X0300Y         S1      
327m1348            R2472 -1          A01X+025128Y+062079X0198Y0197R090 S1      
327m1348            J21   -A70        A01X+027030Y+062344X0140Y0480R090 S1      
317m1349            VIA   -    M      A01X+022774Y+014872X0200Y         S2      
017m1349            VIA   -    M      A18X+022774Y+014872X0260Y         S2      
017m1349                  -    MD0100PA00X+022774Y+014872                       
327m1349            U365  -G          A01X+022007Y+015330X0400Y0560     S1      
327m1349            R5547 -1          A01X+023061Y+014691X0198Y0197R270 S1      
317m1350            VIA   -    M      A01X+129350Y+084350X0200Y         S2      
017m1350            VIA   -    M      A18X+129350Y+084350X0260Y         S2      
017m1350                  -    MD0100PA00X+129350Y+084350                       
327m1350            R4155 -1          A01X+129108Y+084350X0198Y0197R180 S1      
317m1350            VIA   -    MD0100PA00X+132950Y+085192X0180Y         S0      
327m1350            U6    -R6         A01X+133108Y+085349X0160Y         S1      
327m1351            VIA   -    M      A01X+117029Y+062079X0300Y         S1      
327m1351            R2476 -1          A01X+116545Y+062079X0198Y0197R090 S1      
327m1351            J25   -A70        A01X+118448Y+062344X0140Y0480R090 S1      
317m1352            VIA   -    MD0100PA00X+125250Y+101429X0200Y         S0      
317m1352            VIA   -    MD0100PA00X+129350Y+087180X0200Y         S0      
327m1352            R4173 -1          A18X+129642Y+087180X0198Y0197R180 S2      
317m1352            VIA   -    M      A01X+125420Y+114660X0200Y         S2      
017m1352            VIA   -    M      A18X+125420Y+114660X0260Y         S2      
017m1352                  -    MD0100PA00X+125420Y+114660                       
327m1352            R6395 -2   M      A01X+125802Y+114607X0198Y0197R180 S1      
327m1352            U427  -6          A01X+125800Y+116781X0140Y0520     S1      
327m1352            U427  -3   M      A01X+125800Y+115324X0140Y0520     S1      
327m1352            U427  -1          A01X+125288Y+115324X0140Y0520     S1      
317JTAG_CONN_TCK    JP2   -8    D0410PA00X+103064Y+075455X0610Y         S3      
317JTAG_CONN_TCK    VIA   -    M      A01X+101802Y+075156X0200Y         S2      
017JTAG_CONN_TCK    VIA   -    M      A18X+101802Y+075156X0280Y         S2      
017JTAG_CONN_TCK          -    MD0100PA00X+101802Y+075156                       
327JTAG_CONN_TCK    R4901 -2          A01X+101947Y+075455X0198Y0197     S1      
327m1353            PU56  -11         A01X+012654Y+022506X0110Y0240     S1      
327m1353            R5867 -1          A01X+011361Y+013090X0198Y0197R270 S1      
327m1353            R5543 -1   M      A01X+010680Y+014775X0198Y0197R090 S1      
317m1353            VIA   -    M      A01X+010346Y+015737X0200Y         S2      
017m1353            VIA   -    M      A18X+010346Y+015737X0260Y         S2      
017m1353                  -    MD0100PA00X+010346Y+015737                       
327m1353            C2887 -1          A01X+012093Y+023286X0198Y0197R090 S1      
317m1353            VIA   -    MD0100PA00X+012496Y+022865X0200Y         S0      
317JTAG_CONN_TMS    VIA   -    M      A01X+101766Y+077910X0200Y         S2      
017JTAG_CONN_TMS    VIA   -    M      A18X+101766Y+077910X0280Y         S2      
017JTAG_CONN_TMS          -    MD0100PA00X+101766Y+077910                       
327JTAG_CONN_TMS    R4900 -2          A01X+101947Y+077597X0198Y0197     S1      
317JTAG_CONN_TMS    JP2   -6    D0410PA00X+103064Y+077455X0610Y         S3      
327m1354            R6391 -2   M      A01X+080094Y+114607X0198Y0197R180 S1      
317m1354            VIA   -    M      A01X+079716Y+114661X0200Y         S2      
017m1354            VIA   -    M      A18X+079716Y+114661X0260Y         S2      
017m1354                  -    MD0100PA00X+079716Y+114661                       
327m1354            U426  -6          A01X+080091Y+116781X0140Y0520     S1      
327m1354            U426  -3   M      A01X+080091Y+115324X0140Y0520     S1      
327m1354            U426  -1          A01X+079579Y+115324X0140Y0520     S1      
327m1354            R4172 -1          A01X+128792Y+087778X0198Y0197     S1      
317m1354            VIA   -    MD0100PA00X+081300Y+080500X0200Y         S0      
317m1354            VIA   -    MD0100PA00X+128530Y+087728X0200Y    R180 S0      
327m1355            R4232 -2          A01X+082014Y+074250X0198Y0197     S1      
317m1355            VIA   -    M      A01X+134523Y+077768X0200Y         S2      
017m1355            VIA   -    M      A18X+134523Y+077768X0260Y         S2      
017m1355                  -    MD0100PA00X+134523Y+077768                       
327m1355            U324  -22         A01X+132128Y+077144X0160Y0540R270 S1      
317m1355            VIA   -    MD0100PA00X+081979Y+073963X0200Y         S0      
327m1356            VIA   -    M      A01X+011173Y+015486X0300Y         S1      
327m1356            U364  -D          A01X+012145Y+016196X0400Y0560     S1      
327m1356            R5543 -2          A01X+010680Y+015090X0198Y0197R090 S1      
327m1356            R5542 -2   M      A01X+010680Y+015486X0198Y0197R270 S1      
327m1357            PR7139-1          A18X+139308Y+102720X0198Y0197R090 S2      
317m1357            VIA   -    MD0100PA00X+138573Y+102948X0200Y         S0      
327m1357            PU11  -28         A01X+138573Y+102675X0070Y0240     S1      
327m1357            VIA   -    M      A18X+138813Y+102720X0260Y         S2      
327BIC_ADCVREFN1    VIA   -    M      A18X+093733Y+086433X0260Y         S2      
327BIC_ADCVREFN1    C3619 -1          A18X+094503Y+086472X0164Y0164R180 S2      
327BIC_ADCVREFN1    C3618 -2   M      A18X+094177Y+086490X0164Y0164R090 S2      
327BIC_ADCVREFN1    U5    -H3         A01X+092074Y+085946X0160Y    R180 S1      
317BIC_ADCVREFN1    VIA   -    MD0100PA00X+092231Y+085789X0180Y    R270 S0      
317JTAG_CONN_TDI    VIA   -    M      A01X+101807Y+079849X0200Y         S2      
017JTAG_CONN_TDI    VIA   -    M      A18X+101807Y+079849X0280Y         S2      
017JTAG_CONN_TDI          -    MD0100PA00X+101807Y+079849                       
327JTAG_CONN_TDI    R2537 -2          A01X+101892Y+080274X0198Y0197R270 S1      
317JTAG_CONN_TDI    JP2   -3    D0410PA00X+103064Y+080455X0610Y         S3      
317m1358            VIA   -    M      A01X+012538Y+014872X0200Y         S2      
017m1358            VIA   -    M      A18X+012538Y+014872X0260Y         S2      
017m1358                  -    MD0100PA00X+012538Y+014872                       
327m1358            U364  -G          A01X+011771Y+015330X0400Y0560     S1      
327m1358            R5544 -1          A01X+012825Y+014691X0198Y0197R270 S1      
317m1359            VIA   -    MD0100PA00X+128530Y+088178X0200Y    R180 S0      
317m1359            VIA   -    M      A01X+034050Y+114750X0200Y         S2      
017m1359            VIA   -    M      A18X+034050Y+114750X0260Y         S2      
017m1359                  -    MD0100PA00X+034050Y+114750                       
317m1359            VIA   -    MD0100PA00X+036676Y+093455X0200Y         S0      
317m1359            VIA   -    MD0100PA00X+036204Y+081477X0200Y         S0      
327m1359            R4171 -1          A01X+128792Y+088178X0198Y0197     S1      
327m1359            U425  -3   M      A01X+034383Y+115324X0140Y0520     S1      
327m1359            R6389 -2   M      A01X+034385Y+114607X0198Y0197R180 S1      
327m1359            U425  -1          A01X+033871Y+115324X0140Y0520     S1      
327m1359            U425  -6          A01X+034383Y+116781X0140Y0520     S1      
317RST_PLTRST_N     VIA   -    M      A01X+133030Y+075133X0200Y         S2      
017RST_PLTRST_N     VIA   -    M      A18X+133030Y+075133X0260Y         S2      
017RST_PLTRST_N           -    MD0100PA00X+133030Y+075133                       
327RST_PLTRST_N     R4243 -2          A01X+133922Y+074968X0198Y0197R180 S1      
327RST_PLTRST_N     U324  -16         A01X+132128Y+075608X0160Y0540R270 S1      
317m1360            VIA   -    M      A01X+127969Y+091980X0200Y         S2      
017m1360            VIA   -    M      A18X+127969Y+091980X0260Y         S2      
017m1360                  -    MD0100PA00X+127969Y+091980                       
327m1360            R4389 -1          A01X+128349Y+092392X0198Y0197R090 S1      
327m1360            R4390 -1          A01X+127149Y+092392X0198Y0197R090 S1      
327m1360            R4387 -1   M      A01X+127549Y+092392X0198Y0197R090 S1      
327m1360            R4388 -1   M      A01X+127949Y+092392X0198Y0197R090 S1      
327m1360            R4386 -2          A01X+128392Y+091950X0198Y0197R180 S1      
327BIC_ADCVREFP1    VIA   -    M      A18X+093114Y+086567X0260Y         S2      
327BIC_ADCVREFP1    C3617 -1          A18X+094515Y+086817X0164Y0164R180 S2      
327BIC_ADCVREFP1    C3618 -1   M      A18X+094177Y+086805X0164Y0164R090 S2      
327BIC_ADCVREFP1    U5    -J3         A01X+092074Y+086262X0160Y    R180 S1      
317BIC_ADCVREFP1    VIA   -    MD0100PA00X+092231Y+086419X0180Y    R270 S0      
317JTAG_CONN_TDO    VIA   -    M      A01X+101796Y+081210X0200Y         S2      
017JTAG_CONN_TDO    VIA   -    M      A18X+101796Y+081210X0280Y         S2      
017JTAG_CONN_TDO          -    MD0100PA00X+101796Y+081210                       
327JTAG_CONN_TDO    R4902 -2          A01X+101943Y+081505X0198Y0197     S1      
317JTAG_CONN_TDO    JP2   -2    D0410PA00X+103064Y+081455X0610Y         S3      
327BIC_FWSPIMISO    U5    -C8         A01X+090499Y+084372X0160Y    R180 S1      
327BIC_FWSPIMISO    VIA   -    M      A18X+090904Y+080646X0260Y         S2      
327BIC_FWSPIMISO    R5525 -2   M      A18X+090942Y+081662X0198Y0197R270 S2      
327BIC_FWSPIMISO    R5526 -2          A18X+091372Y+080646X0198Y0197R270 S2      
317BIC_FWSPIMISO    VIA   -    MD0100PA00X+090656Y+084214X0180Y    R270 S0      
317TP_JTAG_PIN5     JP2   -5    D0410PA00X+103064Y+078455X0610Y         S3      
327m1361            VIA   -    M      A18X+118822Y+095179X0260Y    R270 S2      
327m1361            R4102 -1          A18X+119322Y+094636X0198Y0197R090 S2      
327m1361            R4108 -1   M      A18X+118922Y+094636X0198Y0197R090 S2      
327m1361            R4103 -2          A18X+120272Y+096771X0198Y0197R090 S2      
327m1361            U318  -3   M      A18X+119080Y+095960X0170Y0460R180 S2      
327BIC_FWSPIMOSI    VIA   -           A18X+091458Y+082713X0260Y         S2      
327BIC_FWSPIMOSI    U5    -C5         A01X+091444Y+084372X0160Y    R180 S1      
317BIC_FWSPIMOSI    VIA   -    MD0100PA00X+091601Y+084214X0180Y    R270 S0      
317m1362            VIA   -    M      A01X+143500Y+084650X0200Y         S2      
017m1362            VIA   -    M      A18X+143500Y+084650X0260Y         S2      
017m1362                  -    MD0100PA00X+143500Y+084650                       
327m1362            R4610 -2          A01X+143258Y+084650X0198Y0197     S1      
327m1362            R4619 -1   M      A01X+143742Y+084650X0198Y0197     S1      
327m1362            U343  -1          A01X+145898Y+084197X0240Y0540R270 S1      
317m1363            VIA   -    MD0080PA00X+162293Y+111821X0160Y         S0      
317m1363            VIA   -    MD0100PA00X+147471Y+068525X0200Y         S0      
327m1363            PEX3  -AV29       A01X+162106Y+111634X0180Y         S1      
317m1363            VIA   -    M      A01X+152710Y+099786X0200Y         S2      
017m1363            VIA   -    M      A18X+152710Y+099786X0260Y         S2      
017m1363                  -    MD0100PA00X+152710Y+099786                       
327m1363            R3965 -1          A01X+152710Y+099511X0198Y0197R270 S1      
317m1363            VIA   -    MD0100PA00X+132701Y+064606X0200Y         S0      
327m1363            R4807 -1          A01X+132458Y+064500X0198Y0197R180 S1      
327m1364            VIA   -    M      A18X+120322Y+096279X0260Y    R270 S2      
327m1364            R4104 -2          A18X+120722Y+096771X0198Y0197R090 S2      
327m1364            U318  -2   M      A18X+119336Y+095960X0170Y0460R180 S2      
327m1364            R4107 -1          A18X+120122Y+094636X0198Y0197R090 S2      
327m1364            R4101 -1   M      A18X+119722Y+094636X0198Y0197R090 S2      
317m1365            VIA   -    M      A01X+131900Y+064100X0200Y         S2      
017m1365            VIA   -    M      A18X+131900Y+064100X0260Y         S2      
017m1365                  -    MD0100PA00X+131900Y+064100                       
327m1365            R4805 -1          A01X+132142Y+059450X0198Y0197     S1      
327m1365            R4807 -2          A01X+132142Y+064500X0198Y0197R180 S1      
327m1365            R4799 -1   M      A01X+132142Y+064100X0198Y0197     S1      
327m1366            U116  -41         A01X+133345Y+035321X0070Y0340R180 S1      
317m1366            VIA   -    M      A01X+133192Y+035984X0200Y         S2      
017m1366            VIA   -    M      A18X+133192Y+035984X0260Y         S2      
017m1366                  -    MD0100PA00X+133192Y+035984                       
317m1366            VIA   -    MD0100PA00X+143972Y+035039X0200Y         S0      
317m1366            VIA   -    MD0100PA00X+135900Y+081162X0200Y         S0      
327m1366            R4146 -1          A18X+136000Y+081642X0198Y0197R270 S2      
317m1367            VIA   -    M      A01X+133666Y+073768X0200Y         S2      
017m1367            VIA   -    M      A18X+133666Y+073768X0260Y         S2      
017m1367                  -    MD0100PA00X+133666Y+073768                       
327m1367            R4237 -2          A01X+133922Y+073768X0198Y0197R180 S1      
327m1367            U324  -13         A01X+132128Y+074801X0240Y0540R270 S1      
317m1367            VIA   -    MD0100PA00X+083158Y+085345X0200Y         S0      
317m1367            VIA   -    MD0100PA00X+083815Y+070022X0200Y         S0      
327m1367            R5478 -1          A18X+083070Y+084899X0198Y0197     S2      
317m1368            VIA   -    M      A01X+132700Y+059450X0200Y         S2      
017m1368            VIA   -    M      A18X+132700Y+059450X0260Y         S2      
017m1368                  -    MD0100PA00X+132700Y+059450                       
327m1368            U350  -1          A01X+135098Y+058997X0240Y0540R270 S1      
327m1368            R4830 -1   M      A01X+132942Y+059450X0198Y0197     S1      
327m1368            R4805 -2          A01X+132458Y+059450X0198Y0197     S1      
317m1369            VIA   -    M      A01X+096387Y+072506X0200Y         S2      
017m1369            VIA   -    M      A18X+096387Y+072506X0260Y         S2      
017m1369                  -    MD0100PA00X+096387Y+072506                       
327m1369            R3152 -2          A01X+095995Y+072846X0198Y0197R270 S1      
327m1369            U325  -1          A01X+096150Y+072080X0220Y0530R180 S1      
327m1369            R3153 -2   M      A01X+096395Y+072846X0198Y0197R270 S1      
327BIC_FWSPICK_R    VIA   -    M      A01X+097279Y+071099X0300Y         S1      
327BIC_FWSPICK_R    J19   -3          A01X+100119Y+069538X0500Y1350R090 S1      
327BIC_FWSPICK_R    R5504 -1          A01X+097371Y+071651X0198Y0197R090 S1      
317m1370            VIA   -    M      A01X+138396Y+036668X0200Y         S2      
017m1370            VIA   -    M      A18X+138396Y+036668X0260Y         S2      
017m1370                  -    MD0100PA00X+138396Y+036668                       
327m1370            U116  -37         A01X+133975Y+035321X0070Y0340R180 S1      
327m1370            R4142 -2          A18X+135100Y+081642X0198Y0197R090 S2      
317m1370            VIA   -    MD0100PA00X+135100Y+081162X0200Y         S0      
317m1371            VIA   -    M      A01X+133675Y+078168X0200Y         S2      
017m1371            VIA   -    M      A18X+133675Y+078168X0260Y         S2      
017m1371                  -    MD0100PA00X+133675Y+078168                       
327m1371            R4233 -2          A01X+133922Y+078168X0198Y0197R180 S1      
327m1371            U324  -23         A01X+132128Y+077399X0160Y0540R270 S1      
317m1372            VIA   -    M      A01X+134964Y+034086X0200Y         S2      
017m1372            VIA   -    M      A18X+134964Y+034086X0260Y         S2      
017m1372                  -    MD0100PA00X+134964Y+034086                       
327m1372            U116  -31         A01X+134270Y+034238X0070Y0340R090 S1      
317m1372            VIA   -    MD0100PA00X+143470Y+034712X0200Y         S0      
317m1372            VIA   -    MD0100PA00X+134900Y+080400X0200Y         S0      
327m1372            R4138 -2          A01X+134900Y+080642X0198Y0197R270 S1      
317m1373            VIA   -    M      A01X+132700Y+064100X0200Y         S2      
017m1373            VIA   -    M      A18X+132700Y+064100X0260Y         S2      
017m1373                  -    MD0100PA00X+132700Y+064100                       
327m1373            U349  -1          A01X+135098Y+063647X0240Y0540R270 S1      
327m1373            R4799 -2          A01X+132458Y+064100X0198Y0197     S1      
327m1373            R4810 -1   M      A01X+132942Y+064100X0198Y0197     S1      
317m1374            VIA   -    MD0100PA00X+134609Y+034080X0200Y         S0      
317m1374            VIA   -    M      A01X+139988Y+036716X0200Y         S2      
017m1374            VIA   -    M      A18X+139988Y+036716X0260Y         S2      
017m1374                  -    MD0100PA00X+139988Y+036716                       
317m1374            VIA   -    MD0100PA00X+133300Y+078800X0200Y         S0      
327m1374            R4134 -2          A01X+133300Y+079042X0198Y0197R270 S1      
327m1374            U116  -30         A01X+134270Y+034080X0070Y0340R090 S1      
327m1375            VIA   -    M      A01X+129999Y+084750X0300Y         S1      
327m1375            U6    -R2         A01X+131848Y+085349X0160Y         S1      
327m1375            R4157 -1          A01X+129108Y+084750X0198Y0197R180 S1      
317m1376            VIA   -    M      A01X+133666Y+074568X0200Y         S2      
017m1376            VIA   -    M      A18X+133666Y+074568X0260Y         S2      
017m1376                  -    MD0100PA00X+133666Y+074568                       
327m1376            R4242 -2          A01X+133922Y+074568X0198Y0197R180 S1      
327m1376            U324  -15         A01X+132128Y+075352X0160Y0540R270 S1      
327m1377            PU13  -6          A01X+137296Y+112155X0090Y0240R270 S1      
327BIC_FWSPICK      R6227 -1          A01X+094967Y+098882X0198Y0197R270 S1      
317BIC_FWSPICK      VIA   -    MD0100PA00X+095585Y+086290X0200Y         S0      
317BIC_FWSPICK      VIA   -    MD0100PA00X+094967Y+099156X0200Y         S0      
327BIC_FWSPICK      J19   -2          A01X+098970Y+070538X0500Y1350R090 S1      
317BIC_FWSPICK      VIA   -    M      A01X+095758Y+074417X0200Y         S2      
017BIC_FWSPICK      VIA   -    M      A18X+095758Y+074417X0260Y         S2      
017BIC_FWSPICK            -    MD0100PA00X+095758Y+074417                       
327BIC_FWSPICK      R5522 -2   M      A01X+098371Y+071651X0198Y0197R270 S1      
327BIC_FWSPICK      U5    -E7         A01X+090814Y+085002X0160Y    R180 S1      
317BIC_FWSPICK      VIA   -    MD0100PA00X+090971Y+084844X0180Y    R270 S0      
327m1378            U116  -24         A01X+133975Y+032998X0070Y0340     S1      
317m1378            VIA   -    M      A01X+134117Y+032593X0200Y         S2      
017m1378            VIA   -    M      A18X+134117Y+032593X0260Y         S2      
017m1378                  -    MD0100PA00X+134117Y+032593                       
327m1378            R4130 -2          A18X+132400Y+081642X0198Y0197R090 S2      
317m1378            VIA   -    MD0100PA00X+132300Y+081162X0200Y         S0      
327m1379            PU13  -31         A01X+135717Y+111023X0090Y0240R180 S1      
317FM_SLPS3_N       VIA   -    M      A01X+133009Y+076376X0200Y         S2      
017FM_SLPS3_N       VIA   -    M      A18X+133009Y+076376X0260Y         S2      
017FM_SLPS3_N             -    MD0100PA00X+133009Y+076376                       
327FM_SLPS3_N       R4248 -2          A01X+133922Y+076168X0198Y0197R180 S1      
327FM_SLPS3_N       U324  -19         A01X+132128Y+076376X0160Y0540R270 S1      
317RST_PEX2_SYS_N   VIA   -    MD0080PA00X+111722Y+121171X0160Y         S0      
317RST_PEX2_SYS_N   VIA   -    M      A01X+128349Y+092986X0200Y    R270 S2      
017RST_PEX2_SYS_N   VIA   -    M      A18X+128349Y+092986X0260Y    R270 S2      
017RST_PEX2_SYS_N         -    MD0100PA00X+128349Y+092986                       
327RST_PEX2_SYS_N   R4389 -2          A01X+128349Y+092707X0198Y0197R090 S1      
317RST_PEX2_SYS_N   VIA   -    MD0100PA00X+106688Y+093191X0200Y         S0      
317RST_PEX2_SYS_N   VIA   -    MD0100PA00X+104648Y+103454X0200Y         S0      
327RST_PEX2_SYS_N   PEX2  -M17        A01X+111909Y+121358X0180Y         S1      
317m1380            VIA   -    M      A01X+134799Y+032254X0200Y         S2      
017m1380            VIA   -    M      A18X+134799Y+032254X0260Y         S2      
017m1380                  -    MD0100PA00X+134799Y+032254                       
327m1380            R4126 -2          A01X+133300Y+080642X0198Y0197R270 S1      
317m1380            VIA   -    MD0100PA00X+133300Y+080400X0200Y         S0      
327m1380            U116  -23         A01X+133817Y+032998X0070Y0340     S1      
317m1381            VIA   -    M      A01X+133666Y+075368X0200Y         S2      
017m1381            VIA   -    M      A18X+133666Y+075368X0260Y         S2      
017m1381                  -    MD0100PA00X+133666Y+075368                       
327m1381            R4241 -2          A01X+133922Y+075368X0198Y0197R180 S1      
327m1381            U324  -17         A01X+132128Y+075864X0160Y0540R270 S1      
327m1382            PU12  -41         A01X+133739Y+112263X0120Y0180R090 S1      
317RST_PEX3_SYS_N   VIA   -    MD0080PA00X+157431Y+121171X0160Y         S0      
317RST_PEX3_SYS_N   VIA   -    MD0100PA00X+129263Y+097984X0200Y         S0      
317RST_PEX3_SYS_N   VIA   -    M      A01X+127266Y+092986X0200Y    R270 S2      
017RST_PEX3_SYS_N   VIA   -    M      A18X+127266Y+092986X0260Y    R270 S2      
017RST_PEX3_SYS_N         -    MD0100PA00X+127266Y+092986                       
327RST_PEX3_SYS_N   R4390 -2          A01X+127149Y+092707X0198Y0197R090 S1      
317RST_PEX3_SYS_N   VIA   -    MD0100PA00X+145735Y+097628X0200Y         S0      
317RST_PEX3_SYS_N   VIA   -    MD0100PA00X+150357Y+103454X0200Y         S0      
327RST_PEX3_SYS_N   PEX3  -M17        A01X+157618Y+121358X0180Y         S1      
327BIC_ADCVREFN0    VIA   -    M      A01X+093904Y+085493X0300Y         S1      
327BIC_ADCVREFN0    U5    -E1         A01X+092704Y+085002X0160Y    R180 S1      
327BIC_ADCVREFN0    C3616 -1          A01X+094754Y+086144X0164Y0164     S1      
327BIC_ADCVREFN0    C3615 -2   M      A01X+094372Y+086102X0164Y0164R090 S1      
327m1383            U116  -18         A01X+133030Y+032998X0070Y0340     S1      
317m1383            VIA   -    M      A01X+133236Y+032268X0200Y         S2      
017m1383            VIA   -    M      A18X+133236Y+032268X0260Y         S2      
017m1383                  -    MD0100PA00X+133236Y+032268                       
327m1383            R4122 -2          A01X+132500Y+080642X0198Y0197R270 S1      
317m1383            VIA   -    MD0100PA00X+132500Y+080400X0200Y         S0      
317RST_PEX1_SYS_N   VIA   -    MD0100PA00X+127949Y+092986X0200Y    R270 S0      
327RST_PEX1_SYS_N   R4388 -2          A01X+127949Y+092707X0198Y0197R090 S1      
317RST_PEX1_SYS_N   VIA   -    MD0100PA00X+056416Y+089441X0200Y         S0      
317RST_PEX1_SYS_N   VIA   -    M      A01X+058788Y+103483X0200Y         S2      
017RST_PEX1_SYS_N   VIA   -    M      A18X+058788Y+103483X0260Y         S2      
017RST_PEX1_SYS_N         -    MD0100PA00X+058788Y+103483                       
327RST_PEX1_SYS_N   PEX1  -M17        A01X+066201Y+121358X0180Y         S1      
317RST_PEX1_SYS_N   VIA   -    MD0080PA00X+066014Y+121171X0160Y         S0      
327BIC_ADCVREFP0    VIA   -    M      A01X+093898Y+084989X0300Y         S1      
327BIC_ADCVREFP0    U5    -E2         A01X+092389Y+085002X0160Y    R180 S1      
327BIC_ADCVREFP0    C3614 -1          A01X+094754Y+085744X0164Y0164     S1      
327BIC_ADCVREFP0    C3615 -1   M      A01X+094372Y+085786X0164Y0164R090 S1      
327m1384            PU12  -6          A01X+134083Y+112155X0090Y0240R270 S1      
327RST_PEX0_SYS_N   PEX0  -M17        A01X+020492Y+121358X0180Y         S1      
317RST_PEX0_SYS_N   VIA   -    MD0080PA00X+020492Y+121358X0160Y         S0      
317RST_PEX0_SYS_N   VIA   -    MD0100PA00X+127549Y+092986X0200Y    R270 S0      
327RST_PEX0_SYS_N   R4387 -2          A01X+127549Y+092707X0198Y0197R090 S1      
317RST_PEX0_SYS_N   VIA   -    M      A01X+006860Y+085942X0200Y         S2      
017RST_PEX0_SYS_N   VIA   -    M      A18X+006860Y+085942X0260Y         S2      
017RST_PEX0_SYS_N         -    MD0100PA00X+006860Y+085942                       
317RST_PEX0_SYS_N   VIA   -    MD0100PA00X+013358Y+109747X0200Y         S0      
327m1385            PEX2  -AV29       A01X+116398Y+111634X0180Y         S1      
317m1385            VIA   -    MD0080PA00X+116585Y+111821X0160Y         S0      
317m1385            VIA   -    MD0100PA00X+132697Y+073646X0200Y         S0      
317m1385            VIA   -    M      A01X+107001Y+099786X0200Y         S2      
017m1385            VIA   -    M      A18X+107001Y+099786X0260Y         S2      
017m1385                  -    MD0100PA00X+107001Y+099786                       
317m1385            VIA   -    MD0100PA00X+102988Y+071176X0200Y         S0      
327m1385            R3963 -1          A01X+107001Y+099511X0198Y0197R270 S1      
327m1385            R4737 -1          A01X+132454Y+073646X0198Y0197R180 S1      
317m1386            VIA   -    M      A01X+133800Y+065350X0200Y    R180 S2      
017m1386            VIA   -    M      A18X+133800Y+065350X0260Y    R180 S2      
017m1386                  -    MD0100PA00X+133800Y+065350                       
327m1386            R4773 -1          A01X+133258Y+065350X0198Y0197R180 S1      
327m1386            U348  -9          A01X+135098Y+066010X0160Y0540R270 S1      
317m1387            VIA   -    MD0100PA00X+131540Y+033371X0200Y         S0      
327m1387            U116  -11         A01X+131947Y+033450X0070Y0340R270 S1      
327m1387            R4118 -2          A18X+131500Y+081642X0198Y0197R090 S2      
317m1387            VIA   -    M      A01X+131500Y+081162X0200Y         S2      
017m1387            VIA   -    M      A18X+131500Y+081162X0260Y         S2      
017m1387                  -    MD0100PA00X+131500Y+081162                       
327m1388            R4737 -2          A01X+132140Y+073646X0198Y0197R180 S1      
327m1388            R4736 -1   M      A01X+132142Y+073250X0198Y0197     S1      
317m1388            VIA   -    MD0100PA00X+131900Y+073250X0200Y         S0      
317m1388            VIA   -    M      A01X+131900Y+068550X0200Y         S2      
017m1388            VIA   -    M      A18X+131900Y+068550X0260Y         S2      
017m1388                  -    MD0100PA00X+131900Y+068550                       
327m1388            R4738 -1          A01X+132142Y+068550X0198Y0197     S1      
317m1389            VIA   -    M      A01X+134674Y+065549X0200Y    R180 S2      
017m1389            VIA   -    M      A18X+134674Y+065549X0260Y    R180 S2      
017m1389                  -    MD0100PA00X+134674Y+065549                       
327m1389            R4774 -1          A01X+133258Y+064950X0198Y0197R180 S1      
327m1389            U348  -10         A01X+135098Y+065754X0160Y0540R270 S1      
327m1390            PU13  -41         A01X+136952Y+112263X0120Y0180R090 S1      
317m1391            VIA   -    M      A01X+132700Y+068550X0200Y         S2      
017m1391            VIA   -    M      A18X+132700Y+068550X0260Y         S2      
017m1391                  -    MD0100PA00X+132700Y+068550                       
327m1391            U348  -1          A01X+135098Y+068097X0240Y0540R270 S1      
327m1391            R4767 -1   M      A01X+132942Y+068550X0198Y0197     S1      
327m1391            R4738 -2          A01X+132458Y+068550X0198Y0197     S1      
327m1392            VIA   -    M      A01X+133407Y+075768X0300Y         S1      
327m1392            R4247 -2          A01X+133922Y+075768X0198Y0197R180 S1      
327m1392            U324  -18         A01X+132128Y+076120X0160Y0540R270 S1      
327LED_POSTCODE_5   U324  -9          A01X+129825Y+075608X0160Y0540R270 S1      
317LED_POSTCODE_5   VIA   -    MD0100PA00X+127954Y+075358X0200Y         S0      
327LED_POSTCODE_5   U6    -J1         A01X+131533Y+087239X0160Y         S1      
327LED_POSTCODE_5   R2983 -1          A01X+127684Y+086449X0198Y0197R180 S1      
317LED_POSTCODE_5   VIA   -    M      A01X+127946Y+086449X0200Y         S2      
017LED_POSTCODE_5   VIA   -    M      A18X+127946Y+086449X0260Y         S2      
017LED_POSTCODE_5         -    MD0100PA00X+127946Y+086449                       
317m1393            VIA   -    M      A01X+129106Y+091700X0200Y         S2      
017m1393            VIA   -    M      A18X+129106Y+091700X0260Y         S2      
017m1393                  -    MD0100PA00X+129106Y+091700                       
327m1393            R4386 -1          A01X+128708Y+091950X0198Y0197R180 S1      
327m1393            U336  -4          A01X+129106Y+091333X0160Y0360     S1      
327m1393            R4385 -1   M      A01X+129092Y+091950X0198Y0197     S1      
317m1394            VIA   -    M      A01X+042141Y+035905X0200Y         S2      
017m1394            VIA   -    M      A18X+042141Y+035905X0260Y         S2      
017m1394                  -    MD0100PA00X+042141Y+035905                       
327m1394            R1134 -1          A01X+042448Y+036208X0198Y0197R090 S1      
327m1394            U115  -47         A01X+042141Y+035011X0070Y0340R180 S1      
327m1394            R1131 -2   M      A01X+042042Y+036208X0198Y0197R270 S1      
327MB_I2C_ISO_EN    VIA   -    M      A18X+118144Y+097894X0260Y    R270 S2      
327MB_I2C_ISO_EN    U318  -5          A18X+118795Y+097672X0240Y0460R180 S2      
327MB_I2C_ISO_EN    R4100 -1          A18X+118278Y+097182X0198Y0197R090 S2      
317m1395            VIA   -    M      A01X+132700Y+065750X0200Y         S2      
017m1395            VIA   -    M      A18X+132700Y+065750X0260Y         S2      
017m1395                  -    MD0100PA00X+132700Y+065750                       
327m1395            R4772 -2          A01X+132942Y+065750X0198Y0197R180 S1      
327m1395            R4158 -1          A01X+128792Y+083550X0198Y0197     S1      
317m1395            VIA   -    MD0100PA00X+128550Y+083550X0200Y    R180 S0      
327m1396            PU12  -31         A01X+132505Y+111023X0090Y0240R180 S1      
327m1397            VIA   -    M      A01X+091915Y+089644X0300Y    R090 S1      
327m1397            U5    -R6         A01X+091129Y+088151X0160Y    R180 S1      
327m1397            R4520 -1          A01X+093263Y+090951X0198Y0197R090 S1      
327LED_POSTCODE_2   U324  -6          A01X+129825Y+076376X0160Y0540R270 S1      
317LED_POSTCODE_2   VIA   -    MD0100PA00X+128254Y+076108X0200Y         S0      
327LED_POSTCODE_2   R2980 -1          A01X+127684Y+087949X0198Y0197R180 S1      
317LED_POSTCODE_2   VIA   -    M      A01X+127946Y+087949X0200Y         S2      
017LED_POSTCODE_2   VIA   -    M      A18X+127946Y+087949X0260Y         S2      
017LED_POSTCODE_2         -    MD0100PA00X+127946Y+087949                       
317LED_POSTCODE_2   VIA   -    MD0100PA00X+132320Y+087396X0180Y         S0      
327LED_POSTCODE_2   U6    -J4         A01X+132478Y+087239X0160Y         S1      
327m1398            VIA   -    M      A18X+091420Y+089006X0260Y         S2      
327m1398            R4517 -1          A18X+092329Y+090876X0198Y0197R270 S2      
327m1398            U5    -N6         A01X+091129Y+087521X0160Y    R180 S1      
317m1398            VIA   -    MD0100PA00X+091286Y+087679X0180Y    R270 S0      
317m1399            VIA   -    M      A01X+132700Y+073250X0200Y         S2      
017m1399            VIA   -    M      A18X+132700Y+073250X0260Y         S2      
017m1399                  -    MD0100PA00X+132700Y+073250                       
327m1399            U347  -1          A01X+135098Y+072797X0240Y0540R270 S1      
327m1399            R4748 -1   M      A01X+132942Y+073250X0198Y0197     S1      
327m1399            R4736 -2          A01X+132458Y+073250X0198Y0197     S1      
327LED_POSTCODE_6   U324  -10         A01X+129825Y+075352X0160Y0540R270 S1      
317LED_POSTCODE_6   VIA   -    MD0100PA00X+128254Y+075108X0200Y         S0      
317LED_POSTCODE_6   VIA   -    M      A01X+127946Y+085949X0200Y         S2      
017LED_POSTCODE_6   VIA   -    M      A18X+127946Y+085949X0260Y         S2      
017LED_POSTCODE_6         -    MD0100PA00X+127946Y+085949                       
327LED_POSTCODE_6   R2984 -1          A01X+127684Y+085949X0198Y0197R180 S1      
317LED_POSTCODE_6   VIA   -    MD0100PA00X+133265Y+087081X0180Y         S0      
327LED_POSTCODE_6   U6    -K7         A01X+133423Y+086924X0160Y         S1      
327m1400            VIA   -    M      A01X+092665Y+090077X0300Y    R090 S1      
327m1400            R4515 -1          A01X+094463Y+090951X0198Y0197R090 S1      
327m1400            U5    -T4         A01X+091759Y+088466X0160Y    R180 S1      
317m1401            VIA   -    MD0100PA00X+089887Y+035111X0200Y         S0      
327m1401            R4110 -2          A01X+089146Y+034154X0198Y0197     S1      
317m1401            VIA   -    MD0100PA00X+109384Y+037134X0200Y         S0      
317m1401            VIA   -    MD0100PA00X+148070Y+036852X0200Y         S0      
327m1401            U142  -22         A01X+152850Y+034680X0120Y0630R270 S1      
317m1401            VIA   -    M      A01X+151684Y+034742X0200Y         S2      
017m1401            VIA   -    M      A18X+151684Y+034742X0260Y         S2      
017m1401                  -    MD0100PA00X+151684Y+034742                       
317LED_POSTCODE_4   VIA   -    M      A01X+128254Y+075608X0200Y         S2      
017LED_POSTCODE_4   VIA   -    M      A18X+128254Y+075608X0260Y         S2      
017LED_POSTCODE_4         -    MD0100PA00X+128254Y+075608                       
327LED_POSTCODE_4   U324  -8          A01X+129825Y+075864X0160Y0540R270 S1      
327LED_POSTCODE_4   U6    -J2         A01X+131848Y+087239X0160Y         S1      
327LED_POSTCODE_4   R2982 -1          A01X+127684Y+086949X0198Y0197R180 S1      
317LED_POSTCODE_4   VIA   -    MD0100PA00X+127946Y+086949X0200Y         S0      
327m1402            VIA   -    M      A01X+092165Y+090077X0300Y    R090 S1      
327m1402            R4519 -1          A01X+093663Y+090951X0198Y0197R090 S1      
327m1402            U5    -T5         A01X+091444Y+088466X0160Y    R180 S1      
317m1403            VIA   -    M      A01X+151591Y+035460X0200Y         S2      
017m1403            VIA   -    M      A18X+151591Y+035460X0260Y         S2      
017m1403                  -    MD0100PA00X+151591Y+035460                       
327m1403            R4109 -2          A01X+149309Y+036858X0198Y0197     S1      
327m1403            U142  -23         A01X+152850Y+034936X0120Y0630R270 S1      
317LED_POSTCODE_3   VIA   -    MD0100PA00X+127954Y+075858X0200Y         S0      
327LED_POSTCODE_3   U324  -7          A01X+129825Y+076120X0160Y0540R270 S1      
327LED_POSTCODE_3   R2981 -1          A01X+127684Y+087449X0198Y0197R180 S1      
317LED_POSTCODE_3   VIA   -    M      A01X+127946Y+087449X0200Y         S2      
017LED_POSTCODE_3   VIA   -    M      A18X+127946Y+087449X0260Y         S2      
017LED_POSTCODE_3         -    MD0100PA00X+127946Y+087449                       
327LED_POSTCODE_3   U6    -J3         A01X+132163Y+087239X0160Y         S1      
317LED_POSTCODE_3   VIA   -    MD0100PA00X+132006Y+087396X0180Y         S0      
327m1404            VIA   -    M      A18X+092389Y+088908X0260Y         S2      
327m1404            U5    -L3         A01X+092074Y+086891X0160Y    R180 S1      
317m1404            VIA   -    MD0100PA00X+092231Y+087049X0180Y    R270 S0      
327m1404            R4527 -1          A18X+093529Y+090876X0198Y0197R270 S2      
317m1405            VIA   -    M      A01X+137842Y+061628X0200Y         S2      
017m1405            VIA   -    M      A18X+137842Y+061628X0260Y         S2      
017m1405                  -    MD0100PA00X+137842Y+061628                       
327m1405            U349  -15         A01X+137402Y+061304X0160Y0540R270 S1      
327m1405            R4822 -1          A01X+138517Y+061550X0198Y0197     S1      
317LED_POSTCODE_7   VIA   -    MD0100PA00X+127954Y+074858X0200Y         S0      
317LED_POSTCODE_7   VIA   -    M      A01X+127946Y+085449X0200Y         S2      
017LED_POSTCODE_7   VIA   -    M      A18X+127946Y+085449X0260Y         S2      
017LED_POSTCODE_7         -    MD0100PA00X+127946Y+085449                       
327LED_POSTCODE_7   R2985 -1          A01X+127683Y+085203X0198Y0197R180 S1      
327LED_POSTCODE_7   U324  -11         A01X+129825Y+075096X0160Y0540R270 S1      
317LED_POSTCODE_7   VIA   -    MD0100PA00X+132950Y+087081X0180Y         S0      
327LED_POSTCODE_7   U6    -K6         A01X+133108Y+086924X0160Y         S1      
327m1406            VIA   -    M      A18X+091149Y+089449X0260Y         S2      
327m1406            R4518 -1          A18X+091529Y+090876X0198Y0197R270 S2      
327m1406            U5    -P8         A01X+090499Y+087836X0160Y    R180 S1      
317m1406            VIA   -    MD0100PA00X+090656Y+087994X0180Y    R270 S0      
327m1407            VIA   -    M      A18X+086989Y+084691X0260Y         S2      
327m1407            R5290 -2          A18X+085683Y+084346X0198Y0197R180 S2      
327m1407            U5    -E13        A01X+088924Y+085002X0160Y    R180 S1      
317m1407            VIA   -    MD0100PA00X+088767Y+084844X0180Y    R270 S0      
317m1408            VIA   -    M      A01X+137842Y+061048X0200Y         S2      
017m1408            VIA   -    M      A18X+137842Y+061048X0260Y         S2      
017m1408                  -    MD0100PA00X+137842Y+061048                       
327m1408            U349  -14         A01X+137402Y+061048X0160Y0540R270 S1      
327m1408            R4821 -1          A01X+138517Y+061150X0198Y0197     S1      
317LED_POSTCODE_0   VIA   -    MD0100PA00X+128254Y+076608X0200Y         S0      
327LED_POSTCODE_0   U324  -4          A01X+129825Y+076888X0160Y0540R270 S1      
317LED_POSTCODE_0   VIA   -    M      A01X+127946Y+088949X0200Y         S2      
017LED_POSTCODE_0   VIA   -    M      A18X+127946Y+088949X0260Y         S2      
017LED_POSTCODE_0         -    MD0100PA00X+127946Y+088949                       
327LED_POSTCODE_0   R2978 -1          A01X+127684Y+088949X0198Y0197R180 S1      
317LED_POSTCODE_0   VIA   -    MD0100PA00X+132636Y+087711X0180Y         S0      
327LED_POSTCODE_0   U6    -H5         A01X+132793Y+087554X0160Y         S1      
327m1409            VIA   -    M      A01X+090665Y+090077X0300Y    R090 S1      
327m1409            R4525 -1          A01X+091090Y+090942X0198Y0197R090 S1      
327m1409            U5    -T8         A01X+090499Y+088466X0160Y    R180 S1      
327m1410            VIA   -    M      A01X+093927Y+086892X0300Y         S1      
327m1410            U5    -G1         A01X+092704Y+085632X0160Y    R180 S1      
327m1410            R4855 -2          A01X+094470Y+087822X0198Y0197R180 S1      
327m1410            C3613 -1   M      A01X+094470Y+087427X0164Y0164     S1      
317m1411            VIA   -    M      A01X+086403Y+068897X0200Y         S2      
017m1411            VIA   -    M      A18X+086403Y+068897X0260Y         S2      
017m1411                  -    MD0100PA00X+086403Y+068897                       
327m1411            R5913 -1          A01X+084968Y+068904X0198Y0197R090 S1      
327m1411            U360  -2   M      A01X+085984Y+068897X0220Y0530R270 S1      
317m1411            VIA   -    MD0100PA00X+085118Y+084346X0200Y         S0      
327m1411            R5290 -1          A18X+085368Y+084346X0198Y0197R180 S2      
317m1412            VIA   -    M      A01X+137842Y+065498X0200Y         S2      
017m1412            VIA   -    M      A18X+137842Y+065498X0260Y         S2      
017m1412                  -    MD0100PA00X+137842Y+065498                       
327m1412            R4777 -1          A01X+139142Y+065600X0198Y0197     S1      
327m1412            U348  -14         A01X+137402Y+065498X0160Y0540R270 S1      
317m1413            VIA   -    M      A01X+133553Y+062226X0200Y    R180 S2      
017m1413            VIA   -    M      A18X+133553Y+062226X0260Y    R180 S2      
017m1413                  -    MD0100PA00X+133553Y+062226                       
327m1413            R4814 -1          A01X+133258Y+062100X0198Y0197R180 S1      
327m1413            U349  -6          A01X+135098Y+062328X0160Y0540R270 S1      
327m1414            VIA   -    M      A18X+091777Y+089762X0260Y         S2      
327m1414            R4516 -1          A18X+091929Y+090876X0198Y0197R270 S2      
327m1414            U5    -P7         A01X+090814Y+087836X0160Y    R180 S1      
317m1414            VIA   -    MD0100PA00X+090971Y+087994X0180Y    R270 S0      
317m1415            VIA   -    M      A01X+137842Y+066078X0200Y         S2      
017m1415            VIA   -    M      A18X+137842Y+066078X0260Y         S2      
017m1415                  -    MD0100PA00X+137842Y+066078                       
327m1415            R4778 -1          A01X+139142Y+066000X0198Y0197     S1      
327m1415            U348  -15         A01X+137402Y+065754X0160Y0540R270 S1      
317m1416            VIA   -    M      A01X+134205Y+062584X0200Y    R180 S2      
017m1416            VIA   -    M      A18X+134205Y+062584X0260Y    R180 S2      
017m1416                  -    MD0100PA00X+134205Y+062584                       
327m1416            R4813 -1          A01X+133258Y+062500X0198Y0197R180 S1      
327m1416            U349  -5          A01X+135098Y+062584X0160Y0540R270 S1      
327SSD10_PWR_EN_R   R6831 -1   M      A01X+122074Y+022572X0198Y0197     S1      
327SSD10_PWR_EN_R   PU42  -11         A01X+121396Y+021710X0110Y0240R270 S1      
317SSD10_PWR_EN_R   VIA   -    MD0100PA00X+119966Y+025630X0200Y         S0      
317SSD10_PWR_EN_R   VIA   -    MD0100PA00X+132900Y+080400X0200Y         S0      
327SSD10_PWR_EN_R   R4123 -2          A01X+132900Y+080642X0198Y0197R270 S1      
327SSD10_PWR_EN_R   R6000 -1          A01X+119966Y+025954X0198Y0197R090 S1      
317SSD10_PWR_EN_R   VIA   -    M      A01X+122274Y+022863X0200Y         S2      
017SSD10_PWR_EN_R   VIA   -    M      A18X+122274Y+022863X0260Y         S2      
017SSD10_PWR_EN_R         -    MD0100PA00X+122274Y+022863                       
327SSD10_PWR_EN_R   C2873 -1   M      A01X+122074Y+022186X0198Y0197     S1      
327m1417            D19   -C   M      A01X+125937Y+085949X0240Y0280R180 S1      
327m1417            D18   -C   M      A01X+125937Y+086449X0240Y0280R180 S1      
327m1417            D20   -C          A01X+125937Y+085449X0240Y0280R180 S1      
327m1417            D17   -C   M      A01X+125937Y+086949X0240Y0280R180 S1      
327m1417            D16   -C   M      A01X+125937Y+087449X0240Y0280R180 S1      
327m1417            D15   -C   M      A01X+125937Y+087949X0240Y0280R180 S1      
327m1417            VIA   -    M      A01X+125694Y+089486X0300Y         S1      
327m1417            D14   -C   M      A01X+125937Y+088449X0240Y0280R180 S1      
327m1417            R2988 -2          A01X+126162Y+089844X0198Y0197R270 S1      
327m1417            R2987 -2   M      A01X+126162Y+089487X0198Y0197R180 S1      
327m1417            D13   -C   M      A01X+125937Y+088949X0240Y0280R180 S1      
327m1418            VIA   -    M      A01X+090915Y+089644X0300Y    R090 S1      
327m1418            U5    -R8         A01X+090499Y+088151X0160Y    R180 S1      
327m1418            R4524 -1          A01X+091450Y+090942X0198Y0197R090 S1      
327m1419            R4793 -2          A01X+132458Y+062100X0198Y0197     S1      
327m1419            R4814 -2          A01X+132942Y+062100X0198Y0197R180 S1      
317m1419            VIA   -    MD0100PA00X+132700Y+062100X0200Y         S0      
317m1419            VIA   -    M      A01X+134468Y+061908X0200Y         S2      
017m1419            VIA   -    M      A18X+134468Y+061908X0260Y         S2      
017m1419                  -    MD0100PA00X+134468Y+061908                       
327m1419            U6    -Y1         A01X+131533Y+083774X0160Y         S1      
317m1419            VIA   -    MD0100PA00X+131376Y+083617X0180Y         S0      
327SSD12_PWR_EN_R   R6829 -1   M      A01X+147310Y+022572X0198Y0197     S1      
327SSD12_PWR_EN_R   PU39  -11         A01X+146633Y+021710X0110Y0240R270 S1      
317SSD12_PWR_EN_R   VIA   -    MD0100PA00X+145203Y+025630X0200Y         S0      
327SSD12_PWR_EN_R   R6010 -1          A01X+145203Y+025954X0198Y0197R090 S1      
327SSD12_PWR_EN_R   C2870 -1   M      A01X+147310Y+022186X0198Y0197     S1      
317SSD12_PWR_EN_R   VIA   -    M      A01X+147510Y+022863X0200Y         S2      
017SSD12_PWR_EN_R   VIA   -    M      A18X+147510Y+022863X0260Y         S2      
017SSD12_PWR_EN_R         -    MD0100PA00X+147510Y+022863                       
317SSD12_PWR_EN_R   VIA   -    MD0100PA00X+132700Y+081162X0200Y         S0      
327SSD12_PWR_EN_R   R4131 -2          A18X+132850Y+081642X0198Y0197R090 S2      
317SSD12_PWR_EN_R   VIA   -    MD0100PA00X+137536Y+043223X0200Y         S0      
317SSD12_PWR_EN_R   VIA   -    MD0100PA00X+143542Y+043036X0200Y         S0      
327m1420            VIA   -    M      A01X+126846Y+085949X0300Y         S1      
327m1420            D19   -A          A01X+126311Y+085949X0240Y0280R180 S1      
327m1420            R2984 -2          A01X+127369Y+085949X0198Y0197R180 S1      
327m1421            VIA   -    M      A01X+091665Y+090077X0300Y    R090 S1      
327m1421            U5    -T6         A01X+091129Y+088466X0160Y    R180 S1      
327m1421            R4521 -1          A01X+092863Y+090951X0198Y0197R090 S1      
317m1422            VIA   -    MD0100PA00X+131376Y+083302X0180Y         S0      
327m1422            U6    -AA1        A01X+131533Y+083460X0160Y         S1      
327m1422            R4800 -1          A01X+132458Y+062900X0198Y0197R180 S1      
327m1422            R4787 -2   M      A01X+132458Y+062500X0198Y0197     S1      
327m1422            R4813 -2          A01X+132942Y+062500X0198Y0197R180 S1      
317m1422            VIA   -    M      A01X+132700Y+062394X0200Y         S2      
017m1422            VIA   -    M      A18X+132700Y+062394X0260Y         S2      
017m1422                  -    MD0100PA00X+132700Y+062394                       
317m1422            VIA   -    MD0100PA00X+134638Y+062373X0200Y         S0      
327SSD14_PWR_EN_R   R6827 -1   M      A01X+167782Y+022572X0198Y0197     S1      
327SSD14_PWR_EN_R   PU43  -11         A01X+167105Y+021710X0110Y0240R270 S1      
317SSD14_PWR_EN_R   VIA   -    MD0100PA00X+165675Y+025630X0200Y         S0      
327SSD14_PWR_EN_R   R6020 -1          A01X+165675Y+025954X0198Y0197R090 S1      
327SSD14_PWR_EN_R   C2874 -1   M      A01X+167783Y+022186X0198Y0197     S1      
317SSD14_PWR_EN_R   VIA   -    M      A01X+167982Y+022863X0200Y         S2      
017SSD14_PWR_EN_R   VIA   -    M      A18X+167982Y+022863X0260Y         S2      
017SSD14_PWR_EN_R         -    MD0100PA00X+167982Y+022863                       
317SSD14_PWR_EN_R   VIA   -    MD0100PA00X+163834Y+037954X0200Y         S0      
327SSD14_PWR_EN_R   R4139 -2          A01X+135300Y+080642X0198Y0197R270 S1      
317SSD14_PWR_EN_R   VIA   -    MD0100PA00X+135300Y+080400X0200Y         S0      
317SSD14_PWR_EN_R   VIA   -    MD0100PA00X+141561Y+041764X0200Y         S0      
327m1423            R2981 -2          A01X+127369Y+087449X0198Y0197R180 S1      
327m1423            D16   -A          A01X+126311Y+087449X0240Y0280R180 S1      
327m1423            VIA   -    M      A01X+126846Y+087449X0300Y         S1      
327m1424            VIA   -    M      A01X+091165Y+090077X0300Y    R090 S1      
327m1424            R4523 -1          A01X+091810Y+090942X0198Y0197R090 S1      
327m1424            U5    -T7         A01X+090814Y+088466X0160Y    R180 S1      
327SSD15_PWR_EN_R   R6826 -1   M      A01X+178018Y+022572X0198Y0197     S1      
327SSD15_PWR_EN_R   PU45  -11         A01X+177341Y+021710X0110Y0240R270 S1      
317SSD15_PWR_EN_R   VIA   -    MD0100PA00X+175911Y+025630X0200Y         S0      
327SSD15_PWR_EN_R   R6021 -1          A01X+175911Y+025954X0198Y0197R090 S1      
327SSD15_PWR_EN_R   C2876 -1   M      A01X+178019Y+022186X0198Y0197     S1      
317SSD15_PWR_EN_R   VIA   -    M      A01X+178219Y+022863X0200Y         S2      
017SSD15_PWR_EN_R   VIA   -    M      A18X+178219Y+022863X0260Y         S2      
017SSD15_PWR_EN_R         -    MD0100PA00X+178219Y+022863                       
327SSD15_PWR_EN_R   R4143 -1          A01X+134500Y+079042X0198Y0197R090 S1      
317SSD15_PWR_EN_R   VIA   -    MD0100PA00X+134500Y+078800X0200Y         S0      
317SSD15_PWR_EN_R   VIA   -    MD0100PA00X+141437Y+039806X0200Y         S0      
317SSD15_PWR_EN_R   VIA   -    MD0100PA00X+166365Y+035328X0200Y         S0      
327m1425            VIA   -    M      A01X+126846Y+085449X0300Y         S1      
327m1425            D20   -A          A01X+126311Y+085449X0240Y0280R180 S1      
327m1425            R2985 -2          A01X+127368Y+085203X0198Y0197R180 S1      
327m1426            VIA   -    M      A01X+091415Y+089644X0300Y    R090 S1      
327m1426            U5    -R7         A01X+090814Y+088151X0160Y    R180 S1      
327m1426            R4522 -1          A01X+092463Y+090951X0198Y0197R090 S1      
327SSD8_PWR_EN_R    R6833 -1   M      A01X+101601Y+022572X0198Y0197     S1      
327SSD8_PWR_EN_R    PU38  -11         A01X+100924Y+021710X0110Y0240R270 S1      
327SSD8_PWR_EN_R    C2869 -1   M      A01X+101602Y+022186X0198Y0197     S1      
317SSD8_PWR_EN_R    VIA   -    M      A01X+101801Y+022863X0200Y         S2      
017SSD8_PWR_EN_R    VIA   -    M      A18X+101801Y+022863X0260Y         S2      
017SSD8_PWR_EN_R          -    MD0100PA00X+101801Y+022863                       
317SSD8_PWR_EN_R    VIA   -    MD0100PA00X+099494Y+025630X0200Y         S0      
327SSD8_PWR_EN_R    R5990 -1          A01X+099494Y+025954X0198Y0197R090 S1      
317SSD8_PWR_EN_R    VIA   -    MD0100PA00X+122576Y+036939X0200Y         S0      
317SSD8_PWR_EN_R    VIA   -    MD0100PA00X+131300Y+078800X0200Y         S0      
327SSD8_PWR_EN_R    R4115 -2          A01X+131300Y+079042X0198Y0197R270 S1      
317SSD8_PWR_EN_R    VIA   -    MD0100PA00X+108279Y+034850X0200Y         S0      
327m1427            VIA   -    M      A01X+126846Y+086449X0300Y         S1      
327m1427            D18   -A          A01X+126311Y+086449X0240Y0280R180 S1      
327m1427            R2983 -2          A01X+127369Y+086449X0198Y0197R180 S1      
327m1428            VIA   -    M      A18X+092248Y+089458X0260Y         S2      
327m1428            U5    -L4         A01X+091759Y+086891X0160Y    R180 S1      
317m1428            VIA   -    MD0100PA00X+091916Y+087049X0180Y    R270 S0      
327m1428            R4528 -1          A18X+092729Y+090876X0198Y0197R270 S2      
327SSD11_PWR_EN_R   R6830 -1   M      A01X+132310Y+022572X0198Y0197     S1      
327SSD11_PWR_EN_R   PU44  -11         A01X+131633Y+021710X0110Y0240R270 S1      
317SSD11_PWR_EN_R   VIA   -    MD0100PA00X+130202Y+025630X0200Y         S0      
327SSD11_PWR_EN_R   R6001 -1          A01X+130202Y+025954X0198Y0197R090 S1      
327SSD11_PWR_EN_R   C2875 -1   M      A01X+132310Y+022186X0198Y0197     S1      
317SSD11_PWR_EN_R   VIA   -    M      A01X+132510Y+022863X0200Y         S2      
017SSD11_PWR_EN_R   VIA   -    M      A18X+132510Y+022863X0260Y         S2      
017SSD11_PWR_EN_R         -    MD0100PA00X+132510Y+022863                       
317SSD11_PWR_EN_R   VIA   -    MD0100PA00X+137223Y+036130X0200Y         S0      
317SSD11_PWR_EN_R   VIA   -    MD0100PA00X+140469Y+036221X0200Y         S0      
317SSD11_PWR_EN_R   VIA   -    MD0100PA00X+134100Y+078800X0200Y         S0      
327SSD11_PWR_EN_R   R4127 -2          A01X+134100Y+079042X0198Y0197R270 S1      
317FPGA_HEARTBEAT   VIA   -    M      A01X+127930Y+089881X0200Y         S2      
017FPGA_HEARTBEAT   VIA   -    M      A18X+127930Y+089881X0260Y         S2      
017FPGA_HEARTBEAT         -    MD0100PA00X+127930Y+089881                       
327FPGA_HEARTBEAT   R3006 -2          A01X+128004Y+090207X0198Y0197R270 S1      
327FPGA_HEARTBEAT   D21   -A          A01X+127700Y+089565X0240Y0280R180 S1      
327m1429            VIA   -    M      A18X+093160Y+090070X0260Y         S2      
327m1429            U5    -M4         A01X+091759Y+087206X0160Y    R180 S1      
317m1429            VIA   -    MD0100PA00X+091916Y+087364X0180Y    R270 S0      
327m1429            R4529 -1          A18X+093129Y+090876X0198Y0197R270 S2      
327m1430            VIA   -           A18X+093371Y+086080X0260Y         S2      
327m1430            C3612 -1          A18X+094512Y+086067X0164Y0164R180 S2      
327m1430            R4854 -2          A18X+094199Y+085721X0198Y0197R270 S2      
327m1430            U5    -F2         A01X+092389Y+085317X0160Y    R180 S1      
317m1430            VIA   -    MD0100PA00X+092546Y+085159X0180Y    R270 S0      
317m1430            VIA   -    MD0100PA00X+093755Y+086080X0200Y         S0      
317m1430            VIA   -    MD0100PA00X+093645Y+085833X0200Y         S0      
327SSD13_PWR_EN_R   R6828 -1   M      A01X+157546Y+022572X0198Y0197     S1      
327SSD13_PWR_EN_R   PU41  -11         A01X+156869Y+021710X0110Y0240R270 S1      
317SSD13_PWR_EN_R   VIA   -    MD0100PA00X+155439Y+025630X0200Y         S0      
327SSD13_PWR_EN_R   R6011 -1          A01X+155439Y+025954X0198Y0197R090 S1      
327SSD13_PWR_EN_R   C2872 -1   M      A01X+157546Y+022186X0198Y0197     S1      
317SSD13_PWR_EN_R   VIA   -    M      A01X+157746Y+022863X0200Y         S2      
017SSD13_PWR_EN_R   VIA   -    M      A18X+157746Y+022863X0260Y         S2      
017SSD13_PWR_EN_R         -    MD0100PA00X+157746Y+022863                       
317SSD13_PWR_EN_R   VIA   -    MD0100PA00X+133100Y+081162X0200Y         S0      
327SSD13_PWR_EN_R   R4135 -2          A18X+133300Y+081642X0198Y0197R090 S2      
317SSD13_PWR_EN_R   VIA   -    MD0100PA00X+147138Y+043312X0200Y         S0      
317SSD13_PWR_EN_R   VIA   -    MD0100PA00X+137540Y+043519X0200Y         S0      
327m1431            VIA   -    M      A01X+126846Y+088449X0300Y         S1      
327m1431            D14   -A          A01X+126311Y+088449X0240Y0280R180 S1      
327m1431            R2979 -2          A01X+127369Y+088449X0198Y0197R180 S1      
327m1432            VIA   -    M      A01X+093931Y+087902X0300Y         S1      
327m1432            U5    -K1         A01X+092704Y+086576X0160Y    R180 S1      
327m1432            R4526 -1          A01X+094449Y+088315X0198Y0197     S1      
317m1433            VIA   -    M      A01X+134653Y+057678X0200Y    R180 S2      
017m1433            VIA   -    M      A18X+134653Y+057678X0260Y    R180 S2      
017m1433                  -    MD0100PA00X+134653Y+057678                       
327m1433            R4833 -1          A01X+133258Y+057450X0198Y0197R180 S1      
327m1433            U350  -6          A01X+135098Y+057678X0160Y0540R270 S1      
327SSD9_PWR_EN_R    R6832 -1   M      A01X+111837Y+022572X0198Y0197     S1      
327SSD9_PWR_EN_R    PU40  -11         A01X+111160Y+021710X0110Y0240R270 S1      
317SSD9_PWR_EN_R    VIA   -    MD0100PA00X+109730Y+025630X0200Y         S0      
327SSD9_PWR_EN_R    R5991 -1          A01X+109730Y+025954X0198Y0197R090 S1      
327SSD9_PWR_EN_R    C2871 -1   M      A01X+111838Y+022186X0198Y0197     S1      
317SSD9_PWR_EN_R    VIA   -    M      A01X+112038Y+022863X0200Y         S2      
017SSD9_PWR_EN_R    VIA   -    M      A18X+112038Y+022863X0260Y         S2      
017SSD9_PWR_EN_R          -    MD0100PA00X+112038Y+022863                       
317SSD9_PWR_EN_R    VIA   -    MD0100PA00X+117493Y+031917X0200Y         S0      
317SSD9_PWR_EN_R    VIA   -    MD0100PA00X+122992Y+032455X0200Y         S0      
317SSD9_PWR_EN_R    VIA   -    MD0100PA00X+131700Y+078800X0200Y         S0      
327SSD9_PWR_EN_R    R4119 -2          A01X+131700Y+079042X0198Y0197R270 S1      
327m1434            R3310 -1          A01X+161454Y+062079X0198Y0197R090 S1      
317m1434            VIA   -    MD0100PA00X+161454Y+061829X0200Y    R180 S0      
327m1434            R3311 -1          A01X+162136Y+065382X0198Y0197R270 S1      
317m1434            VIA   -    MD0100PA00X+162136Y+065632X0200Y         S0      
327m1434            R3309 -1          A01X+116428Y+065382X0198Y0197R270 S1      
327m1434            R4170 -2          A18X+129642Y+087980X0198Y0197     S2      
317m1434            VIA   -    MD0100PA00X+129350Y+087980X0200Y         S0      
317m1434            VIA   -    MD0100PA00X+115989Y+086911X0200Y         S0      
317m1434            VIA   -    MD0100PA00X+116428Y+065632X0200Y         S0      
317m1434            VIA   -    MD0100PA00X+161132Y+068580X0200Y         S0      
327m1434            R5890 -2          A18X+084677Y+082742X0198Y0197     S2      
317m1434            VIA   -    MD0100PA00X+083689Y+082440X0200Y         S0      
327m1434            R3306 -1          A01X+070036Y+062079X0198Y0197R090 S1      
327m1434            R3307 -1          A01X+070719Y+065382X0198Y0197R270 S1      
317m1434            VIA   -    MD0100PA00X+071133Y+065382X0200Y         S0      
317m1434            VIA   -    MD0100PA00X+100580Y+063760X0200Y         S0      
317m1434            VIA   -    MD0100PA00X+082950Y+067679X0200Y         S0      
317m1434            VIA   -    MD0100PA00X+115745Y+061829X0200Y    R180 S0      
327m1434            R3308 -1          A01X+115745Y+062079X0198Y0197R090 S1      
317m1434            VIA   -    MD0100PA00X+055148Y+066150X0200Y         S0      
317m1434            VIA   -    M      A01X+025010Y+065632X0200Y         S2      
017m1434            VIA   -    M      A18X+025010Y+065632X0260Y         S2      
017m1434                  -    MD0100PA00X+025010Y+065632                       
327m1434            R3305 -1          A01X+025010Y+065382X0198Y0197R270 S1      
327m1434            R3304 -1          A01X+024328Y+062079X0198Y0197R090 S1      
317m1434            VIA   -    MD0100PA00X+024328Y+061829X0200Y         S0      
327m1435            VIA   -    M      A01X+126846Y+086949X0300Y         S1      
327m1435            D17   -A          A01X+126311Y+086949X0240Y0280R180 S1      
327m1435            R2982 -2          A01X+127369Y+086949X0198Y0197R180 S1      
327m1436            VIA   -    M      A01X+092415Y+089644X0300Y    R090 S1      
327m1436            R4514 -1          A01X+094063Y+090951X0198Y0197R090 S1      
327m1436            U5    -R5         A01X+091444Y+088151X0160Y    R180 S1      
317m1437            VIA   -    M      A01X+092364Y+056158X0200Y         S2      
017m1437            VIA   -    M      A18X+092364Y+056158X0260Y         S2      
017m1437                  -    MD0100PA00X+092364Y+056158                       
327m1437            R4195 -1          A01X+092608Y+055764X0198Y0197     S1      
327m1437            U117  -A16        A01X+091524Y+056847X0070Y0220R090 S1      
327m1437            R4208 -2   M      A01X+092608Y+056158X0198Y0197R180 S1      
327m1438            PEX1  -AV29       A01X+070689Y+111634X0180Y         S1      
317m1438            VIA   -    MD0080PA00X+070876Y+111821X0160Y         S0      
317m1438            VIA   -    MD0100PA00X+141797Y+072089X0200Y         S0      
327m1438            R4680 -1          A01X+141554Y+072089X0198Y0197R180 S1      
317m1438            VIA   -    MD0100PA00X+057598Y+073252X0200Y         S0      
317m1438            VIA   -    M      A01X+061292Y+099786X0200Y         S2      
017m1438            VIA   -    M      A18X+061292Y+099786X0260Y         S2      
017m1438                  -    MD0100PA00X+061292Y+099786                       
327m1438            R3961 -1          A01X+061292Y+099511X0198Y0197R270 S1      
327m1439            VIA   -    M      A01X+126846Y+088949X0300Y         S1      
327m1439            D13   -A          A01X+126311Y+088949X0240Y0280R180 S1      
327m1439            R2978 -2          A01X+127369Y+088949X0198Y0197R180 S1      
317m1440            VIA   -    M      A01X+141000Y+071700X0200Y         S2      
017m1440            VIA   -    M      A18X+141000Y+071700X0260Y         S2      
017m1440                  -    MD0100PA00X+141000Y+071700                       
327m1440            R4680 -2          A01X+141239Y+072089X0198Y0197R180 S1      
327m1440            R4681 -1   M      A01X+141242Y+071700X0198Y0197     S1      
317m1440            VIA   -    MD0100PA00X+142700Y+080250X0200Y         S0      
327m1440            R4673 -1          A01X+142942Y+080250X0198Y0197     S1      
327m1441            VIA   -           A18X+128850Y+090412X0260Y         S2      
317m1441            VIA   -    MD0100PA00X+128850Y+090125X0200Y         S0      
327m1441            R6177 -2   M      A01X+128466Y+089808X0198Y0197R090 S1      
327m1441            U336  -2          A01X+128850Y+090467X0160Y0360     S1      
327m1441            R4169 -2          A01X+129200Y+089808X0198Y0197R090 S1      
327m1441            R4384 -1   M      A01X+128816Y+089808X0198Y0197R270 S1      
327m1442            U118  -26         A18X+041364Y+131467X0100Y0220R180 S2      
317m1442            VIA   -    MD0100PA00X+041313Y+131801X0200Y         S0      
327m1442            VIA   -           A18X+041266Y+132146X0260Y         S2      
327m1442            U118  -24         A18X+040921Y+131221X0100Y0220R270 S2      
327m1442            R4228 -1   M      A18X+040458Y+131344X0198Y0197     S2      
317m1442            VIA   -    MD0100PA00X+040458Y+131613X0200Y         S0      
327m1442            U118  -15         A18X+041364Y+129597X0100Y0220     S2      
317m1442            VIA   -    MD0100PA00X+041364Y+129286X0200Y         S0      
317m1442            VIA   -    MD0100PA00X+040368Y+129543X0200Y         S0      
327m1442            U118  -18         A18X+040921Y+130040X0100Y0220R270 S2      
327m1442            R4227 -1   M      A18X+040321Y+129796X0198Y0197     S2      
317m1443            VIA   -    M      A01X+141800Y+071700X0200Y         S2      
017m1443            VIA   -    M      A18X+141800Y+071700X0260Y         S2      
017m1443                  -    MD0100PA00X+141800Y+071700                       
327m1443            R4681 -2          A01X+141558Y+071700X0198Y0197     S1      
327m1443            U346  -1          A01X+144198Y+071247X0240Y0540R270 S1      
327m1443            R4703 -1   M      A01X+142042Y+071700X0198Y0197     S1      
327m1444            R2980 -2          A01X+127369Y+087949X0198Y0197R180 S1      
327m1444            D15   -A          A01X+126311Y+087949X0240Y0280R180 S1      
327m1444            VIA   -    M      A01X+126846Y+087949X0300Y         S1      
327m1445            R4642 -2          A01X+142042Y+074900X0198Y0197R180 S1      
317m1445            VIA   -    M      A01X+140748Y+075085X0200Y         S2      
017m1445            VIA   -    M      A18X+140748Y+075085X0260Y         S2      
017m1445                  -    MD0100PA00X+140748Y+075085                       
317m1445            VIA   -    MD0100PA00X+136900Y+080400X0200Y         S0      
327m1445            R4149 -1          A01X+136900Y+080642X0198Y0197R090 S1      
327FM_CLK_EN_R      U424  -1          A18X+041512Y+137555X0100Y0220     S2      
317FM_CLK_EN_R      VIA   -    MD0100PA00X+041603Y+137157X0200Y    R270 S0      
317FM_CLK_EN_R      VIA   -    M      A01X+041101Y+035674X0200Y         S2      
017FM_CLK_EN_R      VIA   -    M      A18X+041101Y+035674X0260Y         S2      
017FM_CLK_EN_R            -    MD0100PA00X+041101Y+035674                       
327FM_CLK_EN_R      U115  -1          A01X+041689Y+034716X0070Y0340R270 S1      
317FM_CLK_EN_R      VIA   -    MD0100PA00X+043442Y+128627X0200Y         S0      
327FM_CLK_EN_R      U118  -1          A18X+042791Y+131221X0100Y0220R090 S2      
317FM_CLK_EN_R      VIA   -    MD0100PA00X+043188Y+131312X0200Y         S0      
317FM_CLK_EN_R      VIA   -    MD0100PA00X+110878Y+032770X0200Y         S0      
327FM_CLK_EN_R      R4168 -2          A01X+128792Y+088578X0198Y0197R180 S1      
317FM_CLK_EN_R      VIA   -    MD0100PA00X+128530Y+088578X0200Y    R180 S0      
317FM_CLK_EN_R      VIA   -    MD0100PA00X+129408Y+034982X0200Y         S0      
327FM_CLK_EN_R      U116  -1          A01X+131947Y+035025X0070Y0340R270 S1      
317FM_CLK_EN_R      VIA   -    MD0100PA00X+125999Y+034069X0200Y         S0      
317FM_CLK_EN_R      VIA   -    MD0100PA00X+097183Y+043019X0200Y         S0      
317FM_CLK_EN_R      VIA   -    MD0100PA00X+099139Y+040923X0200Y         S0      
327FM_CLK_EN_R      R1065 -2          A01X+100864Y+030583X0198Y0197R090 S1      
327FM_CLK_EN_R      R1055 -1   M      A01X+101264Y+030583X0198Y0197R270 S1      
327FM_CLK_EN_R      U113  -A17        A01X+101349Y+031666X0070Y0220     S1      
317FM_CLK_EN_R      VIA   -    MD0100PA00X+101050Y+030906X0200Y         S0      
317FM_CLK_EN_R      VIA   -    MD0100PA00X+052154Y+068632X0200Y         S0      
327FM_CLK_EN_R      R4205 -2          A01X+092608Y+056558X0198Y0197R180 S1      
327FM_CLK_EN_R      R4194 -1   M      A01X+092608Y+056958X0198Y0197     S1      
327FM_CLK_EN_R      U117  -A17        A01X+091524Y+057044X0070Y0220R090 S1      
317FM_CLK_EN_R      VIA   -    MD0100PA00X+092345Y+056958X0200Y         S0      
317FM_CLK_EN_R      VIA   -    MD0100PA00X+092009Y+066671X0200Y         S0      
317FM_CLK_EN_R      VIA   -    MD0100PA00X+092263Y+063377X0200Y         S0      
327FM_CLK_EN_R      U114  -M6         A01X+052154Y+068858X0090Y         S1      
317m1446            VIA   -    MD0080PA00X+119577Y+120049X0160Y         S0      
327m1446            R6397 -2          A01X+125093Y+113713X0198Y0197R270 S1      
327m1446            PEX2  -T38        A01X+119764Y+119862X0180Y         S1      
317m1446            VIA   -    M      A01X+124936Y+116606X0200Y         S2      
017m1446            VIA   -    M      A18X+124936Y+116606X0260Y         S2      
017m1446                  -    MD0100PA00X+124936Y+116606                       
327m1447            R4196 -1          A01X+089193Y+061259X0198Y0197R090 S1      
327m1447            U117  -B27        A01X+090196Y+059160X0110Y0180     S1      
327m1447            R4209 -2   M      A01X+089593Y+061259X0198Y0197R270 S1      
317m1447            VIA   -    M      A01X+089593Y+060970X0200Y         S2      
017m1447            VIA   -    M      A18X+089593Y+060970X0260Y         S2      
017m1447                  -    MD0100PA00X+089593Y+060970                       
327m1447            U117  -A29        A01X+091278Y+059455X0070Y0220     S1      
327m1447            U117  -A30        A01X+091082Y+059455X0070Y0220     S1      
317m1447            VIA   -    MD0100PA00X+091400Y+059710X0200Y         S0      
317m1447            VIA   -    MD0100PA00X+092122Y+058922X0200Y         S0      
327m1447            U117  -A26        A01X+091524Y+058815X0070Y0220R090 S1      
317m1448            VIA   -    M      A01X+143500Y+080250X0200Y         S2      
017m1448            VIA   -    M      A18X+143500Y+080250X0260Y         S2      
017m1448                  -    MD0100PA00X+143500Y+080250                       
327m1448            U345  -1          A01X+145898Y+079797X0240Y0540R270 S1      
327m1448            R4673 -2          A01X+143258Y+080250X0198Y0197     S1      
327m1448            R4685 -1   M      A01X+143742Y+080250X0198Y0197     S1      
317m1449            VIA   -    M      A01X+140425Y+073586X0200Y         S2      
017m1449            VIA   -    M      A18X+140425Y+073586X0260Y         S2      
017m1449                  -    MD0100PA00X+140425Y+073586                       
317m1449            VIA   -    MD0100PA00X+141800Y+073300X0200Y         S0      
327m1449            R4646 -2          A01X+142042Y+073300X0198Y0197R180 S1      
317m1449            VIA   -    MD0100PA00X+136300Y+081162X0200Y         S0      
327m1449            R4150 -1          A18X+136450Y+081642X0198Y0197R270 S2      
317m1450            VIA   -    MD0080PA00X+165285Y+120049X0160Y         S0      
327m1450            PEX3  -T38        A01X+165472Y+119862X0180Y         S1      
317m1450            VIA   -    M      A01X+170645Y+117306X0200Y         S2      
017m1450            VIA   -    M      A18X+170645Y+117306X0260Y         S2      
017m1450                  -    MD0100PA00X+170645Y+117306                       
327m1450            R6401 -2          A01X+170802Y+113713X0198Y0197R270 S1      
317m1451            VIA   -    MD0100PA00X+095115Y+073011X0200Y         S0      
327m1451            U6    -M7         A01X+133423Y+086294X0160Y         S1      
317m1451            VIA   -    MD0100PA00X+133265Y+086137X0180Y         S0      
317m1451            VIA   -    MD0100PA00X+089782Y+099441X0200Y         S0      
327m1451            U5    -F14        A01X+088609Y+085317X0160Y    R180 S1      
317m1451            VIA   -    MD0100PA00X+088452Y+085159X0180Y    R270 S0      
317m1451            VIA   -    M      A01X+093075Y+131056X0200Y         S2      
017m1451            VIA   -    M      A18X+093075Y+131056X0260Y         S2      
017m1451                  -    MD0100PA00X+093075Y+131056                       
317m1451            VIA   -    MD0100PA00X+092719Y+136155X0200Y         S0      
327m1451            R499  -2          A01X+076345Y+161377X0198Y0197R270 S1      
327m1451            R500  -1   M      A01X+076745Y+161692X0198Y0197R270 S1      
317m1451            VIA   -    MD0100PA00X+077138Y+161692X0200Y         S0      
327HP_NIC4_EN       PU47  -11         A01X+096233Y+048974X0110Y0240R090 S1      
317HP_NIC4_EN       VIA   -    MD0100PA00X+097640Y+047304X0200Y    R180 S0      
317HP_NIC4_EN       VIA   -    MD0100PA00X+097886Y+064218X0200Y         S0      
327HP_NIC4_EN       R952  -1          A01X+097886Y+063939X0198Y0197R270 S1      
317HP_NIC4_EN       VIA   -    MD0100PA00X+093999Y+052773X0200Y    R180 S0      
327HP_NIC4_EN       R4445 -1          A01X+094257Y+052773X0198Y0197     S1      
327HP_NIC4_EN       C2878 -1          A01X+095555Y+047898X0198Y0197R180 S1      
317HP_NIC4_EN       VIA   -    M      A01X+095874Y+048216X0200Y    R180 S2      
017HP_NIC4_EN       VIA   -    M      A18X+095874Y+048216X0260Y    R180 S2      
017HP_NIC4_EN             -    MD0100PA00X+095874Y+048216                       
327HP_NIC4_EN       U29   -D          A01X+105101Y+045941X0400Y0560     S1      
327HP_NIC4_EN       R248  -2   M      A01X+106057Y+045538X0198Y0197R090 S1      
317HP_NIC4_EN       VIA   -    MD0100PA00X+106311Y+045592X0200Y         S0      
327HP_NIC4_EN       R6030 -1          A01X+097640Y+047063X0198Y0197R270 S1      
317m1452            VIA   -    M      A01X+135500Y+081162X0200Y         S2      
017m1452            VIA   -    M      A18X+135500Y+081162X0260Y         S2      
017m1452                  -    MD0100PA00X+135500Y+081162                       
327m1452            R4147 -1          A18X+135550Y+081642X0198Y0197R270 S2      
327m1452            R4623 -2          A01X+143742Y+083450X0198Y0197R180 S1      
317m1452            VIA   -    MD0100PA00X+143500Y+083450X0200Y         S0      
327PWR_EN_PEX_R     R827  -1          A01X+051217Y+100477X0198Y0197R180 S1      
327PWR_EN_PEX_R     R830  -1          A01X+051217Y+103077X0198Y0197R180 S1      
327PWR_EN_PEX_R     R835  -1   M      A01X+142634Y+100477X0198Y0197R180 S1      
327PWR_EN_PEX_R     R838  -1   M      A01X+142634Y+103077X0198Y0197R180 S1      
327PWR_EN_PEX_R     R6578 -1          A01X+101799Y+095882X0198Y0197R180 S1      
327PWR_EN_PEX_R     R6584 -1          A01X+179264Y+098966X0198Y0197R180 S1      
327PWR_EN_PEX_R     R6570 -1          A01X+005932Y+084772X0198Y0197R180 S1      
327PWR_EN_PEX_R     R6572 -1          A01X+057638Y+096181X0198Y0197R180 S1      
317PWR_EN_PEX_R     VIA   -    MD0100PA00X+120180Y+101943X0200Y         S0      
317PWR_EN_PEX_R     VIA   -    MD0100PA00X+038268Y+087015X0200Y    R180 S0      
317PWR_EN_PEX_R     VIA   -    MD0100PA00X+051484Y+103077X0200Y         S0      
317PWR_EN_PEX_R     VIA   -    MD0100PA00X+051469Y+100477X0200Y         S0      
317PWR_EN_PEX_R     VIA   -    MD0100PA00X+050314Y+095793X0200Y         S0      
327PWR_EN_PEX_R     R844  -2          A01X+089818Y+122271X0198Y0197     S1      
327PWR_EN_PEX_R     R846  -2          A01X+096215Y+122271X0198Y0197     S1      
317PWR_EN_PEX_R     VIA   -    MD0100PA00X+090908Y+123272X0200Y         S0      
317PWR_EN_PEX_R     VIA   -    MD0100PA00X+091269Y+099435X0200Y         S0      
327PWR_EN_PEX_R     R850  -2          A01X+039274Y+086441X0198Y0197     S1      
327PWR_EN_PEX_R     R851  -1          A01X+039878Y+086829X0198Y0197     S1      
327PWR_EN_PEX_R     C838  -1   M      A01X+039277Y+086829X0198Y0197R180 S1      
317PWR_EN_PEX_R     VIA   -    MD0100PA00X+004726Y+091965X0200Y         S0      
327PWR_EN_PEX_R     R842  -2          A01X+005449Y+121371X0198Y0197     S1      
327PWR_EN_PEX_R     R3067 -1          A01X+144346Y+103749X0198Y0197R270 S1      
327PWR_EN_PEX_R     R3059 -1   M      A01X+143252Y+100152X0198Y0197     S1      
317PWR_EN_PEX_R     VIA   -    M      A01X+141945Y+097719X0200Y         S2      
017PWR_EN_PEX_R     VIA   -    M      A18X+141945Y+097719X0260Y         S2      
017PWR_EN_PEX_R           -    MD0100PA00X+141945Y+097719                       
317PWR_EN_PEX_R     VIA   -    MD0100PA00X+006555Y+085072X0200Y         S0      
317PWR_EN_PEX_R     VIA   -    MD0100PA00X+053047Y+096173X0200Y         S0      
327PWR_EN_PEX_R     R848  -2          A01X+180613Y+122320X0198Y0197     S1      
317PWR_EN_PEX_R     VIA   -    MD0100PA00X+181148Y+122642X0200Y         S0      
317PWR_EN_PEX_R     VIA   -    MD0100PA00X+177914Y+099520X0200Y         S0      
317m1453            VIA   -    MD0080PA00X+165659Y+120423X0160Y         S0      
327m1453            PEX3  -P39        A01X+165846Y+120610X0180Y         S1      
317m1453            VIA   -    M      A01X+171324Y+117604X0200Y         S2      
017m1453            VIA   -    M      A18X+171324Y+117604X0260Y         S2      
017m1453                  -    MD0100PA00X+171324Y+117604                       
327m1453            R6400 -2          A01X+171673Y+118505X0198Y0197R090 S1      
317m1454            VIA   -    MD0100PA00X+165704Y+077360X0200Y         S0      
317m1454            VIA   -    MD0100PA00X+172501Y+113464X0200Y         S0      
327m1454            R4002 -1          A01X+172501Y+113713X0198Y0197R090 S1      
317m1454            VIA   -    MD0100PA00X+175386Y+099727X0200Y         S0      
327m1454            U349  -23         A01X+137402Y+063352X0160Y0540R270 S1      
317m1454            VIA   -    M      A01X+138466Y+063162X0200Y         S2      
017m1454            VIA   -    M      A18X+138466Y+063162X0260Y         S2      
017m1454                  -    MD0100PA00X+138466Y+063162                       
317m1454            VIA   -    MD0100PA00X+138300Y+058450X0200Y         S0      
327m1454            U350  -23         A01X+137402Y+058702X0160Y0540R270 S1      
317m1455            VIA   -    MD0100PA00X+143500Y+081850X0200Y         S0      
327m1455            R4627 -2          A01X+143742Y+081850X0198Y0197R180 S1      
317m1455            VIA   -    M      A01X+136500Y+080400X0200Y         S2      
017m1455            VIA   -    M      A18X+136500Y+080400X0260Y         S2      
017m1455                  -    MD0100PA00X+136500Y+080400                       
327m1455            R4148 -1          A01X+136500Y+080642X0198Y0197R090 S1      
327m1456            C4502 -1          A01X+083939Y+083995X0198Y0197R180 S1      
327m1456            R5772 -1   M      A01X+084593Y+083929X0198Y0197R180 S1      
327m1456            R5773 -1   M      A01X+085683Y+083946X0198Y0197R180 S1      
327m1456            VIA   -    M      A01X+086786Y+084517X0300Y         S1      
327m1456            U5    -F16        A01X+087979Y+085317X0160Y    R180 S1      
327PWR_EN_P3V3_R    PU21  -11         A01X+045461Y+050159X0110Y0240R270 S1      
327PWR_EN_P3V3_R    R6179 -1          A18X+129104Y+088565X0198Y0197     S2      
317PWR_EN_P3V3_R    VIA   -    MD0100PA00X+045114Y+046881X0200Y         S0      
327PWR_EN_P3V3_R    R5824 -1          A01X+045354Y+046881X0198Y0197     S1      
327PWR_EN_P3V3_R    R2774 -2          A01X+046283Y+051661X0198Y0197R180 S1      
327PWR_EN_P3V3_R    C2852 -1   M      A01X+046283Y+051267X0198Y0197     S1      
317PWR_EN_P3V3_R    VIA   -    M      A01X+045964Y+050949X0200Y         S2      
017PWR_EN_P3V3_R    VIA   -    M      A18X+045964Y+050949X0260Y         S2      
017PWR_EN_P3V3_R          -    MD0100PA00X+045964Y+050949                       
327PWR_EN_P3V3_R    R4166 -2          A18X+129642Y+088380X0198Y0197     S2      
317PWR_EN_P3V3_R    VIA   -    MD0100PA00X+129350Y+088380X0200Y         S0      
317PWR_EN_P3V3_R    VIA   -    MD0100PA00X+045924Y+080715X0200Y         S0      
317m1457            VIA   -    MD0100PA00X+165611Y+076867X0200Y         S0      
317m1457            VIA   -    MD0100PA00X+173288Y+113473X0200Y         S0      
327m1457            R4001 -1          A01X+173301Y+113713X0198Y0197R090 S1      
317m1457            VIA   -    MD0100PA00X+175888Y+099563X0200Y         S0      
327m1457            U349  -22         A01X+137402Y+063096X0160Y0540R270 S1      
317m1457            VIA   -    MD0100PA00X+137896Y+063096X0200Y         S0      
317m1457            VIA   -    M      A01X+137896Y+058446X0200Y         S2      
017m1457            VIA   -    M      A18X+137896Y+058446X0260Y         S2      
017m1457                  -    MD0100PA00X+137896Y+058446                       
327m1457            U350  -22         A01X+137402Y+058446X0160Y0540R270 S1      
317m1458            VIA   -    M      A01X+134205Y+057934X0200Y    R180 S2      
017m1458            VIA   -    M      A18X+134205Y+057934X0260Y    R180 S2      
017m1458                  -    MD0100PA00X+134205Y+057934                       
327m1458            R4832 -1          A01X+133258Y+057850X0198Y0197R180 S1      
327m1458            U350  -5          A01X+135098Y+057934X0160Y0540R270 S1      
327m1459            R2520 -2   M      A01X+101513Y+083766X0198Y0197R180 S1      
327m1459            C2491 -1          A01X+101513Y+083366X0198Y0197     S1      
327m1459            U342  -6          A01X+100744Y+083832X0110Y0360R090 S1      
317m1459            VIA   -    M      A01X+101270Y+083766X0200Y         S2      
017m1459            VIA   -    M      A18X+101270Y+083766X0260Y         S2      
017m1459                  -    MD0100PA00X+101270Y+083766                       
317m1459            VIA   -    MD0100PA00X+129327Y+088780X0200Y         S0      
317m1459            VIA   -    MD0100PA00X+105490Y+087932X0200Y         S0      
327m1459            R4165 -2   M      A18X+129642Y+088780X0198Y0197     S2      
327m1459            R3107 -2          A18X+129958Y+089180X0198Y0197R180 S2      
327m1460            U316  -5          A01X+172397Y+114684X0240Y0460     S1      
317m1460            VIA   -    M      A01X+172380Y+114267X0200Y         S2      
017m1460            VIA   -    M      A18X+172380Y+114267X0260Y         S2      
017m1460                  -    MD0100PA00X+172380Y+114267                       
327m1460            R4003 -2          A01X+171301Y+114028X0198Y0197R090 S1      
327m1461            U316  -6   M      A01X+172683Y+114684X0170Y0460     S1      
327m1461            R3998 -1          A01X+171701Y+114028X0198Y0197R270 S1      
327m1461            R4005 -2   M      A01X+172101Y+114028X0198Y0197R090 S1      
327m1461            R4002 -2   M      A01X+172501Y+114028X0198Y0197R090 S1      
327m1461            R4006 -1          A01X+172204Y+117112X0198Y0197     S1      
317m1461            VIA   -    M      A01X+172568Y+115754X0200Y         S2      
017m1461            VIA   -    M      A18X+172568Y+115754X0260Y         S2      
017m1461                  -    MD0100PA00X+172568Y+115754                       
317m1462            VIA   -    MD0100PA00X+137300Y+080400X0200Y         S0      
327m1462            R4152 -1          A01X+137300Y+080642X0198Y0197R090 S1      
317m1462            VIA   -    M      A01X+140912Y+077352X0200Y         S2      
017m1462            VIA   -    M      A18X+140912Y+077352X0260Y         S2      
017m1462                  -    MD0100PA00X+140912Y+077352                       
327m1462            R4690 -2          A01X+143742Y+077450X0198Y0197R180 S1      
317m1463            VIA   -    MD0100PA00X+133265Y+087711X0180Y         S0      
327m1463            U6    -H7         A01X+133423Y+087554X0160Y         S1      
327m1463            R834  -1          A01X+142634Y+099677X0198Y0197R180 S1      
317m1463            VIA   -    M      A01X+130756Y+098695X0200Y         S2      
017m1463            VIA   -    M      A18X+130756Y+098695X0260Y         S2      
017m1463                  -    MD0100PA00X+130756Y+098695                       
317m1463            VIA   -    MD0100PA00X+142886Y+099677X0200Y         S0      
327m1464            VIA   -    M      A01X+094648Y+086962X0300Y         S1      
327m1464            U5    -G2         A01X+092389Y+085632X0160Y    R180 S1      
327m1464            R4853 -1          A01X+095627Y+087028X0198Y0197R180 S1      
327m1465            U316  -7   M      A01X+172939Y+114684X0170Y0460     S1      
327m1465            R4004 -2   M      A01X+172901Y+114028X0198Y0197R090 S1      
327m1465            R3997 -1          A01X+173701Y+114028X0198Y0197R270 S1      
327m1465            R4001 -2   M      A01X+173301Y+114028X0198Y0197R090 S1      
327m1465            R4007 -1          A01X+173219Y+117112X0198Y0197R180 S1      
317m1465            VIA   -    M      A01X+173214Y+115740X0200Y         S2      
017m1465            VIA   -    M      A18X+173214Y+115740X0260Y         S2      
017m1465                  -    MD0100PA00X+173214Y+115740                       
327m1466            R4686 -2          A01X+143742Y+079050X0198Y0197R180 S1      
317m1466            VIA   -    M      A01X+136700Y+081162X0200Y         S2      
017m1466            VIA   -    M      A18X+136700Y+081162X0260Y         S2      
017m1466                  -    MD0100PA00X+136700Y+081162                       
327m1466            R4151 -1          A18X+136900Y+081642X0198Y0197R270 S2      
327m1467            R840  -1          A01X+142634Y+102027X0198Y0197R180 S1      
327m1467            U6    -C1         A01X+131533Y+089129X0160Y         S1      
317m1467            VIA   -    MD0100PA00X+130166Y+089913X0200Y         S0      
317m1467            VIA   -    M      A01X+130771Y+097987X0200Y         S2      
017m1467            VIA   -    M      A18X+130771Y+097987X0260Y         S2      
017m1467                  -    MD0100PA00X+130771Y+097987                       
317m1467            VIA   -    MD0100PA00X+142882Y+102027X0200Y         S0      
327m1468            VIA   -    M      A01X+093900Y+086347X0300Y         S1      
327m1468            U5    -F1         A01X+092704Y+085317X0160Y    R180 S1      
327m1468            R4852 -1          A01X+094455Y+086486X0198Y0197     S1      
327m1469            U316  -2          A01X+172939Y+116397X0170Y0460     S1      
317m1469            VIA   -    M      A01X+172921Y+116777X0200Y         S2      
017m1469            VIA   -    M      A18X+172921Y+116777X0260Y         S2      
017m1469                  -    MD0100PA00X+172921Y+116777                       
327m1469            R3992 -2          A01X+173500Y+117514X0198Y0197R270 S1      
327m1469            R4019 -2   M      A01X+173100Y+117514X0198Y0197R270 S1      
327m1469            R4007 -2   M      A01X+172904Y+117112X0198Y0197R180 S1      
317m1470            VIA   -    MD0100PA00X+141800Y+068900X0200Y         S0      
317m1470            VIA   -    MD0100PA00X+128340Y+071550X0200Y         S0      
327m1470            R4709 -2          A01X+142042Y+068900X0198Y0197R180 S1      
317m1470            VIA   -    M      A01X+128127Y+083549X0200Y    R180 S2      
017m1470            VIA   -    M      A18X+128127Y+083549X0260Y    R180 S2      
017m1470                  -    MD0100PA00X+128127Y+083549                       
327m1470            R4154 -2          A01X+128792Y+083950X0198Y0197R180 S1      
327m1471            R826  -1          A01X+051217Y+099677X0198Y0197R180 S1      
317m1471            VIA   -    M      A01X+049851Y+086539X0200Y         S2      
017m1471            VIA   -    M      A18X+049851Y+086539X0260Y         S2      
017m1471                  -    MD0100PA00X+049851Y+086539                       
317m1471            VIA   -    MD0100PA00X+051469Y+099677X0200Y         S0      
317m1471            VIA   -    MD0100PA00X+132636Y+088341X0180Y         S0      
327m1471            U6    -F5         A01X+132793Y+088184X0160Y         S1      
327m1472            R4153 -1          A01X+138100Y+080642X0198Y0197R090 S1      
317m1472            VIA   -    M      A01X+138100Y+080400X0200Y         S2      
017m1472            VIA   -    M      A18X+138100Y+080400X0260Y         S2      
017m1472                  -    MD0100PA00X+138100Y+080400                       
317m1472            VIA   -    MD0100PA00X+141800Y+070500X0200Y         S0      
327m1472            R4705 -2          A01X+142042Y+070500X0198Y0197R180 S1      
327m1473            R832  -1          A01X+051217Y+102027X0198Y0197R180 S1      
317m1473            VIA   -    M      A01X+050338Y+086302X0200Y         S2      
017m1473            VIA   -    M      A18X+050338Y+086302X0260Y         S2      
017m1473                  -    MD0100PA00X+050338Y+086302                       
317m1473            VIA   -    MD0100PA00X+051465Y+102027X0200Y         S0      
317m1473            VIA   -    MD0100PA00X+132950Y+088026X0180Y         S0      
327m1473            U6    -G6         A01X+133108Y+087869X0160Y         S1      
327m1474            U316  -3          A01X+172683Y+116397X0170Y0460     S1      
317m1474            VIA   -    M      A01X+172419Y+116777X0200Y         S2      
017m1474            VIA   -    M      A18X+172419Y+116777X0260Y         S2      
017m1474                  -    MD0100PA00X+172419Y+116777                       
327m1474            R3990 -2          A01X+172167Y+117509X0198Y0197R270 S1      
327m1474            R4020 -2   M      A01X+172567Y+117509X0198Y0197R270 S1      
327m1474            R4006 -2   M      A01X+172519Y+117112X0198Y0197     S1      
327m1475            R2468 -1          A01X+116028Y+065382X0198Y0197R270 S1      
317m1475            VIA   -    MD0100PA00X+116028Y+065632X0200Y         S0      
317m1475            VIA   -    M      A01X+111885Y+038211X0200Y    R180 S2      
017m1475            VIA   -    M      A18X+111885Y+038211X0260Y    R180 S2      
017m1475                  -    MD0100PA00X+111885Y+038211                       
327m1475            J24   -A70        A01X+111355Y+038207X0140Y0480R270 S1      
317m1476            VIA   -    MD0100PA00X+130390Y+128800X0200Y         S0      
317m1476            VIA   -    MD0100PA00X+140782Y+142698X0200Y         S0      
327m1476            R6315 -1          A18X+140782Y+142370X0198Y0197R180 S2      
317m1476            VIA   -    MD0100PA00X+098878Y+136197X0200Y         S0      
327m1476            PR7163-2          A18X+099378Y+138520X0198Y0197R180 S2      
327m1476            R6251 -2          A01X+076751Y+144663X0198Y0197R270 S1      
317m1476            VIA   -    MD0100PA00X+076881Y+145331X0200Y         S0      
317m1476            VIA   -    MD0100PA00X+126922Y+089476X0200Y         S0      
317m1476            VIA   -    MD0100PA00X+109038Y+089905X0200Y         S0      
317m1476            VIA   -    M      A01X+010959Y+079690X0200Y         S2      
017m1476            VIA   -    M      A18X+010959Y+079690X0260Y         S2      
017m1476                  -    MD0100PA00X+010959Y+079690                       
327m1476            R503  -1          A18X+008876Y+066444X0198Y0197     S2      
317m1476            VIA   -    MD0100PA00X+009554Y+066444X0200Y    R090 S0      
317m1476            VIA   -    MD0100PA00X+141624Y+094228X0200Y         S0      
327m1476            R6406 -2          A01X+142501Y+095156X0198Y0197R180 S1      
327HSC_ALERT1_N     R6248 -2          A18X+080242Y+146098X0198Y0197R180 S2      
327HSC_ALERT1_N     R6247 -2          A01X+079990Y+146953X0198Y0197R270 S1      
327HSC_ALERT1_N     PU1   -10         A01X+080322Y+146140X0090Y0150     S1      
317HSC_ALERT1_N     VIA   -    M      A01X+080268Y+146555X0200Y    R270 S2      
017HSC_ALERT1_N     VIA   -    M      A18X+080268Y+146555X0260Y    R270 S2      
017HSC_ALERT1_N           -    MD0100PA00X+080268Y+146555                       
317m1477            VIA   -    M      A01X+173748Y+118024X0200Y         S2      
017m1477            VIA   -    M      A18X+173748Y+118024X0260Y         S2      
017m1477                  -    MD0100PA00X+173748Y+118024                       
327m1477            R3992 -1          A01X+173500Y+117829X0198Y0197R270 S1      
327m1477            R3991 -2          A01X+173102Y+118205X0198Y0197R270 S1      
327m1477            R3996 -2   M      A01X+173499Y+118209X0198Y0197R270 S1      
327m1478            U6    -G7         A01X+133423Y+087869X0160Y         S1      
317m1478            VIA   -    MD0100PA00X+133265Y+088026X0180Y         S0      
317m1478            VIA   -    MD0100PA00X+105816Y+088764X0200Y         S0      
327m1478            R5538 -1          A01X+098163Y+082516X0198Y0197     S1      
317m1478            VIA   -    MD0100PA00X+098230Y+082120X0200Y         S0      
317m1478            VIA   -    M      A01X+102188Y+069897X0200Y         S2      
017m1478            VIA   -    M      A18X+102188Y+069897X0260Y         S2      
017m1478                  -    MD0100PA00X+102188Y+069897                       
317m1478            VIA   -    MD0100PA00X+087629Y+069897X0200Y         S0      
327m1478            R3144 -2          A01X+087869Y+069897X0198Y0197R180 S1      
327m1479            J2    -B14        A01X+090330Y+026220X0150Y0530R090 S1      
317m1479            VIA   -    M      A01X+089248Y+026086X0200Y         S2      
017m1479            VIA   -    M      A18X+089248Y+026086X0260Y         S2      
017m1479                  -    MD0100PA00X+089248Y+026086                       
317m1479            VIA   -    MD0100PA00X+087547Y+074206X0200Y         S0      
317m1479            VIA   -    MD0100PA00X+081736Y+075683X0200Y         S0      
327m1479            U89   -3          A01X+082813Y+085928X0110Y0280R180 S1      
317m1480            VIA   -    M      A01X+171938Y+118018X0200Y         S2      
017m1480            VIA   -    M      A18X+171938Y+118018X0260Y         S2      
017m1480                  -    MD0100PA00X+171938Y+118018                       
327m1480            R3990 -1          A01X+172167Y+117824X0198Y0197R270 S1      
327m1480            R3989 -2          A01X+172570Y+118206X0198Y0197R270 S1      
327m1480            R3995 -2   M      A01X+172170Y+118206X0198Y0197R270 S1      
317m1481            VIA   -    M      A01X+133800Y+070050X0200Y    R180 S2      
017m1481            VIA   -    M      A18X+133800Y+070050X0260Y    R180 S2      
017m1481                  -    MD0100PA00X+133800Y+070050                       
327m1481            R4754 -1          A01X+133258Y+070050X0198Y0197R180 S1      
327m1481            U347  -9          A01X+135098Y+070710X0160Y0540R270 S1      
327HSC_SS           PC8   -1          A18X+078327Y+144228X0198Y0197     S2      
327HSC_SS           PU1   -16         A01X+079579Y+145524X0090Y0150R270 S1      
317HSC_SS           VIA   -    M      A01X+079099Y+145570X0300Y    R270 S1      
017HSC_SS           VIA   -    M      A18X+079099Y+145570X0200Y    R270 S1      
017HSC_SS                 -    MD0100PA00X+079099Y+145570                       
317HSC_SS           VIA   -    MD0100PA00X+085064Y+145736X0200Y         S0      
327HSC_SS           PC15  -1          A01X+084532Y+145796X0198Y0197R180 S1      
327HSC_SS           PU2   -19         A01X+085586Y+145554X0100Y0150R270 S1      
317HSC_SS           VIA   -    MD0100PA00X+089392Y+146213X0200Y         S0      
327HSC_SS           PC12  -1          A01X+088682Y+146486X0198Y0197R180 S1      
327HSC_SS           PU3   -19         A01X+089786Y+145554X0100Y0150R270 S1      
317m1482            VIA   -    MD0080PA00X+162293Y+121171X0160Y    R270 S0      
327m1482            PEX3  -M29        A01X+162106Y+121358X0180Y         S1      
317m1482            VIA   -    M      A01X+173769Y+118524X0200Y         S2      
017m1482            VIA   -    M      A18X+173769Y+118524X0260Y         S2      
017m1482                  -    MD0100PA00X+173769Y+118524                       
327m1482            R3996 -1          A01X+173499Y+118524X0198Y0197R270 S1      
317m1483            VIA   -    M      A01X+134674Y+070249X0200Y    R180 S2      
017m1483            VIA   -    M      A18X+134674Y+070249X0260Y    R180 S2      
017m1483                  -    MD0100PA00X+134674Y+070249                       
327m1483            R4755 -1          A01X+133258Y+069650X0198Y0197R180 S1      
327m1483            U347  -10         A01X+135098Y+070454X0160Y0540R270 S1      
327m1484            R4768 -2          A01X+132942Y+067350X0198Y0197R180 S1      
317m1484            VIA   -    M      A01X+131398Y+067773X0200Y         S2      
017m1484            VIA   -    M      A18X+131398Y+067773X0260Y         S2      
017m1484                  -    MD0100PA00X+131398Y+067773                       
317m1484            VIA   -    MD0100PA00X+128133Y+084333X0200Y    R180 S0      
327m1484            R4157 -2          A01X+128792Y+084750X0198Y0197R180 S1      
327HSC_MODE_2       PR36  -2          A01X+092165Y+147210X0198Y0197R180 S1      
327HSC_MODE_2       PU3   -8          A01X+091553Y+145948X0100Y0140R270 S1      
327HSC_MODE_2       VIA   -    M      A01X+092165Y+147697X0300Y         S1      
317UART_MB_BIC_TX   VIA   -    M      A01X+083165Y+086449X0200Y    R270 S2      
017UART_MB_BIC_TX   VIA   -    M      A18X+083165Y+086449X0260Y    R270 S2      
017UART_MB_BIC_TX         -    MD0100PA00X+083165Y+086449                       
327UART_MB_BIC_TX   U89   -2          A01X+083010Y+085928X0110Y0280R180 S1      
327UART_MB_BIC_TX   R2739 -2          A01X+083288Y+086729X0198Y0197R270 S1      
317m1485            VIA   -    MD0080PA00X+161919Y+121171X0160Y    R270 S0      
327m1485            PEX3  -M28        A01X+161732Y+121358X0180Y         S1      
327m1485            R3995 -1          A01X+172170Y+118520X0198Y0197R270 S1      
317m1485            VIA   -    M      A01X+171969Y+118722X0200Y         S2      
017m1485            VIA   -    M      A18X+171969Y+118722X0260Y         S2      
017m1485                  -    MD0100PA00X+171969Y+118722                       
317m1486            VIA   -    M      A01X+130119Y+056552X0200Y         S2      
017m1486            VIA   -    M      A18X+130119Y+056552X0260Y         S2      
017m1486                  -    MD0100PA00X+130119Y+056552                       
327m1486            R4840 -2          A01X+138832Y+056500X0198Y0197     S1      
317m1486            VIA   -    MD0100PA00X+139074Y+056500X0200Y    R180 S0      
327m1486            R4804 -1          A18X+138601Y+056100X0198Y0197     S2      
327m1486            R4792 -2   M      A18X+138601Y+056500X0198Y0197R180 S2      
317m1486            VIA   -    MD0100PA00X+132006Y+085822X0180Y         S0      
327m1486            U6    -N3         A01X+132163Y+085979X0160Y         S1      
327m1487            R4753 -2          A01X+132942Y+070450X0198Y0197R180 S1      
317m1487            VIA   -    M      A01X+128550Y+085150X0200Y    R180 S2      
017m1487            VIA   -    M      A18X+128550Y+085150X0260Y    R180 S2      
017m1487                  -    MD0100PA00X+128550Y+085150                       
317m1487            VIA   -    MD0100PA00X+128932Y+070693X0200Y         S0      
327m1487            R4156 -2          A01X+128792Y+085150X0198Y0197R180 S1      
327HSC_FAULT_N      PR40  -2          A01X+092187Y+145743X0198Y0197R090 S1      
317HSC_FAULT_N      VIA   -    MD0100PA00X+091928Y+145623X0200Y         S0      
327HSC_FAULT_N      R492  -1          A01X+083113Y+144885X0198Y0197     S1      
327HSC_FAULT_N      PR8   -1   M      A18X+083390Y+144884X0198Y0197R270 S2      
327HSC_FAULT_N      PU1   -39         A01X+082128Y+145347X0090Y0150R270 S1      
317HSC_FAULT_N      VIA   -    M      A01X+082634Y+145124X0200Y    R270 S2      
017HSC_FAULT_N      VIA   -    M      A18X+082634Y+145124X0260Y    R270 S2      
017HSC_FAULT_N            -    MD0100PA00X+082634Y+145124                       
327HSC_FAULT_N      PR31  -2   M      A18X+088681Y+146085X0198Y0197R180 S2      
327m1488            L148  -2          A18X+094280Y+087227X0280Y0320R180 S2      
327m1488            VIA   -           A18X+093183Y+087453X0260Y         S2      
317m1488            VIA   -    MD0100PA00X+093232Y+087163X0200Y         S0      
317m1488            VIA   -    MD0100PA00X+093493Y+087173X0200Y         S0      
317m1488            VIA   -    MD0100PA00X+091601Y+086734X0180Y    R270 S0      
327m1488            U5    -K5         A01X+091444Y+086576X0160Y    R180 S1      
327m1488            C3611 -1          A18X+091444Y+086891X0164Y0164     S2      
317m1488            VIA   -    MD0100PA00X+091601Y+086419X0180Y    R270 S0      
327m1488            U5    -J5         A01X+091444Y+086262X0160Y    R180 S1      
327m1488            C3610 -1          A18X+091444Y+086576X0164Y0164     S2      
327m1489            J2    -B8         A01X+090330Y+024803X0150Y0530R090 S1      
317m1489            VIA   -    M      A01X+089506Y+025019X0200Y         S2      
017m1489            VIA   -    M      A18X+089506Y+025019X0260Y         S2      
017m1489                  -    MD0100PA00X+089506Y+025019                       
327m1489            R5288 -1          A18X+088802Y+082042X0198Y0197R270 S2      
327m1489            R5475 -1          A18X+088792Y+080646X0198Y0197R090 S2      
317m1489            VIA   -    MD0100PA00X+088792Y+080896X0200Y    R090 S0      
317m1490            VIA   -    MD0080PA00X+165659Y+120797X0160Y         S0      
327m1490            R3994 -1          A01X+170982Y+119652X0198Y0197R090 S1      
327m1490            VIA   -    M      A18X+170476Y+120220X0260Y         S2      
317m1490            VIA   -    MD0100PA00X+171254Y+119660X0200Y         S0      
327m1490            PEX3  -N38        A01X+165472Y+120984X0180Y         S1      
327m1491            R4749 -2          A01X+132942Y+072050X0198Y0197R180 S1      
317m1491            VIA   -    MD0100PA00X+128340Y+071970X0200Y         S0      
327m1491            R4155 -2          A01X+128792Y+084350X0198Y0197R180 S1      
317m1491            VIA   -    M      A01X+128550Y+084350X0200Y    R180 S2      
017m1491            VIA   -    M      A18X+128550Y+084350X0260Y    R180 S2      
017m1491                  -    MD0100PA00X+128550Y+084350                       
327HSC_FLT_TYPE_1   PR30  -1          A01X+088367Y+146886X0198Y0197     S1      
327HSC_FLT_TYPE_1   PU2   -6          A01X+087348Y+145554X0100Y0150R270 S1      
327HSC_FLT_TYPE_1   VIA   -    M      A01X+087824Y+146586X0300Y         S1      
317m1492            VIA   -    MD0100PA00X+135155Y+084247X0180Y         S0      
317m1492            VIA   -    M      A01X+085920Y+074452X0200Y         S2      
017m1492            VIA   -    M      A18X+085920Y+074452X0260Y         S2      
017m1492                  -    MD0100PA00X+085920Y+074452                       
327m1492            R5715 -1          A01X+088392Y+081346X0198Y0197R090 S1      
317m1492            VIA   -    MD0100PA00X+088392Y+080896X0200Y    R090 S0      
327m1492            U6    -V12        A01X+134998Y+084404X0160Y         S1      
317m1493            VIA   -    MD0080PA00X+165659Y+121545X0160Y         S0      
327m1493            R3993 -1          A01X+171757Y+120324X0198Y0197R090 S1      
327m1493            PEX3  -L39        A01X+165846Y+121732X0180Y         S1      
317m1493            VIA   -    MD0100PA00X+171862Y+119981X0200Y         S0      
327m1493            VIA   -    M      A18X+171532Y+120312X0260Y         S2      
317LED_POSTCODE_1   VIA   -    MD0100PA00X+127954Y+076358X0200Y         S0      
327LED_POSTCODE_1   U324  -5          A01X+129825Y+076632X0160Y0540R270 S1      
317LED_POSTCODE_1   VIA   -    M      A01X+127946Y+088449X0200Y         S2      
017LED_POSTCODE_1   VIA   -    M      A18X+127946Y+088449X0260Y         S2      
017LED_POSTCODE_1         -    MD0100PA00X+127946Y+088449                       
327LED_POSTCODE_1   R2979 -1          A01X+127684Y+088449X0198Y0197R180 S1      
317LED_POSTCODE_1   VIA   -    MD0100PA00X+132636Y+087396X0180Y         S0      
327LED_POSTCODE_1   U6    -J5         A01X+132793Y+087239X0160Y         S1      
327HSC_FLT_TYPE_R   PR21  -2          A18X+083446Y+146369X0198Y0197R180 S2      
317HSC_FLT_TYPE_R   VIA   -    MD0100PA00X+083448Y+146006X0200Y         S0      
327HSC_FLT_TYPE_R   PR30  -2          A01X+088682Y+146886X0198Y0197     S1      
317HSC_FLT_TYPE_R   VIA   -    MD0100PA00X+088924Y+146886X0200Y         S2      
327HSC_FLT_TYPE_R   PR39  -2          A01X+092478Y+146810X0198Y0197     S1      
317HSC_FLT_TYPE_R   VIA   -    MD0100PA00X+092544Y+147811X0200Y         S0      
317m1494            VIA   -    M      A01X+000834Y+028066X0200Y         S2      
017m1494            VIA   -    M      A18X+000834Y+028066X0260Y         S2      
017m1494                  -    MD0100PA00X+000834Y+028066                       
317m1494            VIA   -    MD0100PA00X+089957Y+015820X0200Y         S0      
327m1494            R5661 -1          A01X+019717Y+014577X0198Y0197     S1      
327m1494            R5657 -1          A01X+029954Y+014577X0198Y0197     S1      
327m1494            R5669 -1          A01X+044954Y+014577X0198Y0197     S1      
327m1494            R5665 -1          A01X+055190Y+014577X0198Y0197     S1      
327m1494            R5677 -1          A01X+065426Y+014577X0198Y0197     S1      
327m1494            R5673 -1          A01X+075662Y+014577X0198Y0197     S1      
327m1494            R5685 -1          A01X+090662Y+014577X0198Y0197     S1      
327m1494            R5681 -1          A01X+100898Y+014577X0198Y0197     S1      
327m1494            R5693 -1          A01X+111135Y+014577X0198Y0197     S1      
327m1494            R5689 -1          A01X+121371Y+014577X0198Y0197     S1      
327m1494            R5701 -1          A01X+136371Y+014577X0198Y0197     S1      
327m1494            R5705 -1          A01X+167080Y+014577X0198Y0197     S1      
327m1494            R5709 -1          A01X+156843Y+014577X0198Y0197     S1      
327m1494            R5697 -1          A01X+146607Y+014577X0198Y0197     S1      
327m1494            R5649 -1   M      A01X+009481Y+014577X0198Y0197     S1      
317m1494            VIA   -    MD0100PA00X+087992Y+080896X0200Y    R090 S0      
327m1494            R5285 -1          A01X+087992Y+081346X0198Y0197R090 S1      
317m1494            VIA   -    MD0100PA00X+009234Y+014417X0200Y         S0      
327m1494            R5653 -1          A01X+000834Y+028412X0198Y0197     S1      
317I2C0_PEX3_SCL    VIA   -    MD0080PA00X+164537Y+121171X0160Y         S0      
327I2C0_PEX3_SCL    PEX3  -M35        A01X+164350Y+121358X0180Y         S1      
317I2C0_PEX3_SCL    VIA   -    M      A01X+173305Y+118731X0200Y         S2      
017I2C0_PEX3_SCL    VIA   -    M      A18X+173305Y+118731X0260Y         S2      
017I2C0_PEX3_SCL          -    MD0100PA00X+173305Y+118731                       
327I2C0_PEX3_SCL    R3991 -1          A01X+173102Y+118520X0198Y0197R270 S1      
317I2C0_PEX3_SDA    VIA   -    MD0080PA00X+165659Y+121171X0160Y         S0      
327I2C0_PEX3_SDA    PEX3  -M39        A01X+165846Y+121358X0180Y         S1      
327I2C0_PEX3_SDA    R3989 -1          A01X+172570Y+118520X0198Y0197R270 S1      
317I2C0_PEX3_SDA    VIA   -    M      A01X+172834Y+118520X0200Y         S2      
017I2C0_PEX3_SDA    VIA   -    M      A18X+172834Y+118520X0260Y         S2      
017I2C0_PEX3_SDA          -    MD0100PA00X+172834Y+118520                       
317m1495            VIA   -    MD0100PA00X+130082Y+056864X0200Y         S0      
327m1495            R4841 -2          A01X+138832Y+056900X0198Y0197     S1      
317m1495            VIA   -    M      A01X+139074Y+056900X0200Y    R180 S2      
017m1495            VIA   -    M      A18X+139074Y+056900X0260Y    R180 S2      
017m1495                  -    MD0100PA00X+139074Y+056900                       
327m1495            R4798 -2          A18X+138601Y+056900X0198Y0197R180 S2      
317m1495            VIA   -    MD0100PA00X+132320Y+085822X0180Y         S0      
327m1495            U6    -N4         A01X+132478Y+085979X0160Y         S1      
327HSC_VDD_R        PC4   -1          A18X+080108Y+145099X0198Y0197R270 S2      
327HSC_VDD_R        PU1   -45  M      A01X+080106Y+144816X0460Y0630R270 S1      
317HSC_VDD_R        VIA   -    MD0100PA00X+079906Y+144916X0200Y    R270 S0      
317HSC_VDD_R        VIA   -    MD0100PA00X+080106Y+144716X0200Y    R270 S0      
317HSC_VDD_R        VIA   -    MD0100PA00X+080306Y+144916X0200Y    R270 S0      
327HSC_VDD_R        PR4   -1          A18X+078323Y+144619X0198Y0197     S2      
317HSC_VDD_R        VIA   -    M      A01X+078659Y+145280X0200Y    R270 S2      
017HSC_VDD_R        VIA   -    M      A18X+078659Y+145280X0260Y    R270 S2      
017HSC_VDD_R              -    MD0100PA00X+078659Y+145280                       
327HSC_VDD_R        PU1   -17         A01X+079579Y+145347X0090Y0150R270 S1      
327HSC_VDD_R        PC5   -1          A01X+078322Y+145272X0198Y0197R270 S1      
317PRSNT_NIC7_R_N   VIA   -    MD0100PA00X+138305Y+085822X0180Y         S0      
317PRSNT_NIC7_R_N   VIA   -    MD0100PA00X+098837Y+076414X0200Y         S0      
327PRSNT_NIC7_R_N   U6    -N22        A01X+138147Y+085979X0160Y         S1      
317PRSNT_NIC7_R_N   VIA   -    MD0100PA00X+139560Y+055622X0200Y         S0      
327PRSNT_NIC7_R_N   U44   -G   M      A01X+170768Y+056004X0400Y0560R180 S1      
327PRSNT_NIC7_R_N   R400  -1   M      A01X+171354Y+055829X0198Y0197R270 S1      
327PRSNT_NIC7_R_N   C4005 -1          A01X+171354Y+056214X0198Y0197R090 S1      
317PRSNT_NIC7_R_N   VIA   -    M      A01X+169872Y+055006X0200Y    R180 S2      
017PRSNT_NIC7_R_N   VIA   -    M      A18X+169872Y+055006X0260Y    R180 S2      
017PRSNT_NIC7_R_N         -    MD0100PA00X+169872Y+055006                       
327PRSNT_NIC7_R_N   U5    -R2         A01X+092389Y+088151X0160Y    R180 S1      
317PRSNT_NIC7_R_N   VIA   -    MD0100PA00X+092546Y+088309X0180Y    R270 S0      
327HSC_OCREF        PU2   -24         A01X+085581Y+144570X0100Y0140R270 S1      
327HSC_OCREF        PR32  -1          A01X+084531Y+144086X0198Y0197R180 S1      
317HSC_OCREF        VIA   -    MD0100PA00X+084531Y+143827X0200Y         S0      
327HSC_OCREF        PU3   -24         A01X+089781Y+144570X0100Y0140R270 S1      
327HSC_OCREF        PR41  -1          A01X+088682Y+144086X0198Y0197R180 S1      
317HSC_OCREF        VIA   -    MD0100PA00X+089224Y+144086X0200Y         S0      
327HSC_OCREF        PU1   -22         A01X+079791Y+144378X0090Y0150     S1      
317HSC_OCREF        VIA   -    M      A01X+079399Y+144150X0200Y    R270 S2      
017HSC_OCREF        VIA   -    M      A18X+079399Y+144150X0260Y    R270 S2      
017HSC_OCREF              -    MD0100PA00X+079399Y+144150                       
327HSC_VDD_2        PR35  -1          A18X+088682Y+145686X0198Y0197     S2      
327HSC_VDD_2        PC13  -1   M      A01X+089184Y+145208X0198Y0197R090 S1      
317HSC_VDD_2        VIA   -    MD0100PA00X+088934Y+145255X0200Y         S2      
327HSC_VDD_2        PU3   -21         A01X+089786Y+145160X0100Y0150R270 S1      
317m1496            VIA   -    MD0100PA00X+132320Y+084562X0180Y         S0      
327m1496            U6    -U4         A01X+132478Y+084719X0160Y         S1      
327m1496            R4794 -2          A01X+132458Y+060500X0198Y0197     S1      
327m1496            R4818 -2          A01X+132942Y+060500X0198Y0197R180 S1      
317m1496            VIA   -    M      A01X+132700Y+060500X0200Y         S2      
017m1496            VIA   -    M      A18X+132700Y+060500X0260Y         S2      
017m1496                  -    MD0100PA00X+132700Y+060500                       
317m1497            VIA   -    M      A01X+132700Y+061300X0200Y         S2      
017m1497            VIA   -    M      A18X+132700Y+061300X0260Y         S2      
017m1497                  -    MD0100PA00X+132700Y+061300                       
327m1497            R4816 -2          A01X+132942Y+061300X0198Y0197R180 S1      
327m1497            R4160 -1          A01X+128792Y+083150X0198Y0197     S1      
317m1497            VIA   -    MD0100PA00X+128139Y+082739X0200Y    R180 S0      
327HSC_VIN_UVW_N    PU1   -14         A01X+079579Y+145879X0090Y0150R270 S1      
317HSC_VIN_UVW_N    VIA   -    M      A01X+078704Y+146053X0300Y    R270 S1      
017HSC_VIN_UVW_N    VIA   -    M      A18X+078704Y+146053X0200Y    R270 S1      
017HSC_VIN_UVW_N          -    MD0100PA00X+078704Y+146053                       
327HSC_VIN_UVW_N    PR14  -2          A18X+078063Y+145324X0198Y0197R270 S2      
327m1498            PU14  -6          A01X+140642Y+112155X0090Y0240R270 S1      
327P3V3_SSD3_OCP    PU60  -9          A01X+033520Y+022506X0110Y0240     S1      
317P3V3_SSD3_OCP    VIA   -    M      A01X+033443Y+023056X0200Y    R090 S2      
017P3V3_SSD3_OCP    VIA   -    M      A18X+033443Y+023056X0260Y    R090 S2      
017P3V3_SSD3_OCP          -    MD0100PA00X+033443Y+023056                       
327P3V3_SSD3_OCP    PR270 -1          A01X+033505Y+023296X0198Y0197R090 S1      
317m1499            VIA   -    M      A01X+139074Y+056100X0200Y    R180 S2      
017m1499            VIA   -    M      A18X+139074Y+056100X0260Y    R180 S2      
017m1499                  -    MD0100PA00X+139074Y+056100                       
327m1499            R4839 -2          A01X+138832Y+056100X0198Y0197     S1      
317m1499            VIA   -    MD0100PA00X+133110Y+054993X0200Y         S0      
327m1499            R4164 -1          A01X+128792Y+085550X0198Y0197     S1      
317m1499            VIA   -    MD0100PA00X+128550Y+085550X0200Y    R180 S0      
327RST_SMB_FIO_N    VIA   -    M      A18X+088606Y+082811X0260Y         S2      
327RST_SMB_FIO_N    R5288 -2          A18X+088802Y+082356X0198Y0197R270 S2      
327RST_SMB_FIO_N    U5    -C11        A01X+089554Y+084372X0160Y    R180 S1      
317RST_SMB_FIO_N    VIA   -    MD0100PA00X+089397Y+084214X0180Y    R270 S0      
317m1500            VIA   -    M      A01X+133322Y+061548X0200Y         S2      
017m1500            VIA   -    M      A18X+133322Y+061548X0260Y         S2      
017m1500                  -    MD0100PA00X+133322Y+061548                       
327m1500            R4822 -2          A01X+138832Y+061550X0198Y0197     S1      
317m1500            VIA   -    MD0100PA00X+139074Y+061550X0200Y    R180 S0      
327m1500            R4797 -2          A18X+138601Y+061550X0198Y0197R180 S2      
317m1500            VIA   -    MD0100PA00X+132950Y+086137X0180Y         S0      
327m1500            U6    -M6         A01X+133108Y+086294X0160Y         S1      
317m1501            VIA   -    MD0100PA00X+139074Y+060750X0200Y         S0      
327m1501            R4820 -2          A01X+138832Y+060750X0198Y0197     S1      
317m1501            VIA   -    M      A01X+131932Y+059845X0200Y         S2      
017m1501            VIA   -    M      A18X+131932Y+059845X0260Y         S2      
017m1501                  -    MD0100PA00X+131932Y+059845                       
327m1501            R4163 -1          A01X+128792Y+085950X0198Y0197     S1      
317m1501            VIA   -    MD0100PA00X+128550Y+085950X0200Y    R180 S0      
327HSC_IMON         PR13  -1          A01X+088679Y+145266X0198Y0197R180 S1      
327HSC_IMON         PR33  -1   M      A01X+078332Y+143143X0198Y0197R180 S1      
327HSC_IMON         PR43  -1          A01X+084532Y+144896X0198Y0197R180 S1      
327HSC_IMON         PU1   -21         A01X+079579Y+144639X0090Y0150R270 S1      
317HSC_IMON         VIA   -    M      A01X+079075Y+144140X0300Y    R270 S1      
017HSC_IMON         VIA   -    M      A18X+079075Y+144140X0200Y    R270 S1      
017HSC_IMON               -    MD0100PA00X+079075Y+144140                       
327HSC_IMON         PU2   -22         A01X+085586Y+144964X0100Y0150R270 S1      
317HSC_IMON         VIA   -    MD0100PA00X+085054Y+144756X0200Y         S0      
327HSC_IMON         PU3   -22         A01X+089786Y+144964X0100Y0150R270 S1      
317HSC_IMON         VIA   -    MD0100PA00X+089224Y+144964X0200Y         S0      
327HSC_IMON         PC6   -1          A01X+078332Y+142743X0198Y0197R180 S1      
327RST_SMB_SSD_N    VIA   -    M      A01X+088419Y+082136X0300Y    R270 S1      
327RST_SMB_SSD_N    R5285 -2          A01X+087992Y+081662X0198Y0197R090 S1      
327RST_SMB_SSD_N    U5    -B13        A01X+088924Y+084057X0160Y    R180 S1      
327m1502            U313  -5          A01X+035271Y+114684X0240Y0460     S1      
317m1502            VIA   -    M      A01X+035254Y+114267X0200Y         S2      
017m1502            VIA   -    M      A18X+035254Y+114267X0260Y         S2      
017m1502                  -    MD0100PA00X+035254Y+114267                       
327m1502            R3947 -2          A01X+034175Y+114028X0198Y0197R090 S1      
317m1503            VIA   -    MD0080PA00X+160984Y+121732X0160Y    R090 S0      
327m1503            VIA   -    M      A18X+172658Y+122876X0260Y         S2      
317m1503            VIA   -    MD0100PA00X+172932Y+122602X0200Y         S0      
327m1503            R3946 -1          A01X+173091Y+122347X0198Y0197R315 S1      
327m1503            PEX3  -L26        A01X+160984Y+121732X0180Y         S1      
317m1504            VIA   -    M      A01X+132700Y+058383X0200Y         S2      
017m1504            VIA   -    M      A18X+132700Y+058383X0260Y         S2      
017m1504                  -    MD0100PA00X+132700Y+058383                       
327m1504            R4831 -2          A01X+132942Y+058250X0198Y0197R180 S1      
327m1504            R4161 -2          A01X+128792Y+086350X0198Y0197R180 S1      
317m1504            VIA   -    MD0100PA00X+128550Y+086350X0200Y    R180 S0      
327HSC_VTEMP        PR16  -1          A01X+077164Y+145430X0198Y0197     S1      
327HSC_VTEMP        PU1   -15         A01X+079579Y+145702X0090Y0150R270 S1      
327HSC_VTEMP        PC7   -1   M      A01X+078158Y+145807X0198Y0197R180 S1      
317HSC_VTEMP        VIA   -    M      A01X+078362Y+146011X0200Y    R270 S2      
017HSC_VTEMP        VIA   -    M      A18X+078362Y+146011X0260Y    R270 S2      
017HSC_VTEMP              -    MD0100PA00X+078362Y+146011                       
317HSC_VTEMP        VIA   -    MD0100PA00X+085351Y+145751X0200Y         S0      
327HSC_VTEMP        PU2   -18         A01X+085586Y+145751X0100Y0150R270 S1      
317HSC_VTEMP        VIA   -    MD0100PA00X+089524Y+145751X0200Y         S0      
327HSC_VTEMP        PU3   -18         A01X+089786Y+145751X0100Y0150R270 S1      
327m1505            PU68  -11         A01X+170252Y+022506X0110Y0240     S1      
327m1505            R6115 -1          A01X+168959Y+013090X0198Y0197R270 S1      
327m1505            R5585 -1   M      A01X+168278Y+014775X0198Y0197R090 S1      
317m1505            VIA   -    MD0100PA00X+167944Y+015737X0200Y         S0      
327m1505            C2899 -1          A01X+169691Y+023286X0198Y0197R090 S1      
317m1505            VIA   -    M      A01X+170094Y+022865X0200Y    R090 S2      
017m1505            VIA   -    M      A18X+170094Y+022865X0260Y    R090 S2      
017m1505                  -    MD0100PA00X+170094Y+022865                       
317m1506            VIA   -    MD0100PA00X+115251Y+072854X0200Y         S0      
317m1506            VIA   -    M      A01X+141350Y+087600X0200Y         S2      
017m1506            VIA   -    M      A18X+141350Y+087600X0260Y         S2      
017m1506                  -    MD0100PA00X+141350Y+087600                       
327m1506            R3639 -2          A01X+141108Y+087600X0198Y0197     S1      
327m1506            U31   -2          A01X+111178Y+068201X0220Y0530R180 S1      
317m1506            VIA   -    MD0100PA00X+111178Y+068697X0200Y         S0      
327m1507            R4162 -2          A01X+128792Y+086700X0198Y0197R180 S1      
317m1507            VIA   -    MD0100PA00X+128550Y+086750X0200Y    R180 S0      
317m1507            VIA   -    M      A01X+132695Y+056791X0200Y         S2      
017m1507            VIA   -    M      A18X+132695Y+056791X0260Y         S2      
017m1507                  -    MD0100PA00X+132695Y+056791                       
327m1507            R4835 -2          A01X+132942Y+056650X0198Y0197R180 S1      
327HSC_MODE_1       PR27  -2          A01X+088367Y+147286X0198Y0197R180 S1      
327HSC_MODE_1       PU2   -8          A01X+087353Y+145948X0100Y0140R270 S1      
327HSC_MODE_1       VIA   -    M      A01X+087824Y+147136X0300Y         S1      
327m1508            PU15  -31         A01X+142276Y+111023X0090Y0240R180 S1      
317m1509            VIA   -    M      A01X+132700Y+062900X0200Y         S2      
017m1509            VIA   -    M      A18X+132700Y+062900X0260Y         S2      
017m1509                  -    MD0100PA00X+132700Y+062900                       
327m1509            R4812 -2          A01X+132942Y+062900X0198Y0197R180 S1      
327m1509            R4159 -1          A01X+128792Y+082750X0198Y0197     S1      
317m1509            VIA   -    MD0100PA00X+128550Y+082750X0200Y    R180 S0      
327HSC_FLT_TYPE_2   PU3   -6          A01X+091548Y+145554X0100Y0150R270 S1      
327HSC_FLT_TYPE_2   PR39  -1          A01X+092163Y+146810X0198Y0197     S1      
327HSC_FLT_TYPE_2   VIA   -    M      A01X+092163Y+146324X0300Y         S1      
327m1510            VIA   -    M      A01X+088919Y+082136X0300Y    R270 S1      
327m1510            U5    -B12        A01X+089239Y+084057X0160Y    R180 S1      
327m1510            R5289 -2          A01X+088392Y+080646X0198Y0197R090 S1      
327m1511            VIA   -    M      A01X+168772Y+015486X0300Y         S1      
327m1511            U378  -D          A01X+169743Y+016196X0400Y0560     S1      
327m1511            R5585 -2          A01X+168278Y+015090X0198Y0197R090 S1      
327m1511            R5584 -2   M      A01X+168278Y+015486X0198Y0197R270 S1      
327HSC_CS_2         PR42  -1          A01X+088682Y+144886X0198Y0197R180 S1      
327HSC_CS_2         PU3   -23         A01X+089786Y+144767X0100Y0150R270 S1      
327HSC_CS_2         VIA   -    M      A01X+089262Y+144652X0300Y         S1      
317m1512            VIA   -    M      A01X+170136Y+014872X0200Y         S2      
017m1512            VIA   -    M      A18X+170136Y+014872X0260Y         S2      
017m1512                  -    MD0100PA00X+170136Y+014872                       
327m1512            U378  -G          A01X+169369Y+015330X0400Y0560     S1      
327m1512            R5586 -1          A01X+170424Y+014691X0198Y0197R270 S1      
327HSC_D_OC         R493  -1          A01X+080705Y+140477X0198Y0197     S1      
317HSC_D_OC         VIA   -    M      A01X+080465Y+140477X0200Y         S2      
017HSC_D_OC         VIA   -    M      A18X+080465Y+140477X0260Y         S2      
017HSC_D_OC               -    MD0100PA00X+080465Y+140477                       
317HSC_D_OC         VIA   -    M      A01X+082620Y+144069X0200Y    R270 S2      
017HSC_D_OC         VIA   -    M      A18X+082620Y+144069X0260Y    R270 S2      
017HSC_D_OC               -    MD0100PA00X+082620Y+144069                       
327HSC_D_OC         PU1   -37         A01X+082128Y+144993X0090Y0150R270 S1      
327HSC_D_OC         PR7   -1          A01X+083113Y+144085X0198Y0197     S1      
317HSC_D_OC         VIA   -    M      A01X+088924Y+144486X0200Y         S2      
017HSC_D_OC         VIA   -    M      A18X+088924Y+144486X0260Y         S2      
017HSC_D_OC               -    MD0100PA00X+088924Y+144486                       
327HSC_D_OC         PR29  -2          A01X+088682Y+144486X0198Y0197     S1      
317HSC_D_OC         VIA   -    MD0100PA00X+092150Y+144669X0200Y         S0      
327HSC_D_OC         PR38  -2          A01X+092542Y+144954X0198Y0197     S1      
327m1513            R1821 -2          A01X+108690Y+159636X0198Y0197R090 S1      
317m1513            VIA   -    M      A01X+108690Y+159900X0200Y         S2      
017m1513            VIA   -    M      A18X+108690Y+159900X0260Y         S2      
017m1513                  -    MD0100PA00X+108690Y+159900                       
317m1513            VIA   -    MD0100PA00X+130536Y+090260X0200Y         S0      
317m1513            VIA   -    MD0100PA00X+083001Y+083305X0200Y         S0      
317m1513            VIA   -    M      A01X+097498Y+129095X0200Y         S2      
017m1513            VIA   -    M      A18X+097498Y+129095X0260Y         S2      
017m1513                  -    MD0100PA00X+097498Y+129095                       
317m1513            VIA   -    MD0100PA00X+135155Y+088341X0180Y         S0      
327m1513            U6    -F12        A01X+134998Y+088184X0160Y         S1      
327m1514            PU67  -11         A01X+160016Y+022506X0110Y0240     S1      
327m1514            R6114 -1          A01X+158723Y+013090X0198Y0197R270 S1      
327m1514            R5579 -1   M      A01X+158042Y+014775X0198Y0197R090 S1      
317m1514            VIA   -    MD0100PA00X+157708Y+015737X0200Y         S0      
327m1514            C2898 -1          A01X+159455Y+023286X0198Y0197R090 S1      
317m1514            VIA   -    M      A01X+159858Y+022865X0200Y    R090 S2      
017m1514            VIA   -    M      A18X+159858Y+022865X0260Y    R090 S2      
017m1514                  -    MD0100PA00X+159858Y+022865                       
327m1515            PU15  -6          A01X+143855Y+112155X0090Y0240R270 S1      
327HSC_ON_R         PR17  -2          A01X+083113Y+144485X0198Y0197R180 S1      
327HSC_ON_R         PU1   -38         A01X+082128Y+145170X0090Y0150R270 S1      
317HSC_ON_R         VIA   -    M      A01X+082620Y+144469X0300Y    R270 S1      
017HSC_ON_R         VIA   -    M      A18X+082620Y+144469X0200Y    R270 S1      
017HSC_ON_R               -    MD0100PA00X+082620Y+144469                       
327m1516            PU15  -41         A01X+143510Y+112263X0120Y0180R090 S1      
327m1517            VIA   -    M      A01X+158536Y+015486X0300Y         S1      
327m1517            R5579 -2          A01X+158042Y+015090X0198Y0197R090 S1      
327m1517            R5578 -2   M      A01X+158042Y+015486X0198Y0197R270 S1      
327m1517            U376  -D          A01X+159507Y+016196X0400Y0560     S1      
327m1518            PU14  -31         A01X+139063Y+111023X0090Y0240R180 S1      
317m1519            VIA   -    M      A01X+159900Y+014872X0200Y         S2      
017m1519            VIA   -    M      A18X+159900Y+014872X0260Y         S2      
017m1519                  -    MD0100PA00X+159900Y+014872                       
327m1519            U376  -G          A01X+159133Y+015330X0400Y0560     S1      
327m1519            R5580 -1          A01X+160187Y+014691X0198Y0197R270 S1      
327HSC_D_OC_2       PU3   -3          A01X+091548Y+144964X0100Y0150R270 S1      
327HSC_D_OC_2       PR38  -1          A01X+092226Y+144954X0198Y0197     S1      
327HSC_D_OC_2       VIA   -    M      A01X+092024Y+144349X0300Y         S1      
327m1520            PU65  -11         A01X+149780Y+022506X0110Y0240     S1      
327m1520            R6103 -1          A01X+148487Y+013090X0198Y0197R270 S1      
327m1520            R5573 -1   M      A01X+147806Y+014775X0198Y0197R090 S1      
317m1520            VIA   -    MD0100PA00X+147472Y+015737X0200Y         S0      
327m1520            C2896 -1          A01X+149219Y+023286X0198Y0197R090 S1      
317m1520            VIA   -    M      A01X+149622Y+022865X0200Y    R090 S2      
017m1520            VIA   -    M      A18X+149622Y+022865X0260Y    R090 S2      
017m1520                  -    MD0100PA00X+149622Y+022865                       
327HSC_CS_1         PR34  -1          A01X+084532Y+144496X0198Y0197R180 S1      
327HSC_CS_1         PU2   -23         A01X+085586Y+144767X0100Y0150R270 S1      
327HSC_CS_1         VIA   -    M      A01X+085038Y+144396X0300Y         S1      
327m1521            R1811 -2   M      A01X+109090Y+159321X0198Y0197R270 S1      
327m1521            R1819 -1          A01X+109490Y+159321X0198Y0197R090 S1      
327m1521            R1821 -1   M      A01X+108690Y+159321X0198Y0197R090 S1      
317m1521            VIA   -    M      A01X+108390Y+159321X0200Y    R090 S2      
017m1521            VIA   -    M      A18X+108390Y+159321X0260Y    R090 S2      
017m1521                  -    MD0100PA00X+108390Y+159321                       
317m1521            VIA   -    MD0100PA00X+087218Y+099398X0200Y         S0      
327m1521            R5292 -2          A01X+089592Y+081346X0198Y0197R270 S1      
317m1521            VIA   -    MD0100PA00X+089592Y+080896X0200Y    R090 S0      
317m1521            VIA   -    MD0100PA00X+088973Y+129552X0200Y         S0      
317m1522            VIA   -    MD0080PA00X+119951Y+120423X0160Y         S0      
327m1522            PEX2  -P39        A01X+120138Y+120610X0180Y         S1      
317m1522            VIA   -    M      A01X+125622Y+117599X0200Y         S2      
017m1522            VIA   -    M      A18X+125622Y+117599X0260Y         S2      
017m1522                  -    MD0100PA00X+125622Y+117599                       
327m1522            R6396 -2          A01X+125964Y+118505X0198Y0197R090 S1      
327m1523            VIA   -    M      A01X+148299Y+015486X0300Y         S1      
327m1523            U374  -D          A01X+149271Y+016196X0400Y0560     S1      
327m1523            R5573 -2          A01X+147806Y+015090X0198Y0197R090 S1      
327m1523            R5572 -2   M      A01X+147806Y+015486X0198Y0197R270 S1      
327m1524            R4821 -2          A01X+138832Y+061150X0198Y0197     S1      
317m1524            VIA   -    MD0100PA00X+139074Y+061150X0200Y         S0      
327m1524            R4806 -1          A18X+138601Y+060750X0198Y0197     S2      
327m1524            R4791 -2   M      A18X+138601Y+061150X0198Y0197R180 S2      
317m1524            VIA   -    M      A01X+134443Y+060120X0200Y         S2      
017m1524            VIA   -    M      A18X+134443Y+060120X0260Y         S2      
017m1524                  -    MD0100PA00X+134443Y+060120                       
327m1524            U6    -N1         A01X+131533Y+085979X0160Y         S1      
317m1524            VIA   -    MD0100PA00X+131376Y+085822X0180Y         S0      
327HSC_VDD18        PU1   -19         A01X+079579Y+144993X0090Y0150R270 S1      
317HSC_VDD18        VIA   -    M      A01X+079036Y+144790X0300Y    R270 S1      
017HSC_VDD18        VIA   -    M      A18X+079036Y+144790X0200Y    R270 S1      
017HSC_VDD18              -    MD0100PA00X+079036Y+144790                       
327HSC_VDD18        PC9   -1          A01X+078332Y+143943X0198Y0197R180 S1      
327m1525            PU14  -41         A01X+140298Y+112263X0120Y0180R090 S1      
327m1526            VIA   -    M      A01X+089616Y+082493X0300Y    R270 S1      
327m1526            R5292 -1          A01X+089592Y+081662X0198Y0197R270 S1      
327m1526            U5    -B10        A01X+089869Y+084057X0160Y    R180 S1      
317m1527            VIA   -    M      A01X+149664Y+014872X0200Y         S2      
017m1527            VIA   -    M      A18X+149664Y+014872X0260Y         S2      
017m1527                  -    MD0100PA00X+149664Y+014872                       
327m1527            U374  -G          A01X+148897Y+015330X0400Y0560     S1      
327m1527            R5574 -1          A01X+149951Y+014691X0198Y0197R270 S1      
327m1528            R4801 -1          A01X+132458Y+061300X0198Y0197R180 S1      
327m1528            R4788 -2   M      A01X+132458Y+060900X0198Y0197     S1      
327m1528            R4817 -2          A01X+132942Y+060900X0198Y0197R180 S1      
317m1528            VIA   -    MD0100PA00X+132700Y+060900X0200Y         S0      
317m1528            VIA   -    M      A01X+134413Y+060691X0200Y         S2      
017m1528            VIA   -    M      A18X+134413Y+060691X0260Y         S2      
017m1528                  -    MD0100PA00X+134413Y+060691                       
327m1528            U6    -W1         A01X+131533Y+084089X0160Y         S1      
317m1528            VIA   -    MD0100PA00X+131097Y+084232X0200Y         S0      
327m1529            VIA   -    M      A01X+087945Y+056270X0300Y    R180 S1      
327m1529            U117  -A1         A01X+088719Y+056404X0070Y0220R180 S1      
327m1529            R4210 -2   M      A01X+087264Y+056270X0198Y0197     S1      
327m1529            R4197 -1          A01X+087264Y+055470X0198Y0197R180 S1      
327m1529            C2807 -1   M      A01X+087264Y+055870X0198Y0197R180 S1      
327HSC_D_OC_1       PR29  -1          A01X+088367Y+144486X0198Y0197     S1      
327HSC_D_OC_1       PU2   -3          A01X+087348Y+144964X0100Y0150R270 S1      
327HSC_D_OC_1       VIA   -    M      A01X+087895Y+144643X0300Y         S1      
327m1530            PU63  -11         A01X+139544Y+022506X0110Y0240     S1      
327m1530            R6102 -1          A01X+138250Y+013090X0198Y0197R270 S1      
327m1530            R5567 -1   M      A01X+137569Y+014775X0198Y0197R090 S1      
317m1530            VIA   -    MD0100PA00X+137235Y+015737X0200Y         S0      
327m1530            C2894 -1          A01X+138982Y+023286X0198Y0197R090 S1      
317m1530            VIA   -    M      A01X+139386Y+022865X0200Y    R090 S2      
017m1530            VIA   -    M      A18X+139386Y+022865X0260Y    R090 S2      
017m1530                  -    MD0100PA00X+139386Y+022865                       
327HSC_FLT_TYPE     PR21  -1          A18X+083131Y+146369X0198Y0197R180 S2      
327HSC_FLT_TYPE     PU1   -40         A01X+082128Y+145524X0090Y0150R270 S1      
317HSC_FLT_TYPE     VIA   -    M      A01X+082622Y+145524X0300Y         S1      
017HSC_FLT_TYPE     VIA   -    M      A18X+082622Y+145524X0200Y         S1      
017HSC_FLT_TYPE           -    MD0100PA00X+082622Y+145524                       
327m1531            VIA   -    M      A01X+138063Y+015486X0300Y         S1      
327m1531            U372  -D          A01X+139035Y+016196X0400Y0560     S1      
327m1531            R5567 -2          A01X+137569Y+015090X0198Y0197R090 S1      
327m1531            R5566 -2   M      A01X+137569Y+015486X0198Y0197R270 S1      
317m1532            VIA   -    M      A01X+121226Y+017152X0200Y         S2      
017m1532            VIA   -    M      A18X+121226Y+017152X0260Y         S2      
017m1532                  -    MD0100PA00X+121226Y+017152                       
317m1532            VIA   -    MD0100PA00X+121707Y+019018X0200Y         S0      
327m1532            U73   -4          A01X+121435Y+018580X0090Y0240R090 S1      
327m1532            R622  -2   M      A01X+122064Y+019266X0198Y0197R180 S1      
327m1532            R5901 -2          A01X+122064Y+019666X0198Y0197R180 S1      
327m1532            R5900 -2          A01X+121226Y+016871X0198Y0197R180 S1      
327m1533            VIA   -    M      A01X+089769Y+054466X0300Y         S1      
327m1533            R4217 -1          A01X+088943Y+053964X0198Y0197R270 S1      
327m1533            U117  -A10        A01X+090491Y+056404X0070Y0220R180 S1      
327HSC_ON           PU3   -4          A01X+091548Y+145160X0100Y0150R270 S1      
327HSC_ON           PC11  -1          A01X+088367Y+146086X0198Y0197     S1      
327HSC_ON           PR17  -1          A01X+083428Y+144485X0198Y0197R180 S1      
317HSC_ON           VIA   -    MD0100PA00X+083674Y+144485X0200Y         S0      
327HSC_ON           PU2   -4          A01X+087348Y+145160X0100Y0150R270 S1      
317HSC_ON           VIA   -    M      A01X+087824Y+145160X0200Y         S2      
017HSC_ON           VIA   -    M      A18X+087824Y+145160X0260Y         S2      
017HSC_ON                 -    MD0100PA00X+087824Y+145160                       
327HSC_ON           PC14  -1          A01X+092570Y+145425X0198Y0197R090 S1      
317HSC_ON           VIA   -    MD0100PA00X+092024Y+145160X0200Y         S0      
317m1534            VIA   -    M      A01X+139428Y+014872X0200Y         S2      
017m1534            VIA   -    M      A18X+139428Y+014872X0260Y         S2      
017m1534                  -    MD0100PA00X+139428Y+014872                       
327m1534            U372  -G          A01X+138661Y+015330X0400Y0560     S1      
327m1534            R5568 -1          A01X+139715Y+014691X0198Y0197R270 S1      
317m1535            VIA   -    M      A01X+038486Y+094799X0200Y    R180 S2      
017m1535            VIA   -    M      A18X+038486Y+094799X0260Y    R180 S2      
017m1535                  -    MD0100PA00X+038486Y+094799                       
327m1535            U96   -5          A01X+038486Y+095212X0090Y0240     S1      
327m1535            R5627 -2          A01X+037601Y+093998X0198Y0197     S1      
327m1535            R819  -2   M      A01X+037601Y+094381X0198Y0197     S1      
317m1536            VIA   -    M      A01X+092360Y+058158X0200Y         S2      
017m1536            VIA   -    M      A18X+092360Y+058158X0260Y         S2      
017m1536                  -    MD0100PA00X+092360Y+058158                       
327m1536            U117  -B19        A01X+091229Y+058323X0110Y0180R090 S1      
327m1536            R4221 -1          A01X+092608Y+058158X0198Y0197     S1      
317FM_HSC_PWROK     VIA   -    MD0100PA00X+077726Y+144624X0200Y         S0      
327FM_HSC_PWROK     R6251 -1          A01X+076751Y+144978X0198Y0197R270 S1      
327FM_HSC_PWROK     R6249 -1   M      A01X+077471Y+144987X0198Y0197R180 S1      
327FM_HSC_PWROK     PU1   -13         A01X+079791Y+146140X0090Y0150     S1      
317FM_HSC_PWROK     VIA   -    M      A01X+079030Y+146346X0300Y    R270 S1      
017FM_HSC_PWROK     VIA   -    M      A18X+079030Y+146346X0200Y    R270 S1      
017FM_HSC_PWROK           -    MD0100PA00X+079030Y+146346                       
327FM_HSC_PWROK     R6250 -1   M      A18X+077437Y+145416X0198Y0197R090 S2      
317m1537            VIA   -    M      A01X+092979Y+082860X0200Y         S2      
017m1537            VIA   -    M      A18X+092979Y+082860X0260Y         S2      
017m1537                  -    MD0100PA00X+092979Y+082860                       
327m1537            U5    -B2         A01X+092389Y+084057X0160Y    R180 S1      
327m1537            R4850 -2          A01X+094392Y+081462X0198Y0197R090 S1      
327m1537            R4851 -1   M      A01X+093992Y+081462X0198Y0197R270 S1      
327m1537            C3609 -1   M      A01X+093592Y+081462X0198Y0197R270 S1      
327m1538            PU69  -11         A01X+124544Y+022506X0110Y0240     S1      
327m1538            R6091 -1          A01X+123250Y+013090X0198Y0197R270 S1      
327m1538            R5582 -1   M      A01X+122569Y+014775X0198Y0197R090 S1      
317m1538            VIA   -    MD0100PA00X+122235Y+015737X0200Y         S0      
327m1538            C2900 -1          A01X+123982Y+023286X0198Y0197R090 S1      
317m1538            VIA   -    M      A01X+124386Y+022865X0200Y    R090 S2      
017m1538            VIA   -    M      A18X+124386Y+022865X0260Y    R090 S2      
017m1538                  -    MD0100PA00X+124386Y+022865                       
327HSC_FAULT_N_1    VIA   -    M      A18X+087917Y+145955X0260Y         S2      
327HSC_FAULT_N_1    PU2   -5          A01X+087348Y+145357X0100Y0150R270 S1      
317HSC_FAULT_N_1    VIA   -    MD0100PA00X+087574Y+145357X0200Y         S0      
327HSC_FAULT_N_1    PR31  -1          A18X+088366Y+146085X0198Y0197R180 S2      
327m1539            VIA   -    M      A01X+092054Y+057061X0300Y    R180 S1      
327m1539            U117  -B14        A01X+091229Y+057339X0110Y0180R090 S1      
327m1539            R4223 -1          A01X+092608Y+057358X0198Y0197     S1      
327HSC_SCREF        PR37  -1          A01X+088367Y+147686X0198Y0197     S1      
317HSC_SCREF        VIA   -    MD0100PA00X+088124Y+147686X0200Y         S0      
327HSC_SCREF        PR28  -1          A01X+084217Y+146196X0198Y0197     S1      
317HSC_SCREF        VIA   -    MD0100PA00X+083974Y+146196X0200Y         S0      
327HSC_SCREF        PU1   -25         A01X+080322Y+144378X0090Y0150     S1      
317HSC_SCREF        VIA   -    M      A01X+079860Y+143167X0200Y    R270 S2      
017HSC_SCREF        VIA   -    M      A18X+079860Y+143167X0260Y    R270 S2      
017HSC_SCREF              -    MD0100PA00X+079860Y+143167                       
317m1540            VIA   -    M      A01X+093320Y+079830X0200Y         S2      
017m1540            VIA   -    M      A18X+093320Y+079830X0260Y         S2      
017m1540                  -    MD0100PA00X+093320Y+079830                       
327m1540            D7    -A          A01X+093212Y+080247X0240Y0280R090 S1      
327m1540            R4857 -2          A01X+093078Y+079827X0198Y0197     S1      
327m1541            VIA   -    M      A01X+123063Y+015486X0300Y         S1      
327m1541            U377  -D          A01X+124034Y+016196X0400Y0560     S1      
327m1541            R5582 -2          A01X+122569Y+015090X0198Y0197R090 S1      
327m1541            R5581 -2   M      A01X+122569Y+015486X0198Y0197R270 S1      
327m1542            VIA   -           A01X+089354Y+055839X0300Y         S1      
327m1542            U117  -A7         A01X+089900Y+056404X0070Y0220R180 S1      
327HSC_VOSEN        PR2   -1          A18X+080327Y+143624X0198Y0197R180 S2      
327HSC_VOSEN        PR6   -1   M      A18X+079934Y+143624X0198Y0197     S2      
327HSC_VOSEN        PU1   -24         A01X+080145Y+144378X0090Y0150     S1      
327HSC_VOSEN        PC3   -1          A01X+079942Y+143656X0198Y0197R180 S1      
317HSC_VOSEN        VIA   -    M      A01X+080061Y+144076X0200Y    R270 S2      
017HSC_VOSEN        VIA   -    M      A18X+080061Y+144076X0260Y    R270 S2      
017HSC_VOSEN              -    MD0100PA00X+080061Y+144076                       
317m1543            VIA   -    M      A01X+124428Y+014872X0200Y         S2      
017m1543            VIA   -    M      A18X+124428Y+014872X0260Y         S2      
017m1543                  -    MD0100PA00X+124428Y+014872                       
327m1543            U377  -G          A01X+123660Y+015330X0400Y0560     S1      
327m1543            R5583 -1          A01X+124715Y+014691X0198Y0197R270 S1      
327HSC_VDD_1        VIA   -    M      A18X+084365Y+144955X0260Y         S2      
327HSC_VDD_1        PR26  -1          A18X+084422Y+145416X0198Y0197     S2      
327HSC_VDD_1        PC10  -1   M      A01X+084954Y+145118X0198Y0197R090 S1      
317HSC_VDD_1        VIA   -    MD0100PA00X+084604Y+145146X0200Y         S0      
327HSC_VDD_1        PU2   -21         A01X+085586Y+145160X0100Y0150R270 S1      
327m1544            PU66  -11         A01X+114307Y+022506X0110Y0240     S1      
327m1544            R6090 -1          A01X+113014Y+013090X0198Y0197R270 S1      
327m1544            R5576 -1   M      A01X+112333Y+014775X0198Y0197R090 S1      
317m1544            VIA   -    MD0100PA00X+111999Y+015737X0200Y         S0      
317m1544            VIA   -    M      A01X+114150Y+022865X0200Y    R090 S2      
017m1544            VIA   -    M      A18X+114150Y+022865X0260Y    R090 S2      
017m1544                  -    MD0100PA00X+114150Y+022865                       
327m1544            C2897 -1          A01X+113746Y+023286X0198Y0197R090 S1      
327m1545            U94   -4          A01X+096889Y+109662X0090Y0240R090 S1      
317m1545            VIA   -    M      A01X+097278Y+110066X0200Y         S2      
017m1545            VIA   -    M      A18X+097278Y+110066X0260Y         S2      
017m1545                  -    MD0100PA00X+097278Y+110066                       
327m1545            R798  -2          A01X+097518Y+110066X0198Y0197R180 S1      
327m1546            VIA   -           A01X+087734Y+057441X0300Y         S1      
327m1546            U117  -A53        A01X+088473Y+057240X0070Y0220R090 S1      
327HSC_VDD          PR7   -2          A01X+083428Y+144085X0198Y0197     S1      
317HSC_VDD          VIA   -    MD0100PA00X+083670Y+144085X0200Y    R090 S0      
327HSC_VDD          PR35  -2          A18X+088367Y+145686X0198Y0197     S2      
327HSC_VDD          PR26  -2          A18X+084107Y+145416X0198Y0197     S2      
327HSC_VDD          PR8   -2          A18X+083390Y+145199X0198Y0197R270 S2      
317HSC_VDD          VIA   -    MD0100PA00X+088124Y+145686X0200Y         S0      
317HSC_VDD          VIA   -    M      A01X+083547Y+145740X0200Y         S2      
017HSC_VDD          VIA   -    M      A18X+083547Y+145740X0260Y         S2      
017HSC_VDD                -    MD0100PA00X+083547Y+145740                       
317HSC_VDD          VIA   -    MD0100PA00X+077772Y+145019X0200Y         S0      
327HSC_VDD          PR4   -2          A18X+078008Y+144619X0198Y0197     S2      
327HSC_VDD          PR14  -1   M      A18X+078063Y+145008X0198Y0197R270 S2      
327HSC_FAULT_N_2    PR40  -1          A01X+092187Y+145428X0198Y0197R090 S1      
327HSC_FAULT_N_2    PU3   -5          A01X+091548Y+145357X0100Y0150R270 S1      
317HSC_FAULT_N_2    VIA   -    MD0100PA00X+091774Y+145357X0200Y         S2      
317m1547            VIA   -    M      A01X+003251Y+018052X0200Y         S2      
017m1547            VIA   -    M      A18X+003251Y+018052X0260Y         S2      
017m1547                  -    MD0100PA00X+003251Y+018052                       
327m1547            R5539 -1          A01X+003251Y+017745X0198Y0197R180 S1      
327m1547            U363  -G          A01X+003942Y+017074X0400Y0560R270 S1      
327m1548            VIA   -    M      A01X+112827Y+015486X0300Y         S1      
327m1548            R5576 -2          A01X+112333Y+015090X0198Y0197R090 S1      
327m1548            R5575 -2   M      A01X+112333Y+015486X0198Y0197R270 S1      
327m1548            U375  -D          A01X+113798Y+016196X0400Y0560     S1      
327HSC_MODE         PR11  -1          A01X+083115Y+145452X0198Y0197     S1      
327HSC_MODE         PU1   -41         A01X+082128Y+145702X0090Y0150R270 S1      
317HSC_MODE         VIA   -    M      A01X+082636Y+145897X0200Y    R270 S2      
017HSC_MODE         VIA   -    M      A18X+082636Y+145897X0260Y    R270 S2      
017HSC_MODE               -    MD0100PA00X+082636Y+145897                       
317m1549            VIA   -    M      A01X+114192Y+014872X0200Y         S2      
017m1549            VIA   -    M      A18X+114192Y+014872X0260Y         S2      
017m1549                  -    MD0100PA00X+114192Y+014872                       
327m1549            U375  -G          A01X+113424Y+015330X0400Y0560     S1      
327m1549            R5577 -1          A01X+114479Y+014691X0198Y0197R270 S1      
327HSC_VINSEN       PR3   -2          A01X+080493Y+147662X0198Y0197R180 S1      
327HSC_VINSEN       PR5   -1          A18X+080200Y+147099X0198Y0197R270 S2      
317HSC_VINSEN       VIA   -    M      A01X+080758Y+146958X0200Y         S2      
017HSC_VINSEN       VIA   -    M      A18X+080758Y+146958X0260Y         S2      
017HSC_VINSEN             -    MD0100PA00X+080758Y+146958                       
327HSC_VINSEN       PC2   -1   M      A01X+080501Y+146951X0198Y0197R090 S1      
327HSC_VINSEN       PU1   -9          A01X+080499Y+146140X0090Y0150     S1      
327m1550            VIA   -    M      A01X+005028Y+017288X0300Y         S1      
327m1550            U363  -D          A01X+004808Y+016700X0400Y0560R270 S1      
327m1550            R5541 -2          A01X+004112Y+017761X0198Y0197     S1      
327m1550            R5540 -2   M      A01X+004533Y+017761X0198Y0197R180 S1      
327m1551            PU64  -11         A01X+104071Y+022506X0110Y0240     S1      
327m1551            R6079 -1          A01X+102778Y+013090X0198Y0197R270 S1      
327m1551            R5570 -1   M      A01X+102097Y+014775X0198Y0197R090 S1      
317m1551            VIA   -    MD0100PA00X+101763Y+015737X0200Y         S0      
327m1551            C2895 -1          A01X+103510Y+023286X0198Y0197R090 S1      
317m1551            VIA   -    M      A01X+103913Y+022865X0200Y    R090 S2      
017m1551            VIA   -    M      A18X+103913Y+022865X0260Y    R090 S2      
017m1551                  -    MD0100PA00X+103913Y+022865                       
317m1552            VIA   -    M      A01X+091781Y+054432X0200Y         S2      
017m1552            VIA   -    M      A18X+091781Y+054432X0260Y         S2      
017m1552                  -    MD0100PA00X+091781Y+054432                       
327m1552            Y7    -1          A01X+091998Y+054001X0480Y0590R270 S1      
327m1552            R4185 -1          A01X+091725Y+055154X0198Y0197R090 S1      
327m1552            C2791 -1   M      A01X+091781Y+054735X0198Y0197     S1      
327HSC_SCREF_2      PU3   -17         A01X+089781Y+145948X0100Y0140R270 S1      
327HSC_SCREF_2      PR37  -2          A01X+088682Y+147686X0198Y0197     S1      
327HSC_SCREF_2      VIA   -    M      A01X+089210Y+146760X0300Y         S1      
317m1553            VIA   -    M      A01X+181031Y+110482X0200Y         S2      
017m1553            VIA   -    M      A18X+181031Y+110482X0260Y         S2      
017m1553                  -    MD0100PA00X+181031Y+110482                       
327m1553            U95   -5          A01X+181031Y+109967X0090Y0240R180 S1      
327m1553            R808  -2          A01X+181916Y+110514X0198Y0197R180 S1      
317m1554            VIA   -    M      A01X+143774Y+068699X0200Y    R180 S2      
017m1554            VIA   -    M      A18X+143774Y+068699X0260Y    R180 S2      
017m1554                  -    MD0100PA00X+143774Y+068699                       
327m1554            R4711 -1          A01X+142358Y+068100X0198Y0197R180 S1      
327m1554            U346  -10         A01X+144198Y+068904X0160Y0540R270 S1      
327m1555            VIA   -           A01X+088794Y+055834X0300Y         S1      
327m1555            U117  -A6         A01X+089704Y+056404X0070Y0220R180 S1      
327HSC_SCREF_1      PU2   -17         A01X+085581Y+145948X0100Y0140R270 S1      
327HSC_SCREF_1      PR28  -2          A01X+084532Y+146196X0198Y0197     S1      
327HSC_SCREF_1      VIA   -    M      A01X+085074Y+146196X0300Y         S1      
327m1556            VIA   -    M      A01X+102591Y+015486X0300Y         S1      
327m1556            R5570 -2          A01X+102097Y+015090X0198Y0197R090 S1      
327m1556            R5569 -2   M      A01X+102097Y+015486X0198Y0197R270 S1      
327m1556            U373  -D          A01X+103562Y+016196X0400Y0560     S1      
317m1557            VIA   -    MD0100PA00X+091663Y+091524X0200Y         S0      
327m1557            R6192 -2          A01X+091663Y+092255X0198Y0197R270 S1      
327m1557            R4524 -2          A01X+091450Y+091258X0198Y0197R090 S1      
317m1557            VIA   -    M      A01X+097030Y+085377X0200Y         S2      
017m1557            VIA   -    M      A18X+097030Y+085377X0260Y         S2      
017m1557                  -    MD0100PA00X+097030Y+085377                       
317m1557            VIA   -    MD0100PA00X+132636Y+085822X0180Y         S0      
327m1557            U6    -N5         A01X+132793Y+085979X0160Y         S1      
327m1558            VIA   -    M      A01X+088941Y+054491X0300Y         S1      
327m1558            R4218 -1          A01X+088593Y+053964X0198Y0197R270 S1      
327m1558            U117  -B8         A01X+090392Y+056699X0110Y0180R180 S1      
317FM_HSC_FAULT_N   VIA   -    M      A01X+099860Y+136920X0200Y         S2      
017FM_HSC_FAULT_N   VIA   -    M      A18X+099860Y+136920X0260Y         S2      
017FM_HSC_FAULT_N         -    MD0100PA00X+099860Y+136920                       
327FM_HSC_FAULT_N   PR7161-2          A18X+099378Y+136920X0198Y0197R180 S2      
327FM_HSC_FAULT_N   R492  -2          A01X+083428Y+144885X0198Y0197     S1      
317FM_HSC_FAULT_N   VIA   -    MD0100PA00X+083670Y+144885X0200Y    R270 S0      
327FM_HSC_FAULT_N   U340  -1          A01X+075980Y+159501X0220Y0530     S1      
317FM_HSC_FAULT_N   VIA   -    MD0100PA00X+075980Y+159086X0200Y         S0      
327m1559            VIA   -    M      A01X+092867Y+070324X0300Y         S1      
327m1559            R4257 -1          A01X+092402Y+070411X0198Y0197R180 S1      
327m1559            U327  -2          A01X+092867Y+069688X0220Y0530R180 S1      
317m1560            VIA   -    M      A01X+103955Y+014872X0200Y         S2      
017m1560            VIA   -    M      A18X+103955Y+014872X0260Y         S2      
017m1560                  -    MD0100PA00X+103955Y+014872                       
327m1560            R5571 -1          A01X+104242Y+014691X0198Y0197R270 S1      
327m1560            U373  -G          A01X+103188Y+015330X0400Y0560     S1      
327m1561            R6189 -2          A01X+092863Y+092255X0198Y0197R270 S1      
327m1561            R4521 -2          A01X+092863Y+091266X0198Y0197R090 S1      
317m1561            VIA   -    MD0100PA00X+092863Y+091524X0200Y         S0      
317m1561            VIA   -    M      A01X+099409Y+082900X0200Y         S2      
017m1561            VIA   -    M      A18X+099409Y+082900X0260Y         S2      
017m1561                  -    MD0100PA00X+099409Y+082900                       
327m1561            U6    -T3         A01X+132163Y+085034X0160Y         S1      
317m1561            VIA   -    MD0100PA00X+132006Y+084877X0180Y         S0      
327m1562            PU1   -12         A01X+079968Y+146140X0090Y0150     S1      
317m1562            VIA   -    M      A01X+079400Y+146418X0200Y    R270 S2      
017m1562            VIA   -    M      A18X+079400Y+146418X0260Y    R270 S2      
017m1562                  -    MD0100PA00X+079400Y+146418                       
327m1562            R6246 -2          A01X+051384Y+096993X0198Y0197     S1      
317m1562            VIA   -    MD0100PA00X+084406Y+101174X0200Y         S0      
317m1562            VIA   -    MD0100PA00X+088734Y+131499X0200Y         S0      
317m1562            VIA   -    MD0100PA00X+076571Y+143736X0200Y         S0      
327m1562            PJ1   -2          A01X+074753Y+144166X0400Y1090R270 S1      
317m1563            VIA   -    MD0100PA00X+137100Y+081162X0200Y         S0      
317m1563            VIA   -    M      A01X+091325Y+071420X0200Y         S2      
017m1563            VIA   -    M      A18X+091325Y+071420X0260Y         S2      
017m1563                  -    MD0100PA00X+091325Y+071420                       
327m1563            R4257 -2          A01X+092088Y+070411X0198Y0197R180 S1      
327m1563            D12   -2          A01X+091836Y+072057X0320Y0340R180 S1      
327m1563            R2966 -2          A18X+137350Y+081642X0198Y0197R090 S2      
327m1564            PU62  -11         A01X+093902Y+021023X0110Y0240     S1      
327m1564            R6078 -1          A01X+092542Y+013090X0198Y0197R270 S1      
327m1564            R5564 -1   M      A01X+091861Y+014775X0198Y0197R090 S1      
317m1564            VIA   -    MD0100PA00X+091527Y+015737X0200Y         S0      
317m1564            VIA   -    M      A01X+093744Y+021382X0200Y    R090 S2      
017m1564            VIA   -    M      A18X+093744Y+021382X0260Y    R090 S2      
017m1564                  -    MD0100PA00X+093744Y+021382                       
327m1564            C2893 -1          A18X+093743Y+020830X0198Y0197R090 S2      
317m1565            VIA   -    MD0100PA00X+092063Y+091524X0200Y         S0      
327m1565            R6191 -2          A01X+092063Y+092255X0198Y0197R270 S1      
327m1565            R4523 -2          A01X+091810Y+091258X0198Y0197R090 S1      
317m1565            VIA   -    M      A01X+097444Y+084914X0200Y         S2      
017m1565            VIA   -    M      A18X+097444Y+084914X0260Y         S2      
017m1565                  -    MD0100PA00X+097444Y+084914                       
317m1565            VIA   -    MD0100PA00X+132636Y+085507X0180Y         S0      
327m1565            U6    -P5         A01X+132793Y+085664X0160Y         S1      
327m1566            VIA   -    M      A01X+092087Y+057576X0300Y    R180 S1      
327m1566            U117  -B15        A01X+091229Y+057536X0110Y0180R090 S1      
327m1566            R4222 -1          A01X+092608Y+057758X0198Y0197     S1      
327HSC_CS           PR15  -2          A01X+078332Y+143543X0198Y0197     S1      
327HSC_CS           PU1   -20         A01X+079579Y+144816X0090Y0150R270 S1      
317HSC_CS           VIA   -    M      A01X+078769Y+144275X0200Y    R270 S2      
017HSC_CS           VIA   -    M      A18X+078769Y+144275X0260Y    R270 S2      
017HSC_CS                 -    MD0100PA00X+078769Y+144275                       
327m1567            PU54  -11         A01X+002418Y+022506X0110Y0240     S1      
317m1567            VIA   -    M      A01X+002260Y+022865X0200Y    R090 S2      
017m1567            VIA   -    M      A18X+002260Y+022865X0260Y    R090 S2      
017m1567                  -    MD0100PA00X+002260Y+022865                       
327m1567            C2885 -1          A01X+001883Y+023290X0198Y0197R090 S1      
317m1567            VIA   -    MD0100PA00X+001671Y+017594X0200Y         S0      
327m1567            R5541 -1          A01X+003796Y+017761X0198Y0197     S1      
327m1567            R5866 -1          A01X+001671Y+017338X0198Y0197R270 S1      
317m1568            VIA   -    MD0100PA00X+092463Y+091524X0200Y         S0      
327m1568            R6190 -2          A01X+092463Y+092255X0198Y0197R270 S1      
327m1568            R4522 -2          A01X+092463Y+091266X0198Y0197R090 S1      
317m1568            VIA   -    M      A01X+104302Y+078216X0200Y         S2      
017m1568            VIA   -    M      A18X+104302Y+078216X0260Y         S2      
017m1568                  -    MD0100PA00X+104302Y+078216                       
327m1568            U6    -P7         A01X+133423Y+085664X0160Y         S1      
317m1568            VIA   -    MD0100PA00X+133265Y+085507X0180Y         S0      
327m1569            U117  -A11        A01X+090688Y+056404X0070Y0220R180 S1      
327m1569            VIA   -    M      A01X+090371Y+054438X0300Y    R180 S1      
327m1569            R4191 -1          A01X+089993Y+053964X0198Y0197R270 S1      
327m1569            R4202 -2   M      A01X+090343Y+053964X0198Y0197R090 S1      
327RST_FPGA_BIC_N   VIA   -    M      A18X+137548Y+082474X0260Y         S2      
327RST_FPGA_BIC_N   R5503 -2          A18X+137800Y+081958X0198Y0197R270 S2      
327RST_FPGA_BIC_N   R2966 -1   M      A18X+137350Y+081958X0198Y0197R090 S2      
327RST_FPGA_BIC_N   U6    -W19        A01X+137202Y+084089X0160Y         S1      
317RST_FPGA_BIC_N   VIA   -    MD0100PA00X+137360Y+083932X0180Y         S0      
327m1570            VIA   -    M      A01X+092354Y+015486X0300Y         S1      
327m1570            U371  -D          A01X+093326Y+016196X0400Y0560     S1      
327m1570            R5564 -2          A01X+091861Y+015090X0198Y0197R090 S1      
327m1570            R5563 -2   M      A01X+091861Y+015486X0198Y0197R270 S1      
317m1571            VIA   -    M      A01X+093719Y+014872X0200Y         S2      
017m1571            VIA   -    M      A18X+093719Y+014872X0260Y         S2      
017m1571                  -    MD0100PA00X+093719Y+014872                       
327m1571            R5565 -1          A01X+094006Y+014691X0198Y0197R270 S1      
327m1571            U371  -G          A01X+092952Y+015330X0400Y0560     S1      
317m1572            VIA   -    M      A01X+087529Y+057870X0200Y         S2      
017m1572            VIA   -    M      A18X+087529Y+057870X0260Y         S2      
017m1572                  -    MD0100PA00X+087529Y+057870                       
327m1572            R4193 -1          A01X+087264Y+057470X0198Y0197R180 S1      
327m1572            R4204 -2   M      A01X+087264Y+057870X0198Y0197     S1      
327m1572            U117  -B42        A01X+088768Y+057339X0110Y0180R090 S1      
317m1573            VIA   -    M      A01X+091373Y+055050X0200Y         S2      
017m1573            VIA   -    M      A18X+091373Y+055050X0260Y         S2      
017m1573                  -    MD0100PA00X+091373Y+055050                       
327m1573            U117  -B11        A01X+090983Y+056699X0110Y0180R180 S1      
327m1573            Y7    -3          A01X+091163Y+053371X0480Y0590R270 S1      
327m1573            C2792 -1   M      A01X+091373Y+054735X0198Y0197R180 S1      
327HP_NIC3_EN       PU52  -11         A01X+083808Y+047548X0110Y0240R270 S1      
327HP_NIC3_EN       R197  -2   M      A01X+078037Y+055014X0198Y0197R270 S1      
327HP_NIC3_EN       U24   -D          A01X+078977Y+055138X0400Y0560R180 S1      
317HP_NIC3_EN       VIA   -    MD0100PA00X+078143Y+054502X0200Y    R180 S0      
327HP_NIC3_EN       R5955 -1          A01X+080454Y+044833X0198Y0197     S1      
317HP_NIC3_EN       VIA   -    M      A01X+080214Y+044833X0200Y         S2      
017HP_NIC3_EN       VIA   -    M      A18X+080214Y+044833X0260Y         S2      
017HP_NIC3_EN             -    MD0100PA00X+080214Y+044833                       
327HP_NIC3_EN       C2883 -1          A01X+084518Y+048238X0198Y0197     S1      
317HP_NIC3_EN       VIA   -    MD0100PA00X+084248Y+048238X0200Y         S0      
327HP_NIC3_EN       R4456 -1          A01X+089774Y+038570X0198Y0197R090 S1      
327HP_NIC3_EN       R949  -1          A01X+093907Y+044094X0198Y0197R180 S1      
317HP_NIC3_EN       VIA   -    MD0100PA00X+094187Y+044094X0200Y    R270 S0      
317HP_NIC3_EN       VIA   -    MD0100PA00X+089774Y+038312X0200Y    R270 S0      
327REV_ID0          VIA   -    M      A01X+088915Y+089644X0300Y    R090 S1      
327REV_ID0          R4547 -2          A01X+088063Y+090951X0198Y0197R270 S1      
327REV_ID0          R4544 -1   M      A01X+088463Y+090951X0198Y0197R090 S1      
327REV_ID0          U5    -R11        A01X+089554Y+088151X0160Y    R180 S1      
327m1574            C3608 -1          A18X+091444Y+085317X0164Y0164     S2      
327m1574            C3607 -1          A18X+091759Y+085317X0164Y0164R180 S2      
327m1574            U5    -F5         A01X+091444Y+085317X0160Y    R180 S1      
317m1574            VIA   -    MD0100PA00X+091601Y+085159X0180Y    R270 S0      
327m1574            VIA   -           A18X+093334Y+082186X0260Y         S2      
317m1574            VIA   -    MD0100PA00X+093242Y+082514X0200Y         S0      
317m1574            VIA   -    MD0100PA00X+093526Y+082514X0200Y         S0      
327m1574            L147  -2          A18X+093944Y+082529X0280Y0320     S2      
327m1575            R4803 -1          A01X+132458Y+056650X0198Y0197R180 S1      
327m1575            R4790 -2   M      A01X+132458Y+056250X0198Y0197     S1      
327m1575            R4836 -2          A01X+132942Y+056250X0198Y0197R180 S1      
317m1575            VIA   -    M      A01X+132700Y+056250X0200Y         S2      
017m1575            VIA   -    M      A18X+132700Y+056250X0260Y         S2      
017m1575                  -    MD0100PA00X+132700Y+056250                       
327m1575            U6    -L6         A01X+133108Y+086609X0160Y         S1      
317m1575            VIA   -    MD0100PA00X+132950Y+086766X0180Y         S0      
327m1576            C3606 -1          A18X+091444Y+084687X0164Y0164     S2      
327m1576            C3605 -1          A18X+091759Y+084687X0164Y0164R180 S2      
317m1576            VIA   -    MD0100PA00X+093305Y+084380X0200Y         S0      
317m1576            VIA   -    MD0100PA00X+093302Y+084089X0200Y         S0      
327m1576            VIA   -           A18X+093063Y+084239X0260Y         S2      
327m1576            L146  -2          A18X+093623Y+084395X0280Y0320R090 S2      
327m1576            U5    -E5         A01X+091444Y+085002X0160Y    R180 S1      
317m1576            VIA   -    MD0100PA00X+091601Y+084844X0180Y    R270 S0      
327ADM1085_ENOUT    R3148 -1   M      A01X+090689Y+068777X0198Y0197     S1      
327ADM1085_ENOUT    D23   -1          A01X+089729Y+068440X0320Y0340     S1      
327ADM1085_ENOUT    R3149 -2   M      A01X+090689Y+068377X0198Y0197R180 S1      
317ADM1085_ENOUT    VIA   -    M      A01X+090224Y+068933X0300Y         S1      
017ADM1085_ENOUT    VIA   -    M      A18X+090224Y+068933X0200Y         S1      
017ADM1085_ENOUT          -    MD0100PA00X+090224Y+068933                       
327ADM1085_ENOUT    U359  -4          A01X+089575Y+069156X0140Y0580R270 S1      
327ADM1085_ENOUT    R3150 -1   M      A01X+090689Y+069177X0198Y0197     S1      
327ADM1085_ENOUT    U450  -4          A18X+089398Y+069608X0110Y0200R270 S2      
327m1577            U85   -4          A01X+144181Y+059336X0090Y0240R180 S1      
327m1577            R754  -2          A01X+143494Y+059965X0198Y0197R270 S1      
317m1577            VIA   -    M      A01X+143494Y+059713X0200Y    R090 S2      
017m1577            VIA   -    M      A18X+143494Y+059713X0260Y    R090 S2      
017m1577                  -    MD0100PA00X+143494Y+059713                       
327m1577            R5624 -2          A18X+144196Y+060108X0198Y0197     S2      
317m1578            VIA   -    MD0100PA00X+132006Y+087081X0180Y         S0      
327m1578            U6    -K3         A01X+132163Y+086924X0160Y         S1      
327m1578            R6196 -2          A18X+092863Y+092255X0198Y0197R090 S2      
327m1578            R4528 -2          A18X+092729Y+091191X0198Y0197R270 S2      
317m1578            VIA   -    M      A01X+092863Y+091804X0200Y         S2      
017m1578            VIA   -    M      A18X+092863Y+091804X0260Y         S2      
017m1578                  -    MD0100PA00X+092863Y+091804                       
317m1578            VIA   -    MD0100PA00X+100458Y+085368X0200Y         S0      
327m1579            VIA   -    M      A01X+087906Y+058283X0300Y    R180 S1      
327m1579            R4192 -1          A01X+087264Y+058683X0198Y0197R180 S1      
327m1579            U117  -B38        A01X+088768Y+058126X0110Y0180R090 S1      
327m1579            R4203 -2   M      A01X+087264Y+058283X0198Y0197     S1      
317m1580            VIA   -    MD0100PA00X+132320Y+087081X0180Y         S0      
327m1580            U6    -K4         A01X+132478Y+086924X0160Y         S1      
327m1580            R4833 -2          A01X+132942Y+057450X0198Y0197R180 S1      
327m1580            R4795 -2          A01X+132458Y+057450X0198Y0197     S1      
317m1580            VIA   -    M      A01X+132704Y+057335X0200Y         S2      
017m1580            VIA   -    M      A18X+132704Y+057335X0260Y         S2      
017m1580                  -    MD0100PA00X+132704Y+057335                       
327m1581            VIA   -    M      A01X+087945Y+056886X0300Y    R180 S1      
327m1581            U117  -A54        A01X+088473Y+057044X0070Y0220R090 S1      
327m1581            R4206 -2          A01X+087264Y+056670X0198Y0197     S1      
317m1582            VIA   -    M      A01X+134205Y+067034X0200Y    R180 S2      
017m1582            VIA   -    M      A18X+134205Y+067034X0260Y    R180 S2      
017m1582                  -    MD0100PA00X+134205Y+067034                       
327m1582            R4769 -1          A01X+133258Y+066950X0198Y0197R180 S1      
327m1582            U348  -5          A01X+135098Y+067034X0160Y0540R270 S1      
317m1583            VIA   -    MD0080PA00X+074242Y+120423X0160Y         S0      
327m1583            PEX1  -P39        A01X+074429Y+120610X0180Y         S1      
317m1583            VIA   -    M      A01X+079902Y+117598X0200Y         S2      
017m1583            VIA   -    M      A18X+079902Y+117598X0260Y         S2      
017m1583                  -    MD0100PA00X+079902Y+117598                       
327m1583            R6392 -2          A01X+080256Y+118505X0198Y0197R090 S1      
317ADM1085_CEXT     VIA   -    MD0100PA00X+088490Y+069668X0200Y         S0      
327ADM1085_CEXT     VIA   -    M      A01X+087589Y+068222X0300Y         S1      
327ADM1085_CEXT     D23   -2          A01X+088869Y+068440X0320Y0340R180 S1      
327ADM1085_CEXT     R3144 -1   M      A01X+088184Y+069897X0198Y0197R180 S1      
327ADM1085_CEXT     U359  -1          A01X+088930Y+069668X0140Y0580R270 S1      
327ADM1085_CEXT     R3145 -2   M      A01X+088184Y+069497X0198Y0197     S1      
327ADM1085_CEXT     U450  -1          A18X+089101Y+069214X0120Y0210R270 S2      
317m1584            VIA   -    M      A01X+134653Y+066778X0200Y    R180 S2      
017m1584            VIA   -    M      A18X+134653Y+066778X0260Y    R180 S2      
017m1584                  -    MD0100PA00X+134653Y+066778                       
327m1584            R4770 -1          A01X+133258Y+066550X0198Y0197R180 S1      
327m1584            U348  -6          A01X+135098Y+066778X0160Y0540R270 S1      
317m1585            VIA   -    MD0080PA00X+073868Y+120049X0160Y         S0      
327m1585            R6393 -2          A01X+079384Y+113713X0198Y0197R270 S1      
327m1585            PEX1  -T38        A01X+074055Y+119862X0180Y         S1      
317m1585            VIA   -    M      A01X+079228Y+117306X0200Y         S2      
017m1585            VIA   -    M      A18X+079228Y+117306X0260Y         S2      
017m1585                  -    MD0100PA00X+079228Y+117306                       
327m1586            U313  -6   M      A01X+035557Y+114684X0170Y0460     S1      
317m1586            VIA   -    M      A01X+035442Y+115754X0200Y         S2      
017m1586            VIA   -    M      A18X+035442Y+115754X0260Y         S2      
017m1586                  -    MD0100PA00X+035442Y+115754                       
327m1586            R3873 -1          A01X+035078Y+117112X0198Y0197     S1      
327m1586            R3880 -2   M      A01X+035375Y+114028X0198Y0197R090 S1      
327m1586            R3892 -2   M      A01X+034975Y+114028X0198Y0197R090 S1      
327m1586            R3878 -1          A01X+034575Y+114028X0198Y0197R270 S1      
317m1587            VIA   -    M      A01X+134653Y+071478X0200Y    R180 S2      
017m1587            VIA   -    M      A18X+134653Y+071478X0260Y    R180 S2      
017m1587                  -    MD0100PA00X+134653Y+071478                       
327m1587            R4751 -1          A01X+133258Y+071250X0198Y0197R180 S1      
327m1587            U347  -6          A01X+135098Y+071478X0160Y0540R270 S1      
327m1588            R4802 -1          A01X+132458Y+058250X0198Y0197R180 S1      
327m1588            R4789 -2   M      A01X+132458Y+057850X0198Y0197     S1      
327m1588            R4832 -2          A01X+132942Y+057850X0198Y0197R180 S1      
317m1588            VIA   -    M      A01X+132700Y+057850X0200Y         S2      
017m1588            VIA   -    M      A18X+132700Y+057850X0260Y         S2      
017m1588                  -    MD0100PA00X+132700Y+057850                       
317m1588            VIA   -    MD0100PA00X+132636Y+087081X0180Y         S0      
327m1588            U6    -K5         A01X+132793Y+086924X0160Y         S1      
317m1589            VIA   -    M      A01X+087695Y+057142X0200Y         S2      
017m1589            VIA   -    M      A18X+087695Y+057142X0260Y         S2      
017m1589                  -    MD0100PA00X+087695Y+057142                       
327m1589            U117  -B43        A01X+088768Y+057142X0110Y0180R090 S1      
327m1589            R4207 -2          A01X+087264Y+057070X0198Y0197     S1      
317m1590            VIA   -    MD0100PA00X+143100Y+059100X0200Y         S0      
327m1590            R764  -2          A18X+143044Y+059965X0198Y0197R090 S2      
317m1590            VIA   -    MD0100PA00X+175088Y+054194X0200Y         S0      
317m1590            VIA   -    MD0100PA00X+174418Y+038397X0200Y         S0      
327m1590            R5623 -2   M      A01X+174175Y+038272X0198Y0197R090 S1      
327m1590            U86   -5          A01X+173627Y+039157X0090Y0240R090 S1      
317m1590            VIA   -    M      A01X+174142Y+039157X0200Y    R270 S2      
017m1590            VIA   -    M      A18X+174142Y+039157X0260Y    R270 S2      
017m1590                  -    MD0100PA00X+174142Y+039157                       
317m1591            VIA   -    M      A01X+142900Y+068500X0200Y    R180 S2      
017m1591            VIA   -    M      A18X+142900Y+068500X0260Y    R180 S2      
017m1591                  -    MD0100PA00X+142900Y+068500                       
327m1591            U346  -9          A01X+144198Y+069160X0160Y0540R270 S1      
327m1591            R4710 -1          A01X+142358Y+068500X0198Y0197R180 S1      
327m1592            R4837 -2          A01X+132942Y+055850X0198Y0197R180 S1      
327m1592            R4796 -2          A01X+132458Y+055850X0198Y0197     S1      
317m1592            VIA   -    M      A01X+132699Y+055679X0200Y         S2      
017m1592            VIA   -    M      A18X+132699Y+055679X0260Y         S2      
017m1592                  -    MD0100PA00X+132699Y+055679                       
327m1592            U6    -L5         A01X+132793Y+086609X0160Y         S1      
317m1592            VIA   -    MD0100PA00X+132636Y+086766X0180Y         S0      
327m1593            VIA   -    M      A01X+090511Y+055177X0300Y    R180 S1      
327m1593            U117  -B9         A01X+090589Y+056699X0110Y0180R180 S1      
327m1593            R4190 -1          A01X+089293Y+053964X0198Y0197R270 S1      
327m1593            R4201 -2   M      A01X+089643Y+053964X0198Y0197R090 S1      
327JTAG_BIC_TDI     R5279 -2          A01X+089192Y+080646X0198Y0197R090 S1      
317JTAG_BIC_TDI     VIA   -    M      A01X+089505Y+082855X0200Y         S2      
017JTAG_BIC_TDI     VIA   -    M      A18X+089505Y+082855X0280Y         S2      
017JTAG_BIC_TDI           -    MD0100PA00X+089505Y+082855                       
327JTAG_BIC_TDI     U5    -C10        A01X+089869Y+084372X0160Y    R180 S1      
317JTAG_BIC_TDI     VIA   -    MD0100PA00X+089712Y+084214X0180Y         S0      
327m1594            U313  -7   M      A01X+035813Y+114684X0170Y0460     S1      
317m1594            VIA   -    M      A01X+036088Y+115740X0200Y         S2      
017m1594            VIA   -    M      A18X+036088Y+115740X0260Y         S2      
017m1594                  -    MD0100PA00X+036088Y+115740                       
327m1594            R3874 -1          A01X+036097Y+117037X0198Y0197R180 S1      
327m1594            R3879 -2   M      A01X+035775Y+114028X0198Y0197R090 S1      
327m1594            R3877 -1          A01X+036575Y+114028X0198Y0197R270 S1      
327m1594            R3891 -2   M      A01X+036175Y+114028X0198Y0197R090 S1      
317m1595            VIA   -    M      A01X+134205Y+071734X0200Y    R180 S2      
017m1595            VIA   -    M      A18X+134205Y+071734X0260Y    R180 S2      
017m1595                  -    MD0100PA00X+134205Y+071734                       
327m1595            R4750 -1          A01X+133258Y+071650X0198Y0197R180 S1      
327m1595            U347  -5          A01X+135098Y+071734X0160Y0540R270 S1      
317PRSNT_NIC4_R_N   VIA   -    MD0100PA00X+119576Y+098813X0200Y         S0      
317PRSNT_NIC4_R_N   VIA   -    MD0100PA00X+137990Y+087396X0180Y         S0      
317PRSNT_NIC4_R_N   VIA   -    MD0100PA00X+092546Y+087994X0180Y    R270 S0      
327PRSNT_NIC4_R_N   U5    -P2         A01X+092389Y+087836X0160Y    R180 S1      
317PRSNT_NIC4_R_N   VIA   -    MD0100PA00X+092680Y+096630X0200Y         S0      
327PRSNT_NIC4_R_N   U6    -J21        A01X+137832Y+087239X0160Y         S1      
327PRSNT_NIC4_R_N   C4002 -1          A01X+104141Y+044866X0198Y0197R270 S1      
327PRSNT_NIC4_R_N   R247  -1   M      A01X+104141Y+045251X0198Y0197R090 S1      
327PRSNT_NIC4_R_N   U29   -G   M      A01X+104727Y+045075X0400Y0560     S1      
317PRSNT_NIC4_R_N   VIA   -    M      A01X+105955Y+045871X0200Y         S2      
017PRSNT_NIC4_R_N   VIA   -    M      A18X+105955Y+045871X0260Y         S2      
017PRSNT_NIC4_R_N         -    MD0100PA00X+105955Y+045871                       
317m1596            VIA   -    MD0100PA00X+149262Y+083732X0200Y         S0      
327m1596            R3880 -1          A01X+035375Y+113713X0198Y0197R090 S1      
317m1596            VIA   -    MD0100PA00X+035375Y+113473X0200Y         S0      
317m1596            VIA   -    M      A01X+038246Y+101243X0200Y         S2      
017m1596            VIA   -    M      A18X+038246Y+101243X0260Y         S2      
017m1596                  -    MD0100PA00X+038246Y+101243                       
327m1596            U343  -23         A01X+148202Y+083902X0160Y0540R270 S1      
327m1596            U344  -23         A01X+146502Y+075352X0160Y0540R270 S1      
317m1596            VIA   -    MD0100PA00X+147400Y+075309X0200Y         S0      
327PRSNT_NIC1_R_N   U6    -E22        A01X+138147Y+088499X0160Y         S1      
317PRSNT_NIC1_R_N   VIA   -    MD0100PA00X+091916Y+087994X0180Y    R270 S0      
327PRSNT_NIC1_R_N   U5    -P4         A01X+091759Y+087836X0160Y    R180 S1      
317PRSNT_NIC1_R_N   VIA   -    MD0100PA00X+092823Y+095112X0200Y         S0      
317PRSNT_NIC1_R_N   VIA   -    MD0100PA00X+138305Y+088656X0180Y         S0      
317PRSNT_NIC1_R_N   VIA   -    M      A01X+032746Y+055006X0200Y    R180 S2      
017PRSNT_NIC1_R_N   VIA   -    M      A18X+032746Y+055006X0260Y    R180 S2      
017PRSNT_NIC1_R_N         -    MD0100PA00X+032746Y+055006                       
327PRSNT_NIC1_R_N   C3999 -1          A01X+034228Y+056214X0198Y0197R090 S1      
327PRSNT_NIC1_R_N   U14   -G   M      A01X+033642Y+056004X0400Y0560R180 S1      
327PRSNT_NIC1_R_N   R94   -1   M      A01X+034228Y+055829X0198Y0197R270 S1      
317PRSNT_NIC1_R_N   VIA   -    MD0100PA00X+059846Y+050468X0200Y         S0      
317PRSNT_NIC1_R_N   VIA   -    MD0100PA00X+082729Y+053310X0200Y         S0      
317PRSNT_NIC1_R_N   VIA   -    MD0100PA00X+037688Y+051856X0200Y         S0      
317m1597            VIA   -    M      A01X+091430Y+055814X0200Y         S2      
017m1597            VIA   -    M      A18X+091430Y+055814X0260Y         S2      
017m1597                  -    MD0100PA00X+091430Y+055814                       
327m1597            U117  -A13        A01X+091082Y+056404X0070Y0220R180 S1      
327m1597            R4185 -2          A01X+091725Y+055470X0198Y0197R090 S1      
317m1598            VIA   -    M      A01X+137842Y+055880X0200Y         S2      
017m1598            VIA   -    M      A18X+137842Y+055880X0260Y         S2      
017m1598                  -    MD0100PA00X+137842Y+055880                       
327m1598            U350  -13         A01X+137402Y+056103X0240Y0540R270 S1      
327m1598            R4839 -1          A01X+138517Y+056100X0198Y0197     S1      
327PRSNT_NIC5_R_N   R298  -1   M      A01X+125646Y+055829X0198Y0197R270 S1      
327PRSNT_NIC5_R_N   C4003 -1          A01X+125646Y+056214X0198Y0197R090 S1      
327PRSNT_NIC5_R_N   U34   -G   M      A01X+125060Y+056004X0400Y0560R180 S1      
317PRSNT_NIC5_R_N   VIA   -    MD0100PA00X+124163Y+055006X0200Y    R180 S0      
327PRSNT_NIC5_R_N   U6    -L17        A01X+136572Y+086609X0160Y         S1      
317PRSNT_NIC5_R_N   VIA   -    MD0100PA00X+136730Y+086766X0180Y         S0      
317PRSNT_NIC5_R_N   VIA   -    MD0100PA00X+092329Y+096578X0200Y         S0      
327PRSNT_NIC5_R_N   U5    -P3         A01X+092074Y+087836X0160Y    R180 S1      
317PRSNT_NIC5_R_N   VIA   -    MD0100PA00X+092231Y+087994X0180Y    R270 S0      
317PRSNT_NIC5_R_N   VIA   -    M      A01X+138356Y+055439X0200Y         S2      
017PRSNT_NIC5_R_N   VIA   -    M      A18X+138356Y+055439X0260Y         S2      
017PRSNT_NIC5_R_N         -    MD0100PA00X+138356Y+055439                       
327m1599            VIA   -    M      A01X+071321Y+062079X0300Y         S1      
327m1599            R2474 -1          A01X+070836Y+062079X0198Y0197R090 S1      
327m1599            J23   -A70        A01X+072739Y+062344X0140Y0480R090 S1      
327m1600            U81   -4          A01X+052763Y+059336X0090Y0240R180 S1      
327m1600            R710  -2          A01X+052077Y+059965X0198Y0197R270 S1      
317m1600            VIA   -    M      A01X+052077Y+059713X0200Y    R090 S2      
017m1600            VIA   -    M      A18X+052077Y+059713X0260Y    R090 S2      
017m1600                  -    MD0100PA00X+052077Y+059713                       
327m1600            R5622 -2          A18X+052591Y+060079X0198Y0197     S2      
317m1601            VIA   -    MD0100PA00X+148696Y+083646X0200Y         S0      
317m1601            VIA   -    MD0100PA00X+035775Y+113473X0200Y         S0      
327m1601            R3879 -1          A01X+035775Y+113713X0198Y0197R090 S1      
317m1601            VIA   -    M      A01X+038371Y+100728X0200Y         S2      
017m1601            VIA   -    M      A18X+038371Y+100728X0260Y         S2      
017m1601                  -    MD0100PA00X+038371Y+100728                       
327m1601            U343  -22         A01X+148202Y+083646X0160Y0540R270 S1      
327m1601            U344  -22         A01X+146502Y+075096X0160Y0540R270 S1      
317m1601            VIA   -    MD0100PA00X+146996Y+075096X0200Y         S0      
327m1602            U314  -5          A01X+080980Y+114684X0240Y0460     S1      
317m1602            VIA   -    M      A01X+080963Y+114267X0200Y         S2      
017m1602            VIA   -    M      A18X+080963Y+114267X0260Y         S2      
017m1602                  -    MD0100PA00X+080963Y+114267                       
327m1602            R3948 -2          A01X+079884Y+114028X0198Y0197R090 S1      
317m1603            VIA   -    M      A01X+137842Y+060530X0200Y         S2      
017m1603            VIA   -    M      A18X+137842Y+060530X0260Y         S2      
017m1603                  -    MD0100PA00X+137842Y+060530                       
327m1603            U349  -13         A01X+137402Y+060753X0240Y0540R270 S1      
327m1603            R4820 -1          A01X+138517Y+060750X0198Y0197     S1      
317m1604            VIA   -    MD0100PA00X+132006Y+085192X0180Y         S0      
327m1604            U6    -R3         A01X+132163Y+085349X0160Y         S1      
317m1604            VIA   -    M      A01X+132700Y+070050X0200Y         S2      
017m1604            VIA   -    M      A18X+132700Y+070050X0260Y         S2      
017m1604                  -    MD0100PA00X+132700Y+070050                       
327m1604            R4754 -2          A01X+132942Y+070050X0198Y0197R180 S1      
327m1604            R4740 -1          A01X+132458Y+070450X0198Y0197R180 S1      
327m1604            R4725 -2   M      A01X+132458Y+070050X0198Y0197     S1      
317m1605            VIA   -    M      A01X+133929Y+061496X0200Y    R180 S2      
017m1605            VIA   -    M      A18X+133929Y+061496X0260Y    R180 S2      
017m1605                  -    MD0100PA00X+133929Y+061496                       
327m1605            R4816 -1          A01X+133258Y+061300X0198Y0197R180 S1      
327m1605            U349  -8          A01X+135098Y+061816X0160Y0540R270 S1      
317PRSNT_NIC3_R_N   VIA   -    M      A01X+090981Y+096240X0200Y         S2      
017PRSNT_NIC3_R_N   VIA   -    M      A18X+090981Y+096240X0260Y         S2      
017PRSNT_NIC3_R_N         -    MD0100PA00X+090981Y+096240                       
327PRSNT_NIC3_R_N   U5    -P5         A01X+091444Y+087836X0160Y    R180 S1      
317PRSNT_NIC3_R_N   VIA   -    MD0100PA00X+091601Y+087994X0180Y    R270 S0      
327PRSNT_NIC3_R_N   U6    -H19        A01X+137202Y+087554X0160Y         S1      
317PRSNT_NIC3_R_N   VIA   -    MD0100PA00X+137360Y+087711X0180Y         S0      
317PRSNT_NIC3_R_N   VIA   -    MD0100PA00X+082827Y+053546X0200Y         S0      
327PRSNT_NIC3_R_N   R196  -1   M      A01X+079937Y+055829X0198Y0197R270 S1      
327PRSNT_NIC3_R_N   C4001 -1          A01X+079937Y+056214X0198Y0197R090 S1      
327PRSNT_NIC3_R_N   U24   -G          A01X+079351Y+056004X0400Y0560R180 S1      
317m1606            VIA   -    M      A01X+134653Y+062840X0200Y    R180 S2      
017m1606            VIA   -    M      A18X+134653Y+062840X0260Y    R180 S2      
017m1606                  -    MD0100PA00X+134653Y+062840                       
327m1606            R4812 -1          A01X+133258Y+062900X0198Y0197R180 S1      
327m1606            U349  -4          A01X+135098Y+062840X0160Y0540R270 S1      
317PRSNT_NIC2_R_N   VIA   -    MD0100PA00X+072471Y+089314X0200Y         S0      
317PRSNT_NIC2_R_N   VIA   -    MD0100PA00X+081803Y+090775X0200Y         S0      
317PRSNT_NIC2_R_N   VIA   -    M      A01X+060246Y+045871X0200Y         S2      
017PRSNT_NIC2_R_N   VIA   -    M      A18X+060246Y+045871X0260Y         S2      
017PRSNT_NIC2_R_N         -    MD0100PA00X+060246Y+045871                       
327PRSNT_NIC2_R_N   C4000 -1          A01X+058432Y+044866X0198Y0197R270 S1      
327PRSNT_NIC2_R_N   R145  -1   M      A01X+058432Y+045251X0198Y0197R090 S1      
327PRSNT_NIC2_R_N   U19   -G   M      A01X+059018Y+045075X0400Y0560     S1      
327PRSNT_NIC2_R_N   U6    -G21        A01X+137832Y+087869X0160Y         S1      
317PRSNT_NIC2_R_N   VIA   -    MD0100PA00X+093526Y+096272X0200Y         S0      
317PRSNT_NIC2_R_N   VIA   -    MD0100PA00X+092861Y+087994X0180Y    R270 S0      
327PRSNT_NIC2_R_N   U5    -P1         A01X+092704Y+087836X0160Y    R180 S1      
317PRSNT_NIC2_R_N   VIA   -    MD0100PA00X+137990Y+088026X0180Y         S0      
317m1607            VIA   -    M      A01X+137842Y+064980X0200Y         S2      
017m1607            VIA   -    M      A18X+137842Y+064980X0260Y         S2      
017m1607                  -    MD0100PA00X+137842Y+064980                       
327m1607            R4776 -1          A01X+139142Y+065200X0198Y0197     S1      
327m1607            U348  -13         A01X+137402Y+065203X0240Y0540R270 S1      
317m1608            VIA   -    M      A01X+089033Y+082855X0200Y         S2      
017m1608            VIA   -    M      A18X+089033Y+082855X0280Y         S2      
017m1608                  -    MD0100PA00X+089033Y+082855                       
327m1608            U5    -A12        A01X+089239Y+083742X0160Y    R180 S1      
327m1608            R5278 -2          A01X+088792Y+081662X0198Y0197R090 S1      
327m1609            R3893 -1          A01X+034639Y+120340X0198Y0197R090 S1      
327m1609            VIA   -    M      A18X+034406Y+120312X0260Y         S2      
317m1609            VIA   -    MD0100PA00X+034639Y+119926X0200Y         S0      
327m1609            PEX0  -L39        A01X+028720Y+121732X0180Y         S1      
317m1609            VIA   -    MD0080PA00X+028533Y+121545X0160Y         S0      
317m1610            VIA   -    M      A01X+130584Y+066001X0200Y         S2      
017m1610            VIA   -    M      A18X+130584Y+066001X0260Y         S2      
017m1610                  -    MD0100PA00X+130584Y+066001                       
327m1610            R4742 -1   M      A01X+132458Y+065750X0198Y0197R180 S1      
327m1610            R4727 -2   M      A01X+132458Y+065350X0198Y0197     S1      
327m1610            R4773 -2          A01X+132942Y+065350X0198Y0197R180 S1      
327m1610            U6    -V5         A01X+132793Y+084404X0160Y         S1      
317m1610            VIA   -    MD0100PA00X+132636Y+084247X0180Y         S0      
317m1611            VIA   -    M      A01X+133929Y+065946X0200Y    R180 S2      
017m1611            VIA   -    M      A18X+133929Y+065946X0260Y    R180 S2      
017m1611                  -    MD0100PA00X+133929Y+065946                       
327m1611            R4772 -1          A01X+133258Y+065750X0198Y0197R180 S1      
327m1611            U348  -8          A01X+135098Y+066266X0160Y0540R270 S1      
327RST_BJT_Q15_C    VIA   -    M      A01X+090646Y+072373X0300Y         S1      
327RST_BJT_Q15_C    Q57   -C          A01X+090120Y+071897X0320Y0360R090 S1      
327RST_BJT_Q15_C    Q56   -B          A01X+090732Y+071351X0320Y0360R090 S1      
327RST_BJT_Q15_C    R5493 -1   M      A01X+090769Y+071897X0198Y0197     S1      
317m1612            VIA   -    M      A01X+086859Y+039850X0200Y    R270 S2      
017m1612            VIA   -    M      A18X+086859Y+039850X0260Y    R270 S2      
017m1612                  -    MD0100PA00X+086859Y+039850                       
327m1612            U82   -5          A01X+086576Y+039957X0090Y0240R090 S1      
327m1612            R720  -2          A01X+086809Y+038008X0198Y0197R090 S1      
327m1612            R5621 -2          A18X+086497Y+038824X0198Y0197R180 S2      
327m1613            PEX0  -N38        A01X+028346Y+120984X0180Y         S1      
317m1613            VIA   -    MD0080PA00X+028533Y+120797X0160Y         S0      
327m1613            VIA   -    M      A18X+033350Y+120220X0260Y         S2      
317m1613            VIA   -    MD0100PA00X+033954Y+119689X0200Y         S0      
327m1613            R3894 -1          A01X+034215Y+120344X0198Y0197R090 S1      
317m1614            VIA   -    M      A01X+134653Y+067290X0200Y    R180 S2      
017m1614            VIA   -    M      A18X+134653Y+067290X0260Y    R180 S2      
017m1614                  -    MD0100PA00X+134653Y+067290                       
327m1614            R4768 -1          A01X+133258Y+067350X0198Y0197R180 S1      
327m1614            U348  -4          A01X+135098Y+067290X0160Y0540R270 S1      
327RST_BJT_Q15_B    VIA   -    M      A01X+089153Y+072803X0300Y         S1      
327RST_BJT_Q15_B    Q57   -B          A01X+089332Y+072271X0320Y0360R090 S1      
327RST_BJT_Q15_B    R5495 -2          A01X+088684Y+072277X0198Y0197     S1      
327m1615            VIA   -    M      A01X+058420Y+079079X0300Y         S1      
327m1615            R6639 -1          A01X+028230Y+092634X0198Y0197R090 S1      
317m1615            VIA   -    MD0100PA00X+027926Y+092634X0200Y         S0      
317m1615            VIA   -    MD0100PA00X+058606Y+079314X0200Y         S0      
327m1615            U104  -1          A18X+058606Y+079711X0140Y0440     S2      
317m1615            VIA   -    MD0100PA00X+043410Y+079740X0200Y         S0      
327m1615            R6632 -2          A01X+041210Y+079869X0198Y0197R090 S1      
327m1615            R6641 -2          A01X+057519Y+077670X0198Y0197     S1      
317m1616            VIA   -    M      A01X+137842Y+069680X0200Y         S2      
017m1616            VIA   -    M      A18X+137842Y+069680X0260Y         S2      
017m1616                  -    MD0100PA00X+137842Y+069680                       
327m1616            U347  -13         A01X+137402Y+069903X0240Y0540R270 S1      
327m1616            R4757 -1          A01X+139142Y+069900X0198Y0197     S1      
317m1617            VIA   -    M      A01X+139700Y+065200X0200Y    R180 S2      
017m1617            VIA   -    M      A18X+139700Y+065200X0260Y    R180 S2      
017m1617                  -    MD0100PA00X+139700Y+065200                       
317m1617            VIA   -    MD0100PA00X+146011Y+068354X0200Y         S0      
317m1617            VIA   -    MD0100PA00X+141350Y+082800X0200Y         S0      
327m1617            R4097 -1          A01X+141108Y+082800X0198Y0197R180 S1      
327m1617            R4776 -2          A01X+139458Y+065200X0198Y0197     S1      
317m1618            VIA   -    M      A01X+109704Y+017762X0200Y         S2      
017m1618            VIA   -    M      A18X+109704Y+017762X0260Y         S2      
017m1618                  -    MD0100PA00X+109704Y+017762                       
327m1618            R613  -2          A01X+109025Y+017615X0198Y0197R090 S1      
327m1618            C326  -2   M      A01X+109425Y+017615X0198Y0197R090 S1      
327m1618            U72   -12         A01X+110097Y+017990X0090Y0240R090 S1      
317m1619            VIA   -    M      A01X+133929Y+070646X0200Y    R180 S2      
017m1619            VIA   -    M      A18X+133929Y+070646X0260Y    R180 S2      
017m1619                  -    MD0100PA00X+133929Y+070646                       
327m1619            R4753 -1          A01X+133258Y+070450X0198Y0197R180 S1      
327m1619            U347  -8          A01X+135098Y+070966X0160Y0540R270 S1      
327HP_NIC7_EN       PU53  -11         A01X+175225Y+048048X0110Y0240R270 S1      
317HP_NIC7_EN       VIA   -    MD0100PA00X+171631Y+045433X0200Y         S0      
327HP_NIC7_EN       R4457 -1          A01X+176950Y+037348X0198Y0197R090 S1      
327HP_NIC7_EN       R961  -1   M      A01X+181501Y+042460X0198Y0197R180 S1      
327HP_NIC7_EN       R401  -2   M      A01X+169454Y+055014X0198Y0197R270 S1      
327HP_NIC7_EN       U44   -D          A01X+170394Y+055138X0400Y0560R180 S1      
317HP_NIC7_EN       VIA   -    MD0100PA00X+169203Y+055014X0200Y    R180 S0      
327HP_NIC7_EN       C2884 -1   M      A01X+175935Y+048738X0198Y0197     S1      
317HP_NIC7_EN       VIA   -    M      A01X+175639Y+048738X0200Y         S2      
017HP_NIC7_EN       VIA   -    M      A18X+175639Y+048738X0260Y         S2      
017HP_NIC7_EN             -    MD0100PA00X+175639Y+048738                       
327HP_NIC7_EN       R6043 -1          A01X+171871Y+045433X0198Y0197     S1      
317USB2_BIC_DP      VIA   -    MD0100PA00X+041733Y+147710X0200Y         S0      
317USB2_BIC_DP      VIA   -    MD0100PA00X+041520Y+149612X0200Y    R270 S0      
327USB2_BIC_DP      R6731 -2   M      A01X+041884Y+149803X0180Y0200R270 S1      
327USB2_BIC_DP      R5447 -2          A01X+041884Y+149803X0180Y0200R090 S1      
327USB2_BIC_DP      VIA   -    M      A01X+042039Y+146789X0160Y0041R315 S1      
327USB2_BIC_DP      R6760 -1   M      A01X+095199Y+089989X0198Y0197     S1      
327USB2_BIC_DP      U5    -E4         A01X+091759Y+085002X0160Y    R180 S1      
317USB2_BIC_DP      VIA   -    MD0100PA01X+091916Y+084844X0180Y    R270 S0      
317USB2_BIC_DP      VIA   -    MD0100PA01X+094938Y+088674X0200Y         S0      
317SSD9_ADC_A0      VIA   -           A01X+111530Y+017856X0200Y         S2      
017SSD9_ADC_A0      VIA   -           A18X+111530Y+017856X0260Y         S2      
017SSD9_ADC_A0            -     D0100PA00X+111530Y+017856                       
327SSD9_ADC_A0      R606  -1          A01X+111828Y+017666X0198Y0197     S1      
327SSD9_ADC_A0      R609  -1   M      A01X+111828Y+018066X0198Y0197     S1      
327SSD9_ADC_A0      U72   -2          A01X+111199Y+018187X0090Y0240R090 S1      
317m1620            VIA   -    M      A01X+134653Y+071990X0200Y    R180 S2      
017m1620            VIA   -    M      A18X+134653Y+071990X0260Y    R180 S2      
017m1620                  -    MD0100PA00X+134653Y+071990                       
327m1620            R4749 -1          A01X+133258Y+072050X0198Y0197R180 S1      
327m1620            U347  -4          A01X+135098Y+071990X0160Y0540R270 S1      
317m1621            VIA   -    MD0100PA00X+132006Y+083617X0180Y         S0      
327m1621            U6    -Y3         A01X+132163Y+083774X0160Y         S1      
317m1621            VIA   -    MD0100PA00X+091263Y+091524X0200Y         S0      
327m1621            R6193 -2          A01X+091263Y+092255X0198Y0197R270 S1      
327m1621            R4525 -2          A01X+091090Y+091258X0198Y0197R090 S1      
317m1621            VIA   -    M      A01X+098592Y+080514X0200Y         S2      
017m1621            VIA   -    M      A18X+098592Y+080514X0260Y         S2      
017m1621                  -    MD0100PA00X+098592Y+080514                       
317USB2_BIC_DN      VIA   -    MD0100PA00X+041393Y+147710X0200Y         S0      
317USB2_BIC_DN      VIA   -    MD0100PA00X+041520Y+149952X0200Y    R270 S0      
327USB2_BIC_DN      R6732 -2   M      A01X+041149Y+149812X0180Y0200R270 S1      
327USB2_BIC_DN      R5449 -2          A01X+041149Y+149812X0180Y0200R090 S1      
327USB2_BIC_DN      VIA   -    M      A01X+042973Y+145702X0160Y0041R315 S1      
327USB2_BIC_DN      R6761 -1   M      A01X+094799Y+089989X0198Y0197R180 S1      
327USB2_BIC_DN      U5    -F4         A01X+091759Y+085317X0160Y    R180 S1      
317USB2_BIC_DN      VIA   -    MD0100PA01X+091916Y+085159X0180Y    R270 S0      
317USB2_BIC_DN      VIA   -    MD0100PA01X+094598Y+088674X0200Y         S0      
317m1622            VIA   -    M      A01X+087640Y+079742X0200Y         S2      
017m1622            VIA   -    M      A18X+087640Y+079742X0280Y         S2      
017m1622                  -    MD0100PA00X+087640Y+079742                       
327m1622            R5281 -2          A01X+087630Y+079423X0198Y0197     S1      
327m1622            R5278 -1          A01X+088792Y+081346X0198Y0197R090 S1      
327m1622            R5280 -2   M      A01X+088792Y+080646X0198Y0197R090 S1      
317m1623            VIA   -    M      A01X+110990Y+017152X0200Y         S2      
017m1623            VIA   -    M      A18X+110990Y+017152X0260Y         S2      
017m1623                  -    MD0100PA00X+110990Y+017152                       
327m1623            R5899 -2          A01X+110990Y+016871X0198Y0197R180 S1      
317m1623            VIA   -    MD0100PA00X+111471Y+019018X0200Y         S0      
327m1623            U72   -4          A01X+111199Y+018580X0090Y0240R090 S1      
327m1623            R611  -2          A01X+111828Y+019266X0198Y0197R180 S1      
317m1624            VIA   -    M      A01X+147526Y+068093X0200Y         S2      
017m1624            VIA   -    M      A18X+147526Y+068093X0260Y         S2      
017m1624                  -    MD0100PA00X+147526Y+068093                       
327m1624            U346  -13         A01X+146502Y+068353X0240Y0540R270 S1      
327m1624            R4713 -1          A01X+148192Y+067763X0198Y0197     S1      
317m1625            VIA   -    M      A01X+139700Y+069900X0200Y    R180 S2      
017m1625            VIA   -    M      A18X+139700Y+069900X0260Y    R180 S2      
017m1625                  -    MD0100PA00X+139700Y+069900                       
317m1625            VIA   -    MD0100PA00X+146912Y+071906X0200Y         S0      
317m1625            VIA   -    MD0100PA00X+141350Y+083200X0200Y         S0      
327m1625            R4096 -1          A01X+141108Y+083200X0198Y0197R180 S1      
327m1625            R4757 -2          A01X+139458Y+069900X0198Y0197     S1      
317m1626            VIA   -    MD0100PA00X+132636Y+084562X0180Y         S0      
327m1626            U6    -U5         A01X+132793Y+084719X0160Y         S1      
327m1626            R4526 -2   M      A01X+094764Y+088315X0198Y0197     S1      
327m1626            R6194 -2          A01X+095412Y+088314X0198Y0197R090 S1      
317m1626            VIA   -    MD0100PA00X+095324Y+087683X0200Y         S0      
317m1626            VIA   -    M      A01X+095534Y+086685X0200Y         S2      
017m1626            VIA   -    M      A18X+095534Y+086685X0260Y         S2      
017m1626                  -    MD0100PA00X+095534Y+086685                       
317m1627            VIA   -    M      A01X+109762Y+017219X0200Y         S2      
017m1627            VIA   -    M      A18X+109762Y+017219X0260Y         S2      
017m1627                  -    MD0100PA00X+109762Y+017219                       
327m1627            R612  -2          A01X+109419Y+016870X0198Y0197R180 S1      
327m1627            C326  -1   M      A01X+109425Y+017300X0198Y0197R090 S1      
327m1627            U72   -13         A01X+110353Y+017734X0090Y0240R180 S1      
317m1628            VIA   -    MD0100PA00X+132950Y+085822X0180Y         S0      
327m1628            U6    -N6         A01X+133108Y+085979X0160Y         S1      
317m1628            VIA   -    M      A01X+128981Y+067761X0200Y         S2      
017m1628            VIA   -    M      A18X+128981Y+067761X0260Y         S2      
017m1628                  -    MD0100PA00X+128981Y+067761                       
327m1628            R4770 -2          A01X+132942Y+066550X0198Y0197R180 S1      
327m1628            R4732 -2   M      A01X+132458Y+066550X0198Y0197     S1      
317m1629            VIA   -    M      A01X+143346Y+069266X0200Y    R180 S2      
017m1629            VIA   -    M      A18X+143346Y+069266X0260Y    R180 S2      
017m1629                  -    MD0100PA00X+143346Y+069266                       
327m1629            R4709 -1          A01X+142358Y+068900X0198Y0197R180 S1      
327m1629            U346  -8          A01X+144198Y+069416X0160Y0540R270 S1      
327m1630            R6195 -2          A18X+093663Y+092255X0198Y0197R090 S2      
327m1630            R4527 -2          A18X+093529Y+091191X0198Y0197R270 S2      
317m1630            VIA   -    MD0100PA00X+093663Y+091804X0200Y         S0      
317m1630            VIA   -    M      A01X+103181Y+085027X0200Y         S2      
017m1630            VIA   -    M      A18X+103181Y+085027X0260Y         S2      
017m1630                  -    MD0100PA00X+103181Y+085027                       
327m1630            U6    -U3         A01X+132163Y+084719X0160Y         S1      
317m1630            VIA   -    MD0100PA00X+132006Y+084562X0180Y         S0      
327P3V3_SSD12_OCP   PU63  -9          A01X+139937Y+022506X0110Y0240     S1      
317P3V3_SSD12_OCP   VIA   -    M      A01X+139860Y+023056X0200Y    R090 S2      
017P3V3_SSD12_OCP   VIA   -    M      A18X+139860Y+023056X0260Y    R090 S2      
017P3V3_SSD12_OCP         -    MD0100PA00X+139860Y+023056                       
327P3V3_SSD12_OCP   PR274 -1          A01X+139923Y+023296X0198Y0197R090 S1      
327m1631            R6804 -2          A01X+086384Y+070917X0198Y0197     S1      
327m1631            VIA   -    M      A01X+086533Y+071792X0300Y         S1      
327m1631            Q58   -2          A01X+087032Y+071317X0170Y0240R270 S1      
327m1631            R5497 -1   M      A01X+086384Y+071317X0198Y0197R180 S1      
317m1632            VIA   -    M      A01X+111519Y+018383X0200Y         S2      
017m1632            VIA   -    M      A18X+111519Y+018383X0260Y         S2      
017m1632                  -    MD0100PA00X+111519Y+018383                       
327m1632            R607  -1          A01X+111828Y+018466X0198Y0197     S1      
327m1632            U72   -3          A01X+111199Y+018383X0090Y0240R090 S1      
317m1633            VIA   -    M      A01X+143753Y+070440X0200Y    R180 S2      
017m1633            VIA   -    M      A18X+143753Y+070440X0260Y    R180 S2      
017m1633                  -    MD0100PA00X+143753Y+070440                       
327m1633            R4705 -1          A01X+142358Y+070500X0198Y0197R180 S1      
327m1633            U346  -4          A01X+144198Y+070440X0160Y0540R270 S1      
327m1634            J4    -3          A01X+092730Y+049643X0500Y1350R090 S1      
317m1634            VIA   -    M      A01X+095095Y+031795X0200Y         S2      
017m1634            VIA   -    M      A18X+095095Y+031795X0260Y         S2      
017m1634                  -    MD0100PA00X+095095Y+031795                       
327m1634            R1002 -1          A01X+094766Y+031674X0198Y0197R180 S1      
327m1635            R6804 -1          A01X+086069Y+070917X0198Y0197     S1      
317m1635            VIA   -    M      A01X+085800Y+070724X0200Y         S2      
017m1635            VIA   -    M      A18X+085800Y+070724X0260Y         S2      
017m1635                  -    MD0100PA00X+085800Y+070724                       
327m1635            R5502 -2          A01X+086069Y+070517X0198Y0197R180 S1      
317m1636            VIA   -    M      A01X+110943Y+019249X0200Y         S2      
017m1636            VIA   -    M      A18X+110943Y+019249X0260Y         S2      
017m1636                  -    MD0100PA00X+110943Y+019249                       
327m1636            U72   -5          A01X+110943Y+018836X0090Y0240R180 S1      
327m1636            R610  -2          A01X+111828Y+019666X0198Y0197R180 S1      
317m1637            VIA   -    M      A01X+149663Y+076500X0200Y         S2      
017m1637            VIA   -    M      A18X+149663Y+076500X0260Y         S2      
017m1637                  -    MD0100PA00X+149663Y+076500                       
327m1637            R4694 -1          A01X+149942Y+076500X0198Y0197     S1      
327m1637            U345  -13         A01X+148202Y+076903X0240Y0540R270 S1      
317m1638            VIA   -    M      A01X+146837Y+067381X0200Y         S2      
017m1638            VIA   -    M      A18X+146837Y+067381X0260Y         S2      
017m1638                  -    MD0100PA00X+146837Y+067381                       
327m1638            R4713 -2          A01X+148508Y+067763X0198Y0197     S1      
317m1638            VIA   -    MD0100PA00X+141350Y+083600X0200Y         S0      
327m1638            R4095 -1          A01X+141108Y+083600X0198Y0197R180 S1      
317m1639            VIA   -    M      A01X+144729Y+077646X0200Y    R180 S2      
017m1639            VIA   -    M      A18X+144729Y+077646X0260Y    R180 S2      
017m1639                  -    MD0100PA00X+144729Y+077646                       
327m1639            R4690 -1          A01X+144058Y+077450X0198Y0197R180 S1      
327m1639            U345  -8          A01X+145898Y+077966X0160Y0540R270 S1      
317m1640            VIA   -    M      A01X+086746Y+071061X0200Y         S2      
017m1640            VIA   -    M      A18X+086746Y+071061X0260Y         S2      
017m1640                  -    MD0100PA00X+086746Y+071061                       
327m1640            Q58   -3          A01X+087032Y+071061X0170Y0240R270 S1      
327m1640            R5781 -2          A01X+086384Y+070117X0198Y0197     S1      
327m1640            R5502 -1   M      A01X+086384Y+070517X0198Y0197R180 S1      
317m1641            VIA   -    M      A01X+145453Y+078990X0200Y    R180 S2      
017m1641            VIA   -    M      A18X+145453Y+078990X0260Y    R180 S2      
017m1641                  -    MD0100PA00X+145453Y+078990                       
327m1641            R4686 -1          A01X+144058Y+079050X0198Y0197R180 S1      
327m1641            U345  -4          A01X+145898Y+078990X0160Y0540R270 S1      
327m1642            U6    -E3         A01X+132163Y+088499X0160Y         S1      
317m1642            VIA   -    MD0100PA00X+132006Y+088656X0180Y         S0      
317m1642            VIA   -    M      A01X+130525Y+088925X0200Y         S2      
017m1642            VIA   -    M      A18X+130525Y+088925X0260Y         S2      
017m1642                  -    MD0100PA00X+130525Y+088925                       
327m1642            R4165 -1          A18X+129958Y+088780X0198Y0197     S2      
327m1643            VIA   -    M      A18X+088729Y+089624X0260Y         S2      
327m1643            U5    -M12        A01X+089239Y+087206X0160Y    R180 S1      
317m1643            VIA   -    MD0100PA00X+089082Y+087364X0180Y    R270 S0      
327m1643            R4556 -1          A18X+088729Y+090876X0198Y0197R270 S2      
317m1644            VIA   -    M      A01X+147966Y+075456X0200Y         S2      
017m1644            VIA   -    M      A18X+147966Y+075456X0260Y         S2      
017m1644                  -    MD0100PA00X+147966Y+075456                       
327m1644            R4694 -2          A01X+150258Y+076500X0198Y0197     S1      
317m1644            VIA   -    MD0100PA00X+141350Y+084000X0200Y         S0      
327m1644            R4094 -1          A01X+141108Y+084000X0198Y0197R180 S1      
327HP_NIC0_EN       PU46  -11         A01X+004815Y+048974X0110Y0240R090 S1      
327HP_NIC0_EN       C2877 -1          A01X+004138Y+047898X0198Y0197R180 S1      
327HP_NIC0_EN       U9    -D          A01X+013684Y+045941X0400Y0560     S1      
327HP_NIC0_EN       R44   -2   M      A01X+014640Y+045538X0198Y0197R090 S1      
327HP_NIC0_EN       R5855 -1          A01X+006222Y+047063X0198Y0197R270 S1      
317HP_NIC0_EN       VIA   -    MD0100PA00X+006469Y+064218X0200Y         S0      
327HP_NIC0_EN       R4444 -1          A01X+002840Y+052773X0198Y0197     S1      
317HP_NIC0_EN       VIA   -    MD0100PA00X+002582Y+052773X0200Y    R180 S0      
317HP_NIC0_EN       VIA   -    M      A01X+004456Y+048216X0200Y    R180 S2      
017HP_NIC0_EN       VIA   -    M      A18X+004456Y+048216X0260Y    R180 S2      
017HP_NIC0_EN             -    MD0100PA00X+004456Y+048216                       
317HP_NIC0_EN       VIA   -    MD0100PA00X+014894Y+045592X0200Y         S0      
317HP_NIC0_EN       VIA   -    MD0100PA00X+006222Y+047304X0200Y    R180 S0      
327HP_NIC0_EN       R903  -1          A01X+006469Y+063939X0198Y0197R270 S1      
317m1645            VIA   -    MD0080PA00X+165285Y+121545X0160Y         S0      
327m1645            PEX3  -L37        A01X+165098Y+121732X0180Y         S1      
327m1645            VIA   -    M      A18X+173046Y+119763X0260Y         S2      
327m1645            R4183 -1          A01X+173766Y+120344X0198Y0197R090 S1      
327m1645            R4184 -2          A01X+173766Y+119857X0198Y0197R090 S1      
317m1645            VIA   -    MD0100PA00X+173766Y+120097X0200Y         S0      
327m1646            R1496 -2          A18X+085368Y+087946X0198Y0197     S2      
317m1646            VIA   -    MD0100PA00X+084838Y+087946X0200Y         S0      
327m1646            R4109 -1          A01X+148994Y+036858X0198Y0197     S1      
317m1646            VIA   -    M      A01X+148689Y+036858X0200Y         S2      
017m1646            VIA   -    M      A18X+148689Y+036858X0260Y         S2      
017m1646                  -    MD0100PA00X+148689Y+036858                       
317m1646            VIA   -    MD0100PA00X+109103Y+037481X0200Y         S0      
317m1646            VIA   -    MD0100PA00X+085399Y+063295X0200Y         S0      
317m1646            VIA   -    MD0100PA00X+088355Y+035728X0200Y         S0      
327m1646            R4263 -2          A01X+088355Y+034534X0198Y0197     S1      
317m1647            VIA   -    MD0100PA00X+132950Y+085507X0180Y         S0      
327m1647            U6    -P6         A01X+133108Y+085664X0160Y         S1      
317m1647            VIA   -    M      A01X+132700Y+069550X0200Y         S2      
017m1647            VIA   -    M      A18X+132700Y+069550X0260Y         S2      
017m1647                  -    MD0100PA00X+132700Y+069550                       
327m1647            R4755 -2          A01X+132942Y+069650X0198Y0197R180 S1      
327m1647            R4731 -2          A01X+132458Y+069650X0198Y0197     S1      
327m1648            VIA   -           A18X+087740Y+058413X0260Y         S2      
327m1648            R4198 -1          A18X+088995Y+055396X0280Y0320     S2      
317m1648            VIA   -    MD0100PA00X+088655Y+055396X0200Y         S0      
327m1648            C2804 -1          A18X+089838Y+059387X0198Y0197R090 S2      
327m1648            C2801 -1          A18X+089417Y+059380X0198Y0197R090 S2      
327m1648            C2803 -1          A18X+089445Y+060079X0198Y0197R270 S2      
327m1648            C2799 -1          A18X+088795Y+059996X0280Y0320     S2      
327m1648            L81   -2          A18X+088095Y+059912X0440Y0540R270 S2      
327m1648            C2802 -1          A18X+088763Y+057729X0198Y0197R180 S2      
327m1648            C2800 -1          A18X+088768Y+058577X0198Y0197R180 S2      
327m1648            U117  -B29        A01X+089802Y+059160X0110Y0180     S1      
317m1648            VIA   -    MD0100PA00X+089821Y+059989X0200Y    R090 S0      
327m1648            U117  -B32        A01X+089211Y+059160X0110Y0180     S1      
317m1648            VIA   -    MD0100PA00X+089167Y+060005X0200Y    R090 S0      
327m1648            U117  -B40        A01X+088768Y+057732X0110Y0180R090 S1      
317m1648            VIA   -    M      A01X+088113Y+057735X0200Y    R090 S2      
017m1648            VIA   -    M      A18X+088113Y+057735X0260Y    R090 S2      
017m1648                  -    MD0100PA00X+088113Y+057735                       
327m1648            U117  -B35        A01X+088768Y+058717X0110Y0180R090 S1      
317m1648            VIA   -    M      A01X+088148Y+058820X0200Y    R090 S2      
017m1648            VIA   -    M      A18X+088148Y+058820X0260Y    R090 S2      
017m1648                  -    MD0100PA00X+088148Y+058820                       
317m1649            VIA   -    MD0100PA00X+084820Y+088340X0200Y         S0      
327m1649            R1494 -2          A18X+085368Y+088346X0198Y0197     S2      
327m1649            R4110 -1   M      A01X+088831Y+034154X0198Y0197     S1      
317m1649            VIA   -    MD0100PA00X+085399Y+063045X0200Y         S0      
317m1649            VIA   -    M      A01X+088881Y+035737X0200Y         S2      
017m1649            VIA   -    M      A18X+088881Y+035737X0260Y         S2      
017m1649                  -    MD0100PA00X+088881Y+035737                       
327m1649            R4264 -2          A01X+088355Y+034134X0198Y0197     S1      
317m1650            VIA   -    M      A01X+132700Y+071150X0200Y         S2      
017m1650            VIA   -    M      A18X+132700Y+071150X0260Y         S2      
017m1650                  -    MD0100PA00X+132700Y+071150                       
327m1650            R4751 -2          A01X+132942Y+071250X0198Y0197R180 S1      
327m1650            R4730 -2          A01X+132458Y+071250X0198Y0197     S1      
327m1650            U6    -T2         A01X+131848Y+085034X0160Y         S1      
317m1650            VIA   -    MD0100PA00X+131691Y+084877X0180Y         S0      
317m1651            VIA   -    M      A01X+147200Y+072750X0200Y         S2      
017m1651            VIA   -    M      A18X+147200Y+072750X0260Y         S2      
017m1651                  -    MD0100PA00X+147200Y+072750                       
327m1651            U344  -13         A01X+146502Y+072753X0240Y0540R270 S1      
327m1651            R4650 -1          A01X+148242Y+072350X0198Y0197     S1      
327m1652            VIA   -           A18X+092729Y+056712X0260Y         S2      
327m1652            C2790 -1          A18X+091457Y+057839X0198Y0197     S2      
327m1652            U117  -B17        A01X+091229Y+057929X0110Y0180R090 S1      
317m1652            VIA   -    MD0100PA00X+091904Y+057938X0200Y    R090 S2      
317m1652            VIA   -    MD0100PA00X+092151Y+057879X0200Y    R090 S0      
327m1652            VIA   -           A18X+092131Y+056730X0260Y         S2      
327m1652            R4186 -2          A18X+092155Y+057286X0280Y0320R090 S2      
327m1652            C2789 -1          A18X+091595Y+057226X0280Y0320R180 S2      
317m1653            VIA   -    M      A01X+143029Y+073496X0200Y    R180 S2      
017m1653            VIA   -    M      A18X+143029Y+073496X0260Y    R180 S2      
017m1653                  -    MD0100PA00X+143029Y+073496                       
327m1653            U344  -8          A01X+144198Y+073816X0160Y0540R270 S1      
327m1653            R4646 -1          A01X+142358Y+073300X0198Y0197R180 S1      
317m1654            VIA   -    M      A01X+147976Y+072088X0200Y    R180 S2      
017m1654            VIA   -    M      A18X+147976Y+072088X0260Y    R180 S2      
017m1654                  -    MD0100PA00X+147976Y+072088                       
327m1654            R4650 -2          A01X+148558Y+072350X0198Y0197     S1      
317m1654            VIA   -    MD0100PA00X+141350Y+084800X0200Y         S0      
327m1654            R4093 -1          A01X+141108Y+084800X0198Y0197R180 S1      
327m1655            VIA   -           A18X+093045Y+060332X0260Y         S2      
327m1655            VIA   -           A18X+092016Y+059491X0260Y         S2      
327m1655            L79   -2          A18X+092145Y+060312X0440Y0540R270 S2      
327m1655            C2785 -1          A18X+091495Y+060396X0280Y0320     S2      
327m1655            C2788 -1          A18X+090715Y+059382X0198Y0197R090 S2      
327m1655            U117  -B23        A01X+090983Y+059160X0110Y0180     S1      
317m1655            VIA   -    M      A01X+091079Y+059873X0200Y    R090 S2      
017m1655            VIA   -    M      A18X+091079Y+059873X0260Y    R090 S2      
017m1655                  -    MD0100PA00X+091079Y+059873                       
327m1655            C2787 -1          A18X+091452Y+058286X0198Y0197     S2      
327m1655            C2786 -1          A18X+091457Y+058662X0198Y0197     S2      
327m1655            R4186 -1          A18X+092735Y+057286X0280Y0320R090 S2      
327m1655            U117  -B21        A01X+091229Y+058717X0110Y0180R090 S1      
317m1655            VIA   -    MD0100PA00X+091908Y+058764X0200Y    R090 S0      
327m1656            PU66  -8          A01X+114898Y+022506X0110Y0240     S1      
317m1656            VIA   -    M      A01X+115049Y+022782X0200Y    R090 S2      
017m1656            VIA   -    M      A18X+115049Y+022782X0260Y    R090 S2      
017m1656                  -    MD0100PA00X+115049Y+022782                       
327m1656            R4507 -1          A01X+114965Y+024168X0198Y0197     S1      
327m1656            R898  -2   M      A01X+115110Y+023298X0198Y0197R270 S1      
317m1657            VIA   -    M      A01X+091633Y+037775X0200Y    R090 S2      
017m1657            VIA   -    M      A18X+091633Y+037775X0260Y    R090 S2      
017m1657                  -    MD0100PA00X+091633Y+037775                       
327m1657            R1018 -2          A01X+091507Y+038133X0198Y0197R270 S1      
327m1657            U112  -19         A01X+091938Y+037275X0100Y0290R180 S1      
327m1658            U114  -M1         A01X+051170Y+068858X0090Y         S1      
327m1658            R1089 -2          A01X+049851Y+068501X0198Y0197     S1      
327PEX0_MODE_SEL9   R1161 -1          A01X+009584Y+098611X0198Y0197R270 S1      
327PEX0_MODE_SEL9   R1215 -2          A01X+009584Y+099196X0198Y0197R270 S1      
317PEX0_MODE_SEL9   VIA   -    M      A01X+009584Y+098881X0200Y         S2      
017PEX0_MODE_SEL9   VIA   -    M      A18X+009584Y+098881X0260Y         S2      
017PEX0_MODE_SEL9         -    MD0100PA00X+009584Y+098881                       
327PEX0_MODE_SEL9   PEX0  -AV28       A01X+024606Y+111634X0180Y         S1      
317PEX0_MODE_SEL9   VIA   -    MD0080PA00X+024793Y+111821X0160Y         S0      
317PU_PEX1_TR_TCK   VIA   -    MD0080PA00X+067510Y+121545X0160Y    R090 S0      
327PU_PEX1_TR_TCK   PEX1  -L20        A01X+067323Y+121732X0180Y         S1      
317PU_PEX1_TR_TCK   VIA   -    M      A01X+059263Y+123492X0200Y         S2      
017PU_PEX1_TR_TCK   VIA   -    M      A18X+059263Y+123492X0260Y         S2      
017PU_PEX1_TR_TCK         -    MD0100PA00X+059263Y+123492                       
327PU_PEX1_TR_TCK   R1325 -1          A01X+056269Y+122660X0198Y0197R270 S1      
317m1659            VIA   -    M      A01X+088650Y+026897X0200Y         S2      
017m1659            VIA   -    M      A18X+088650Y+026897X0260Y         S2      
017m1659                  -    MD0100PA00X+088650Y+026897                       
327m1659            U142  -3          A01X+150646Y+034680X0120Y0630R270 S1      
317m1659            VIA   -    MD0100PA00X+144750Y+036078X0200Y         S0      
317m1659            VIA   -    MD0100PA00X+083555Y+083512X0200Y         S0      
317m1659            VIA   -    MD0100PA00X+082750Y+075000X0200Y         S0      
327m1659            R5720 -1          A18X+084273Y+085146X0198Y0197R180 S2      
317m1659            VIA   -    MD0100PA00X+083743Y+085146X0200Y         S0      
327SMB_PEX0_SDA     R6805 -2          A01X+034614Y+119098X0198Y0197R270 S1      
317SMB_PEX0_SDA     VIA   -    MD0100PA00X+035780Y+118806X0200Y         S0      
327SMB_PEX0_SDA     R6320 -1          A18X+083626Y+090966X0198Y0197R090 S2      
327SMB_PEX0_SDA     R1542 -2          A01X+083691Y+091162X0198Y0197R090 S1      
317SMB_PEX0_SDA     VIA   -    M      A01X+038033Y+078263X0200Y         S2      
017SMB_PEX0_SDA     VIA   -    M      A18X+038033Y+078263X0260Y         S2      
017SMB_PEX0_SDA           -    MD0100PA00X+038033Y+078263                       
317SMB_PEX0_SDA     VIA   -    MD0100PA00X+037286Y+093514X0200Y         S0      
317SMB_PEX0_SDA     VIA   -    MD0100PA00X+084600Y+077208X0200Y         S0      
317SMB_PEX0_SDA     VIA   -    MD0100PA00X+083691Y+091402X0200Y    R090 S0      
327SMB_PEX_SCL      VIA   -    M      A18X+087675Y+086504X0260Y         S2      
327SMB_PEX_SCL      R1495 -1          A18X+085683Y+086346X0198Y0197     S2      
327SMB_PEX_SCL      U5    -K14        A01X+088609Y+086576X0160Y    R180 S1      
317SMB_PEX_SCL      VIA   -    MD0100PA00X+088452Y+086734X0180Y    R270 S0      
317m1660            VIA   -    MD0100PA00X+139055Y+039744X0200Y         S0      
317m1660            VIA   -    MD0100PA00X+135000Y+082550X0200Y         S0      
327m1660            U6    -AA12       A01X+134998Y+083460X0160Y         S1      
317m1660            VIA   -    M      A01X+178592Y+020886X0200Y         S2      
017m1660            VIA   -    M      A18X+178592Y+020886X0260Y         S2      
017m1660                  -    MD0100PA00X+178592Y+020886                       
327m1660            R4473 -2          A01X+178334Y+020886X0198Y0197     S1      
317m1660            VIA   -    MD0100PA00X+166686Y+035366X0200Y         S0      
317m1660            VIA   -    MD0100PA00X+173633Y+025888X0200Y         S0      
327m1660            R6025 -2          A01X+169206Y+024208X0198Y0197R180 S1      
327P3V3_SSD8_OCP    PU62  -9          A01X+094295Y+021023X0110Y0240     S1      
317P3V3_SSD8_OCP    VIA   -    M      A01X+094218Y+021573X0200Y    R090 S2      
017P3V3_SSD8_OCP    VIA   -    M      A18X+094218Y+021573X0260Y    R090 S2      
017P3V3_SSD8_OCP          -    MD0100PA00X+094218Y+021573                       
327P3V3_SSD8_OCP    PR273 -1          A01X+094280Y+021813X0198Y0197R090 S1      
317m1661            VIA   -    M      A01X+091065Y+037608X0200Y    R090 S2      
017m1661            VIA   -    M      A18X+091065Y+037608X0260Y    R090 S2      
017m1661                  -    MD0100PA00X+091065Y+037608                       
327m1661            R1016 -2          A01X+091107Y+038133X0198Y0197R270 S1      
327m1661            U112  -20         A01X+091741Y+037275X0100Y0290R180 S1      
327PEX1_SPARE6      VIA   -    M      A18X+078810Y+123228X0260Y         S2      
327PEX1_SPARE6      R1320 -2          A01X+081949Y+119857X0198Y0197R090 S1      
327PEX1_SPARE6      R1309 -1          A01X+081949Y+120344X0198Y0197R090 S1      
317PEX1_SPARE6      VIA   -    MD0100PA00X+081949Y+120104X0200Y         S0      
327PEX1_SPARE6      PEX1  -L28        A01X+070315Y+121732X0180Y         S1      
317PEX1_SPARE6      VIA   -    MD0080PA00X+070502Y+121545X0160Y    R270 S0      
317m1662            VIA   -    M      A01X+154543Y+035236X0200Y         S2      
017m1662            VIA   -    M      A18X+154543Y+035236X0260Y         S2      
017m1662                  -    MD0100PA00X+154543Y+035236                       
327m1662            U142  -21         A01X+152850Y+034424X0120Y0630R270 S1      
327m1662            R1761 -1   M      A01X+154830Y+035236X0198Y0197     S1      
327m1662            R1751 -2          A01X+155830Y+035236X0198Y0197R180 S1      
327m1663            VIA   -           A18X+070190Y+163386X0260Y         S2      
317m1663            J5    -D9   D0122PA00X+069886Y+160705X0282Y    R180 S3      
317m1664            VIA   -    M      A01X+141800Y+074500X0200Y         S2      
017m1664            VIA   -    M      A18X+141800Y+074500X0260Y         S2      
017m1664                  -    MD0100PA00X+141800Y+074500                       
327m1664            R4613 -1          A01X+141558Y+074900X0198Y0197R180 S1      
327m1664            R4600 -2   M      A01X+141558Y+074500X0198Y0197     S1      
327m1664            R4643 -2          A01X+142042Y+074500X0198Y0197R180 S1      
327m1664            U6    -Y15        A01X+135942Y+083774X0160Y         S1      
317m1664            VIA   -    MD0100PA00X+136100Y+083617X0180Y         S0      
317m1665            VIA   -    M      A01X+090500Y+036216X0200Y    R090 S2      
017m1665            VIA   -    M      A18X+090500Y+036216X0260Y    R090 S2      
017m1665                  -    MD0100PA00X+090500Y+036216                       
327m1665            U112  -24         A01X+091184Y+036522X0100Y0290R090 S1      
327m1665            R1014 -2          A01X+090234Y+035837X0198Y0197     S1      
317PEX0_MODE_SEL8   VIA   -    M      A01X+012784Y+098881X0200Y         S2      
017PEX0_MODE_SEL8   VIA   -    M      A18X+012784Y+098881X0260Y         S2      
017PEX0_MODE_SEL8         -    MD0100PA00X+012784Y+098881                       
327PEX0_MODE_SEL8   R1204 -2          A01X+012784Y+099196X0198Y0197R270 S1      
327PEX0_MODE_SEL8   R1160 -1          A01X+012784Y+098611X0198Y0197R270 S1      
327PEX0_MODE_SEL8   PEX0  -AW29       A01X+024980Y+111260X0180Y         S1      
317PEX0_MODE_SEL8   VIA   -    MD0080PA00X+025167Y+111447X0160Y         S0      
317TP_PEX1_TDO      VIA   -    MD0080PA00X+067136Y+121545X0160Y    R180 S0      
327TP_PEX1_TDO      VIA   -           A18X+066949Y+121732X0260Y         S2      
327TP_PEX1_TDO      PEX1  -L19        A01X+066949Y+121732X0180Y         S1      
317PEX3_SYS_ERR_N   VIA   -    MD0080PA00X+162667Y+111821X0160Y         S0      
327PEX3_SYS_ERR_N   R1458 -1          A01X+145540Y+102105X0198Y0197     S1      
317PEX3_SYS_ERR_N   VIA   -    M      A01X+145628Y+102340X0200Y         S2      
017PEX3_SYS_ERR_N   VIA   -    M      A18X+145628Y+102340X0260Y         S2      
017PEX3_SYS_ERR_N         -    MD0100PA00X+145628Y+102340                       
327PEX3_SYS_ERR_N   PEX3  -AV30       A01X+162480Y+111634X0180Y         S1      
317m1666            VIA   -    M      A01X+149984Y+035400X0200Y         S2      
017m1666            VIA   -    M      A18X+149984Y+035400X0260Y         S2      
017m1666                  -    MD0100PA00X+149984Y+035400                       
327m1666            R1750 -2          A01X+148312Y+035420X0198Y0197     S1      
327m1666            R1759 -1   M      A01X+149312Y+035420X0198Y0197R180 S1      
327m1666            U142  -2          A01X+150646Y+034936X0120Y0630R270 S1      
327SMB_PEX0_SCL     R6322 -1          A18X+083226Y+090962X0198Y0197R090 S2      
327SMB_PEX0_SCL     R1541 -2          A01X+083724Y+091902X0198Y0197R270 S1      
317SMB_PEX0_SCL     VIA   -    M      A01X+037370Y+078256X0200Y         S2      
017SMB_PEX0_SCL     VIA   -    M      A18X+037370Y+078256X0260Y         S2      
017SMB_PEX0_SCL           -    MD0100PA00X+037370Y+078256                       
317SMB_PEX0_SCL     VIA   -    MD0100PA00X+036896Y+093774X0200Y         S0      
317SMB_PEX0_SCL     VIA   -    MD0100PA00X+084266Y+076952X0200Y         S0      
317SMB_PEX0_SCL     VIA   -    MD0100PA00X+083691Y+091662X0200Y    R090 S0      
317SMB_PEX0_SCL     VIA   -    MD0100PA00X+034312Y+118841X0200Y         S0      
327SMB_PEX0_SCL     R6806 -2          A01X+034230Y+119084X0198Y0197R270 S1      
327m1667            VIA   -    M      A18X+135500Y+082950X0260Y         S2      
327m1667            U6    -W13        A01X+135312Y+084089X0160Y         S1      
317m1667            VIA   -    MD0100PA00X+135470Y+083932X0180Y         S0      
327m1667            R4147 -2          A18X+135550Y+081958X0198Y0197R270 S2      
327m1668            PU63  -8          A01X+140134Y+022506X0110Y0240     S1      
317m1668            VIA   -    M      A01X+140286Y+022782X0200Y    R090 S2      
017m1668            VIA   -    M      A18X+140286Y+022782X0260Y    R090 S2      
017m1668                  -    MD0100PA00X+140286Y+022782                       
327m1668            R4499 -1          A01X+140201Y+024168X0198Y0197     S1      
327m1668            R895  -2   M      A01X+140346Y+023298X0198Y0197R270 S1      
317m1669            VIA   -    M      A01X+090548Y+035526X0200Y    R090 S2      
017m1669            VIA   -    M      A18X+090548Y+035526X0260Y    R090 S2      
017m1669                  -    MD0100PA00X+090548Y+035526                       
327m1669            U112  -25         A01X+091184Y+036325X0100Y0290R090 S1      
327m1669            R1012 -2          A01X+090234Y+035437X0198Y0197     S1      
327m1670            R1076 -2          A01X+103379Y+030583X0198Y0197R090 S1      
327m1670            U113  -A27        A01X+103318Y+031666X0070Y0220     S1      
327PEX1_SPARE7      VIA   -    M      A18X+080239Y+122120X0260Y         S2      
327PEX1_SPARE7      R1321 -2          A01X+080825Y+121499X0198Y0197R135 S1      
327PEX1_SPARE7      R1310 -1          A01X+080378Y+121854X0198Y0197R135 S1      
317PEX1_SPARE7      VIA   -    MD0100PA00X+080702Y+121790X0200Y         S0      
327PEX1_SPARE7      PEX1  -M27        A01X+069941Y+121358X0180Y         S1      
317PEX1_SPARE7      VIA   -    MD0080PA00X+070128Y+121545X0160Y         S0      
317TP_PEX3_TRST_L   VIA   -    MD0080PA00X+157805Y+121171X0160Y         S0      
327TP_PEX3_TRST_L   VIA   -    M      A18X+158740Y+121358X0260Y         S2      
327TP_PEX3_TRST_L   R1459 -1          A18X+159521Y+121388X0198Y0197R270 S2      
327TP_PEX3_TRST_L   PEX3  -M18        A01X+157992Y+121358X0180Y         S1      
317m1671            VIA   -    M      A01X+149592Y+035870X0200Y         S2      
017m1671            VIA   -    M      A18X+149592Y+035870X0260Y         S2      
017m1671                  -    MD0100PA00X+149592Y+035870                       
327m1671            R1749 -2          A01X+148312Y+035870X0198Y0197     S1      
327m1671            U142  -1          A01X+150646Y+035192X0120Y0630R270 S1      
327m1671            R1758 -1   M      A01X+149312Y+035870X0198Y0197R180 S1      
317m1672            J11   -O9   D0122PA00X+035240Y+150980X0282Y    R180 S3      
317m1672            VIA   -    MD0100PA00X+045438Y+130184X0200Y    R180 S0      
327m1672            R1219 -2          A18X+044848Y+130154X0198Y0197R180 S2      
327m1673            C4104 -2          A01X+057976Y+152379X0198Y0197R090 S1      
317m1673            J5    -C9   D0122PA00X+069886Y+161217X0282Y    R180 S3      
317m1673            VIA   -    M      A01X+057981Y+152816X0200Y         S2      
017m1673            VIA   -    M      A18X+057981Y+152816X0260Y         S2      
017m1673                  -    MD0100PA00X+057981Y+152816                       
327m1673            R1845 -2          A01X+057981Y+153543X0198Y0197R270 S1      
327m1674            VIA   -    M      A01X+126162Y+090707X0300Y         S1      
327m1674            R2988 -1          A01X+126162Y+090159X0198Y0197R270 S1      
327m1674            Q113  -6          A01X+127488Y+090828X0240Y0240R270 S1      
327m1675            U6    -AA17       A01X+136572Y+083460X0160Y         S1      
317m1675            VIA   -    MD0100PA00X+136730Y+083302X0180Y         S0      
327m1675            R6185 -2          A18X+092463Y+092255X0198Y0197R090 S2      
327m1675            R4517 -2          A18X+092329Y+091191X0198Y0197R270 S2      
317m1675            VIA   -    MD0100PA00X+092463Y+091804X0200Y         S0      
317m1675            VIA   -    M      A01X+103753Y+083649X0200Y         S2      
017m1675            VIA   -    M      A18X+103753Y+083649X0260Y         S2      
017m1675                  -    MD0100PA00X+103753Y+083649                       
327m1676            R1075 -2          A01X+103739Y+030583X0198Y0197R090 S1      
327m1676            U113  -A28        A01X+103514Y+031666X0070Y0220     S1      
327PEX0_MODE_SEL7   PEX0  -AV26       A01X+023858Y+111634X0180Y         S1      
317PEX0_MODE_SEL7   VIA   -    MD0080PA00X+024045Y+111821X0160Y         S0      
327PEX0_MODE_SEL7   R1159 -1          A01X+009984Y+098611X0198Y0197R270 S1      
327PEX0_MODE_SEL7   R1203 -2          A01X+009984Y+099196X0198Y0197R270 S1      
317PEX0_MODE_SEL7   VIA   -    MD0100PA00X+010020Y+098880X0200Y         S0      
327PEX0_MODE_SEL7   VIA   -    M      A18X+022500Y+106285X0260Y         S2      
327PEX1_SYS_ERR_N   PEX1  -AV30       A01X+071063Y+111634X0180Y         S1      
317PEX1_SYS_ERR_N   VIA   -    MD0080PA00X+071250Y+111821X0160Y         S0      
317PEX1_SYS_ERR_N   VIA   -    M      A01X+054557Y+102373X0200Y         S2      
017PEX1_SYS_ERR_N   VIA   -    M      A18X+054557Y+102373X0260Y         S2      
017PEX1_SYS_ERR_N         -    MD0100PA00X+054557Y+102373                       
327PEX1_SYS_ERR_N   R1322 -1          A01X+054123Y+102105X0198Y0197     S1      
317m1677            VIA   -    MD0080PA00X+157057Y+121545X0160Y         S0      
327m1677            R1460 -1          A01X+149152Y+122555X0198Y0197R225 S1      
317m1677            VIA   -    M      A01X+150706Y+122940X0200Y         S2      
017m1677            VIA   -    M      A18X+150706Y+122940X0260Y         S2      
017m1677                  -    MD0100PA00X+150706Y+122940                       
327m1677            PEX3  -L16        A01X+157244Y+121732X0180Y         S1      
327m1678            U5    -A9         A01X+090184Y+083742X0160Y    R180 S1      
317m1678            VIA   -    MD0100PA00X+090027Y+083899X0180Y    R090 S0      
317m1678            VIA   -    M      A01X+132650Y+092550X0200Y         S2      
017m1678            VIA   -    M      A18X+132650Y+092550X0260Y         S2      
017m1678                  -    MD0100PA00X+132650Y+092550                       
317m1678            VIA   -    MD0100PA00X+088276Y+093347X0200Y         S0      
327m1678            R3546 -1   M      A01X+132650Y+092308X0198Y0197R270 S1      
327m1678            R6283 -2          A01X+132250Y+091992X0198Y0197R270 S1      
327m1679            VIA   -    M      A01X+137160Y+081740X0300Y         S1      
327m1679            U6    -AB19       A01X+137202Y+083144X0160Y         S1      
327m1679            R4152 -2          A01X+137300Y+080958X0198Y0197R090 S1      
327m1680            PU69  -8          A01X+125134Y+022506X0110Y0240     S1      
317m1680            VIA   -    M      A01X+125285Y+022782X0200Y    R090 S2      
017m1680            VIA   -    M      A18X+125285Y+022782X0260Y    R090 S2      
017m1680                  -    MD0100PA00X+125285Y+022782                       
327m1680            R4511 -1          A01X+125201Y+024168X0198Y0197     S1      
327m1680            R901  -2   M      A01X+125346Y+023298X0198Y0197R270 S1      
327m1681            R1074 -2          A01X+105565Y+031924X0198Y0197R180 S1      
327m1681            U113  -A31        A01X+103761Y+032306X0070Y0220R270 S1      
327PEX1_MODE_SEL3   PEX1  -AV27       A01X+069941Y+111634X0180Y         S1      
317PEX1_MODE_SEL3   VIA   -    MD0080PA00X+070128Y+111821X0160Y         S0      
327PEX1_MODE_SEL3   R1292 -2          A01X+057292Y+099196X0198Y0197R270 S1      
327PEX1_MODE_SEL3   R1272 -1          A01X+057292Y+098611X0198Y0197R270 S1      
317PEX1_MODE_SEL3   VIA   -    MD0100PA00X+057292Y+098881X0200Y         S0      
327PEX1_MODE_SEL3   VIA   -    M      A18X+069008Y+105876X0260Y         S2      
317PEX3_SPARE2      VIA   -    MD0080PA00X+161358Y+121732X0160Y         S0      
327PEX3_SPARE2      PEX3  -L27        A01X+161358Y+121732X0180Y         S1      
327PEX3_SPARE2      VIA   -    M      A18X+170914Y+123395X0260Y         S2      
327PEX3_SPARE2      R1452 -2          A01X+172525Y+121781X0198Y0197R135 S1      
327PEX3_SPARE2      R1441 -1          A01X+172078Y+122136X0198Y0197R135 S1      
317PEX3_SPARE2      VIA   -    MD0100PA00X+172320Y+121990X0200Y         S0      
327m1682            R1073 -2          A01X+105565Y+032284X0198Y0197R180 S1      
327m1682            U113  -A32        A01X+103761Y+032502X0070Y0220R270 S1      
327PEX0_MODE_SEL6   PEX0  -AV31       A01X+025728Y+111634X0180Y         S1      
317PEX0_MODE_SEL6   VIA   -    MD0080PA00X+025915Y+111821X0160Y         S0      
327PEX0_MODE_SEL6   R1199 -2          A01X+014384Y+099196X0198Y0197R270 S1      
327PEX0_MODE_SEL6   R1158 -1          A01X+014384Y+098611X0198Y0197R270 S1      
317PEX0_MODE_SEL6   VIA   -    M      A01X+014384Y+098881X0200Y         S2      
017PEX0_MODE_SEL6   VIA   -    M      A18X+014384Y+098881X0260Y         S2      
017PEX0_MODE_SEL6         -    MD0100PA00X+014384Y+098881                       
327m1683            PEX1  -AW32       A01X+071811Y+111260X0180Y         S1      
317m1683            VIA   -    MD0080PA00X+071998Y+111447X0160Y         S0      
327m1683            VIA   -    M      A18X+070725Y+105579X0260Y         S2      
317m1683            VIA   -    MD0100PA00X+059692Y+098881X0200Y         S0      
327m1683            R1281 -1          A01X+059692Y+098611X0198Y0197R270 S1      
327m1683            R1301 -2          A01X+059692Y+099196X0198Y0197R270 S1      
317PEX3_SPARE3      VIA   -    MD0080PA00X+163415Y+121545X0160Y    R270 S0      
327PEX3_SPARE3      VIA   -    M      A18X+170250Y+122106X0260Y         S2      
327PEX3_SPARE3      R1451 -2          A01X+172566Y+119857X0198Y0197R090 S1      
327PEX3_SPARE3      R1440 -1          A01X+172566Y+120344X0198Y0197R090 S1      
317PEX3_SPARE3      VIA   -    MD0100PA00X+172566Y+120104X0200Y         S0      
327PEX3_SPARE3      PEX3  -L32        A01X+163228Y+121732X0180Y         S1      
317m1684            VIA   -    MD0100PA00X+137045Y+083617X0180Y         S0      
327m1684            U6    -Y18        A01X+136887Y+083774X0160Y         S1      
327m1684            R6186 -2          A18X+091663Y+092255X0198Y0197R090 S2      
327m1684            R4518 -2          A18X+091529Y+091191X0198Y0197R270 S2      
317m1684            VIA   -    M      A01X+091663Y+091804X0200Y         S2      
017m1684            VIA   -    M      A18X+091663Y+091804X0260Y         S2      
017m1684                  -    MD0100PA00X+091663Y+091804                       
317m1684            VIA   -    MD0100PA00X+104110Y+083850X0200Y         S0      
327m1685            U114  -M2         A01X+051367Y+068858X0090Y         S1      
327m1685            R1090 -2          A01X+050546Y+067323X0198Y0197R090 S1      
317m1686            VIA   -    M      A01X+041657Y+035753X0200Y         S2      
017m1686            VIA   -    M      A18X+041657Y+035753X0260Y         S2      
017m1686                  -    MD0100PA00X+041657Y+035753                       
327m1686            R1130 -2          A01X+041232Y+036207X0198Y0197R270 S1      
327m1686            U115  -48         A01X+041984Y+035011X0070Y0340R180 S1      
327m1686            R1133 -1   M      A01X+041632Y+036207X0198Y0197R090 S1      
327m1687            PEX1  -AV32       A01X+071811Y+111634X0180Y         S1      
317m1687            VIA   -    MD0080PA00X+071998Y+111821X0160Y         S0      
327m1687            R1299 -2          A01X+060492Y+099196X0198Y0197R270 S1      
327m1687            R1279 -1          A01X+060492Y+098611X0198Y0197R270 S1      
317m1687            VIA   -    MD0100PA00X+060492Y+098881X0200Y         S0      
327m1687            VIA   -    M      A18X+072282Y+106461X0260Y         S2      
317TP_PEX3_TMS      VIA   -    MD0080PA00X+158553Y+121171X0160Y         S0      
327TP_PEX3_TMS      VIA   -           A18X+158366Y+120984X0260Y         S2      
327TP_PEX3_TMS      PEX3  -M20        A01X+158740Y+121358X0180Y         S1      
327m1688            R4687 -2          A01X+143742Y+078650X0198Y0197R180 S1      
327m1688            R4661 -2   M      A01X+143258Y+078650X0198Y0197     S1      
317m1688            VIA   -    MD0100PA00X+137045Y+082987X0180Y         S0      
327m1688            U6    -AB18       A01X+136887Y+083144X0160Y         S1      
327m1688            R4674 -1   M      A01X+143258Y+079050X0198Y0197R180 S1      
317m1688            VIA   -    M      A01X+141460Y+079238X0200Y         S2      
017m1688            VIA   -    M      A18X+141460Y+079238X0260Y         S2      
017m1688                  -    MD0100PA00X+141460Y+079238                       
327PEX0_MODE_SEL5   R1196 -2          A01X+010784Y+099196X0198Y0197R270 S1      
327PEX0_MODE_SEL5   R1157 -1          A01X+010784Y+098611X0198Y0197R270 S1      
317PEX0_MODE_SEL5   VIA   -    MD0100PA00X+010784Y+098881X0200Y         S0      
327PEX0_MODE_SEL5   VIA   -    M      A18X+022417Y+105598X0260Y         S2      
327PEX0_MODE_SEL5   PEX0  -AW25       A01X+023484Y+111260X0180Y         S1      
317PEX0_MODE_SEL5   VIA   -    MD0080PA00X+023671Y+111447X0160Y         S0      
327PEX1_DBG_MODE1   R1285 -2          A01X+059148Y+121141X0198Y0197R045 S1      
327PEX1_DBG_MODE1   R1265 -1   M      A01X+058866Y+121424X0198Y0197R225 S1      
317PEX1_DBG_MODE1   VIA   -    M      A01X+059418Y+122007X0200Y         S2      
017PEX1_DBG_MODE1   VIA   -    M      A18X+059418Y+122007X0260Y         S2      
017PEX1_DBG_MODE1         -    MD0100PA00X+059418Y+122007                       
327PEX1_DBG_MODE1   PEX1  -L13        A01X+064705Y+121732X0180Y         S1      
317PEX1_DBG_MODE1   VIA   -    MD0080PA00X+064892Y+121545X0160Y    R180 S0      
317PEX3_SPARE4      VIA   -    MD0080PA00X+160797Y+121171X0160Y    R270 S0      
327PEX3_SPARE4      PEX3  -M25        A01X+160610Y+121358X0180Y         S1      
317PEX3_SPARE4      VIA   -    MD0100PA00X+172166Y+120104X0200Y         S0      
327PEX3_SPARE4      R1450 -2          A01X+172166Y+119857X0198Y0197R090 S1      
327PEX3_SPARE4      R1439 -1          A01X+172166Y+120344X0198Y0197R090 S1      
327PEX3_SPARE4      VIA   -    M      A18X+171741Y+119560X0260Y         S2      
327m1689            J30   -B10        A01X+006010Y+009524X0150Y0500R090 S1      
317m1689            VIA   -    MD0100PA00X+005592Y+009524X0200Y         S0      
327m1689            R3584 -2          A01X+134995Y+094918X0198Y0197R090 S1      
317m1689            VIA   -    MD0100PA00X+132243Y+098822X0200Y         S0      
317m1689            VIA   -    M      A01X+013686Y+085724X0200Y         S2      
017m1689            VIA   -    M      A18X+013686Y+085724X0260Y         S2      
017m1689                  -    MD0100PA00X+013686Y+085724                       
317m1690            VIA   -    MD0100PA00X+136100Y+084562X0180Y         S0      
327m1690            U6    -U15        A01X+135942Y+084719X0160Y         S1      
327m1690            R4614 -1          A01X+141558Y+073300X0198Y0197R180 S1      
327m1690            R4601 -2   M      A01X+141558Y+072900X0198Y0197     S1      
327m1690            R4647 -2          A01X+142042Y+072900X0198Y0197R180 S1      
317m1690            VIA   -    M      A01X+141800Y+072900X0200Y         S2      
017m1690            VIA   -    M      A18X+141800Y+072900X0260Y         S2      
017m1690                  -    MD0100PA00X+141800Y+072900                       
327P3V3_SSD11_SS    PU69  -7          A01X+125331Y+022506X0110Y0240     S1      
317P3V3_SSD11_SS    VIA   -    M      A01X+125744Y+023012X0200Y    R090 S2      
017P3V3_SSD11_SS    VIA   -    M      A18X+125744Y+023012X0260Y    R090 S2      
017P3V3_SSD11_SS          -    MD0100PA00X+125744Y+023012                       
327P3V3_SSD11_SS    PC591 -1          A01X+125746Y+023298X0198Y0197R090 S1      
327PEX1_DBG_MODE3   PEX1  -AW26       A01X+069567Y+111260X0180Y         S1      
317PEX1_DBG_MODE3   VIA   -    MD0080PA00X+069754Y+111447X0160Y         S0      
327PEX1_DBG_MODE3   R1287 -2          A01X+056892Y+099196X0198Y0197R270 S1      
327PEX1_DBG_MODE3   R1267 -1          A01X+056892Y+098611X0198Y0197R270 S1      
317PEX1_DBG_MODE3   VIA   -    M      A01X+056892Y+098881X0200Y         S2      
017PEX1_DBG_MODE3   VIA   -    M      A18X+056892Y+098881X0260Y         S2      
017PEX1_DBG_MODE3         -    MD0100PA00X+056892Y+098881                       
317PEX3_SPARE7      VIA   -    MD0080PA00X+161545Y+121545X0160Y         S0      
327PEX3_SPARE7      PEX3  -M27        A01X+161358Y+121358X0180Y         S1      
327PEX3_SPARE7      R1457 -2          A01X+172242Y+121499X0198Y0197R135 S1      
327PEX3_SPARE7      R1446 -1          A01X+171795Y+121854X0198Y0197R135 S1      
317PEX3_SPARE7      VIA   -    MD0100PA00X+172054Y+121723X0200Y         S0      
327PEX3_SPARE7      VIA   -    M      A18X+171657Y+122120X0260Y         S2      
327SMB_GPU_2_SCL    VIA   -    M      A18X+039045Y+149136X0260Y         S2      
327SMB_GPU_2_SCL    R1831 -2          A18X+038841Y+148578X0198Y0197     S2      
317SMB_GPU_2_SCL    J11   -R9   D0122PA00X+035240Y+149445X0282Y    R180 S3      
317m1691            J5    -A7   D0122PA00X+068154Y+162240X0282Y    R180 S3      
317m1691            VIA   -    M      A01X+058381Y+153302X0200Y         S2      
017m1691            VIA   -    M      A18X+058381Y+153302X0260Y         S2      
017m1691                  -    MD0100PA00X+058381Y+153302                       
327m1691            R1843 -1          A01X+058381Y+153543X0198Y0197R090 S1      
317m1692            VIA   -    MD0100PA00X+136100Y+084877X0180Y         S0      
327m1692            U6    -T15        A01X+135942Y+085034X0160Y         S1      
327m1692            R4668 -2          A01X+143258Y+076650X0198Y0197     S1      
327m1692            R4692 -2          A01X+143742Y+076650X0198Y0197R180 S1      
317m1692            VIA   -    M      A01X+143500Y+076550X0200Y         S2      
017m1692            VIA   -    M      A18X+143500Y+076550X0260Y         S2      
017m1692                  -    MD0100PA00X+143500Y+076550                       
327PEX0_MODE_SEL4   VIA   -    M      A18X+023032Y+105004X0260Y         S2      
317PEX0_MODE_SEL4   VIA   -    MD0100PA00X+012384Y+098881X0200Y         S0      
327PEX0_MODE_SEL4   R1195 -2          A01X+012384Y+099196X0198Y0197R270 S1      
327PEX0_MODE_SEL4   R1156 -1          A01X+012384Y+098611X0198Y0197R270 S1      
327PEX0_MODE_SEL4   PEX0  -AW28       A01X+024606Y+111260X0180Y         S1      
317PEX0_MODE_SEL4   VIA   -    MD0080PA00X+024793Y+111447X0160Y         S0      
327PEX1_MODE_SEL7   PEX1  -AV26       A01X+069567Y+111634X0180Y         S1      
317PEX1_MODE_SEL7   VIA   -    MD0080PA00X+069754Y+111821X0160Y         S0      
327PEX1_MODE_SEL7   R1296 -2          A01X+055692Y+099196X0198Y0197R270 S1      
327PEX1_MODE_SEL7   R1276 -1          A01X+055692Y+098611X0198Y0197R270 S1      
317PEX1_MODE_SEL7   VIA   -    MD0100PA00X+055692Y+098881X0200Y         S0      
327PEX1_MODE_SEL7   VIA   -    M      A18X+068209Y+106285X0260Y         S2      
317PEX3_SPARE5      VIA   -    MD0080PA00X+160797Y+121545X0160Y    R270 S0      
327PEX3_SPARE5      VIA   -    M      A01X+172955Y+123079X0300Y         S1      
327PEX3_SPARE5      PEX3  -L25        A01X+160610Y+121732X0180Y         S1      
327PEX3_SPARE5      R1449 -2          A01X+173374Y+122630X0198Y0197R135 S1      
327PEX3_SPARE5      R1438 -1          A01X+172644Y+122702X0198Y0197R135 S1      
317PEX3_SPARE5      VIA   -    MD0100PA00X+173153Y+122823X0200Y         S0      
327m1693            R1472 -1          A01X+129858Y+033000X0198Y0197R180 S1      
317m1693            VIA   -    M      A01X+131224Y+033468X0200Y         S2      
017m1693            VIA   -    M      A18X+131224Y+033468X0260Y         S2      
017m1693                  -    MD0100PA00X+131224Y+033468                       
327m1693            U116  -7          A01X+131947Y+034080X0070Y0340R270 S1      
327m1694            U6    -V17        A01X+136572Y+084404X0160Y         S1      
317m1694            VIA   -    MD0100PA00X+136730Y+084247X0180Y         S0      
317m1694            VIA   -    M      A01X+105155Y+082315X0200Y         S2      
017m1694            VIA   -    M      A18X+105155Y+082315X0260Y         S2      
017m1694                  -    MD0100PA00X+105155Y+082315                       
317m1694            VIA   -    MD0100PA00X+093263Y+091524X0200Y         S0      
327m1694            R6188 -2          A01X+093263Y+092255X0198Y0197R270 S1      
327m1694            R4520 -2          A01X+093263Y+091266X0198Y0197R090 S1      
327P3V3_SSD14_SS    PU67  -7          A01X+160804Y+022506X0110Y0240     S1      
317P3V3_SSD14_SS    VIA   -    M      A01X+161217Y+023012X0200Y    R090 S2      
017P3V3_SSD14_SS    VIA   -    M      A18X+161217Y+023012X0260Y    R090 S2      
017P3V3_SSD14_SS          -    MD0100PA00X+161217Y+023012                       
327P3V3_SSD14_SS    PC579 -1          A01X+161218Y+023298X0198Y0197R090 S1      
327m1695            R1085 -2          A01X+051346Y+067323X0198Y0197R090 S1      
327m1695            U114  -M4         A01X+051760Y+068858X0090Y         S1      
317PEX1_DBG_SEL1    VIA   -    M      A01X+058352Y+123041X0200Y         S2      
017PEX1_DBG_SEL1    VIA   -    M      A18X+058352Y+123041X0260Y         S2      
017PEX1_DBG_SEL1          -    MD0100PA00X+058352Y+123041                       
327PEX1_DBG_SEL1    R1283 -2   M      A01X+057452Y+122838X0198Y0197R045 S1      
327PEX1_DBG_SEL1    R1263 -1          A01X+056669Y+122660X0198Y0197R270 S1      
327PEX1_DBG_SEL1    PEX1  -M19        A01X+066949Y+121358X0180Y         S1      
317PEX1_DBG_SEL1    VIA   -    MD0080PA00X+066762Y+121545X0160Y         S0      
317PEX3_SPARE0      VIA   -    MD0080PA00X+161171Y+121545X0160Y         S0      
327PEX3_SPARE0      VIA   -    M      A18X+171444Y+123754X0260Y         S2      
327PEX3_SPARE0      R1443 -1          A01X+172361Y+122419X0198Y0197R135 S1      
327PEX3_SPARE0      R1454 -2          A01X+172808Y+122064X0198Y0197R135 S1      
317PEX3_SPARE0      VIA   -    MD0100PA00X+172648Y+122317X0200Y         S0      
327PEX3_SPARE0      PEX3  -M26        A01X+160984Y+121358X0180Y         S1      
327m1696            R1471 -1          A01X+129858Y+033350X0198Y0197R180 S1      
317m1696            VIA   -    M      A01X+131310Y+033961X0200Y         S2      
017m1696            VIA   -    M      A18X+131310Y+033961X0260Y         S2      
017m1696                  -    MD0100PA00X+131310Y+033961                       
327m1696            U116  -6          A01X+131947Y+034238X0070Y0340R270 S1      
327m1697            C4100 -2          A01X+059501Y+150146X0198Y0197R180 S1      
317m1697            VIA   -    M      A01X+059149Y+150169X0200Y         S2      
017m1697            VIA   -    M      A18X+059149Y+150169X0260Y         S2      
017m1697                  -    MD0100PA00X+059149Y+150169                       
317m1697            J5    -Z6   D0122PA00X+067287Y+145272X0282Y    R180 S3      
327m1697            R1842 -2          A01X+058851Y+150169X0198Y0197     S1      
327SSD15_PWRDIS     VIA   -    M      A01X+136100Y+081420X0300Y         S1      
327SSD15_PWRDIS     U6    -AB13       A01X+135312Y+083144X0160Y         S1      
327SSD15_PWRDIS     R4144 -2          A01X+136100Y+080958X0198Y0197R090 S1      
327m1698            PU64  -8          A01X+104662Y+022506X0110Y0240     S1      
317m1698            VIA   -    M      A01X+104813Y+022782X0200Y    R090 S2      
017m1698            VIA   -    M      A18X+104813Y+022782X0260Y    R090 S2      
017m1698                  -    MD0100PA00X+104813Y+022782                       
327m1698            R4502 -1          A01X+104729Y+024168X0198Y0197     S1      
327m1698            R896  -2   M      A01X+104874Y+023298X0198Y0197R270 S1      
327PEX0_MODE_SEL3   R1193 -2          A01X+011584Y+099196X0198Y0197R270 S1      
327PEX0_MODE_SEL3   R1155 -1          A01X+011584Y+098611X0198Y0197R270 S1      
317PEX0_MODE_SEL3   VIA   -    MD0100PA00X+011584Y+098881X0200Y         S0      
327PEX0_MODE_SEL3   VIA   -    M      A18X+023300Y+105876X0260Y         S2      
327PEX0_MODE_SEL3   PEX0  -AV27       A01X+024232Y+111634X0180Y         S1      
317PEX0_MODE_SEL3   VIA   -    MD0080PA00X+024419Y+111821X0160Y         S0      
327PEX1_MODE_SEL9   PEX1  -AV28       A01X+070315Y+111634X0180Y         S1      
317PEX1_MODE_SEL9   VIA   -    MD0080PA00X+070502Y+111821X0160Y         S0      
317PEX1_MODE_SEL9   VIA   -    M      A01X+055292Y+098881X0200Y         S2      
017PEX1_MODE_SEL9   VIA   -    M      A18X+055292Y+098881X0260Y         S2      
017PEX1_MODE_SEL9         -    MD0100PA00X+055292Y+098881                       
327PEX1_MODE_SEL9   R1298 -2          A01X+055292Y+099196X0198Y0197R270 S1      
327PEX1_MODE_SEL9   R1278 -1          A01X+055292Y+098611X0198Y0197R270 S1      
317PEX3_SPARE1      VIA   -    MD0080PA00X+162667Y+121545X0160Y    R270 S0      
327PEX3_SPARE1      VIA   -    M      A18X+170616Y+122451X0260Y         S2      
327PEX3_SPARE1      R1453 -2          A01X+172966Y+119857X0198Y0197R090 S1      
327PEX3_SPARE1      R1442 -1          A01X+172966Y+120344X0198Y0197R090 S1      
317PEX3_SPARE1      VIA   -    MD0100PA00X+172963Y+120104X0200Y         S0      
327PEX3_SPARE1      PEX3  -L30        A01X+162480Y+121732X0180Y         S1      
327m1699            PU32  -8          A01X+019743Y+021120X0110Y0240R270 S1      
317m1699            VIA   -    M      A01X+020133Y+020704X0200Y         S2      
017m1699            VIA   -    M      A18X+020133Y+020704X0260Y         S2      
017m1699                  -    MD0100PA00X+020133Y+020704                       
327m1699            R863  -2          A01X+020420Y+020486X0198Y0197R180 S1      
327m1699            R4460 -1   M      A01X+020420Y+020886X0198Y0197     S1      
317m1700            VIA   -    M      A01X+141800Y+072400X0200Y         S2      
017m1700            VIA   -    M      A18X+141800Y+072400X0260Y         S2      
017m1700                  -    MD0100PA00X+141800Y+072400                       
327m1700            R4607 -2          A01X+141558Y+072500X0198Y0197     S1      
327m1700            R4648 -2          A01X+142042Y+072500X0198Y0197R180 S1      
317m1700            VIA   -    MD0100PA00X+136730Y+082987X0180Y         S0      
327m1700            U6    -AB17       A01X+136572Y+083144X0160Y         S1      
327P3V3_SSD15_SS    PU68  -7          A01X+171040Y+022506X0110Y0240     S1      
317P3V3_SSD15_SS    VIA   -    M      A01X+171453Y+023012X0200Y    R090 S2      
017P3V3_SSD15_SS    VIA   -    M      A18X+171453Y+023012X0260Y    R090 S2      
017P3V3_SSD15_SS          -    MD0100PA00X+171453Y+023012                       
327P3V3_SSD15_SS    PC590 -1          A01X+171455Y+023298X0198Y0197R090 S1      
327m1701            PEX1  -AW31       A01X+071437Y+111260X0180Y         S1      
317m1701            VIA   -    MD0080PA00X+071624Y+111447X0160Y         S0      
327m1701            R1300 -2          A01X+059292Y+099196X0198Y0197R270 S1      
327m1701            R1280 -1          A01X+059292Y+098611X0198Y0197R270 S1      
317m1701            VIA   -    M      A01X+059292Y+098881X0200Y         S2      
017m1701            VIA   -    M      A18X+059292Y+098881X0260Y         S2      
017m1701                  -    MD0100PA00X+059292Y+098881                       
317TP_PEX3_TDI      VIA   -    MD0080PA00X+157431Y+121545X0160Y    R090 S0      
327TP_PEX3_TDI      PEX3  -L17        A01X+157618Y+121732X0180Y         S1      
327TP_PEX3_TDI      VIA   -           A18X+157618Y+121732X0260Y         S2      
317m1702            VIA   -    M      A01X+059083Y+149569X0200Y    R270 S2      
017m1702            VIA   -    M      A18X+059083Y+149569X0260Y    R270 S2      
017m1702                  -    MD0100PA00X+059083Y+149569                       
317m1702            J5    -Z4   D0122PA00X+065555Y+145272X0282Y    R180 S3      
327m1702            R1840 -2          A01X+058851Y+149769X0198Y0197     S1      
327m1702            C4098 -2   M      A01X+059491Y+149756X0198Y0197R180 S1      
327m1703            VIA   -    M      A01X+135700Y+081750X0300Y         S1      
327m1703            U6    -AA13       A01X+135312Y+083460X0160Y         S1      
327m1703            R4145 -2          A01X+135700Y+080958X0198Y0197R090 S1      
327PEX0_MODE_SEL2   R6426 -2          A01X+161133Y+073242X0198Y0197R180 S1      
317PEX0_MODE_SEL2   VIA   -    MD0100PA00X+161133Y+073597X0200Y         S0      
317PEX0_MODE_SEL2   VIA   -    MD0100PA00X+116015Y+069949X0200Y         S0      
317PEX0_MODE_SEL2   VIA   -    MD0100PA00X+088164Y+074415X0200Y         S0      
317PEX0_MODE_SEL2   VIA   -    MD0100PA00X+071322Y+079081X0200Y         S0      
327PEX0_MODE_SEL2   R1154 -1          A01X+010384Y+098611X0198Y0197R270 S1      
327PEX0_MODE_SEL2   R1192 -2          A01X+010384Y+099196X0198Y0197R270 S1      
317PEX0_MODE_SEL2   VIA   -    M      A01X+010384Y+098881X0200Y         S2      
017PEX0_MODE_SEL2   VIA   -    M      A18X+010384Y+098881X0260Y         S2      
017PEX0_MODE_SEL2         -    MD0100PA00X+010384Y+098881                       
327PEX0_MODE_SEL2   PEX0  -AV25       A01X+023484Y+111634X0180Y         S1      
317PEX0_MODE_SEL2   VIA   -    MD0080PA00X+023671Y+111821X0160Y         S0      
327PEX1_DBG_MODE0   R1284 -2          A01X+058300Y+121990X0198Y0197R045 S1      
327PEX1_DBG_MODE0   R1264 -1          A01X+058017Y+122272X0198Y0197R225 S1      
317PEX1_DBG_MODE0   VIA   -    MD0100PA00X+058650Y+122730X0200Y         S0      
327PEX1_DBG_MODE0   VIA   -    M      A18X+059299Y+121504X0260Y         S2      
327PEX1_DBG_MODE0   PEX1  -L12        A01X+064331Y+121732X0180Y         S1      
317PEX1_DBG_MODE0   VIA   -    MD0080PA00X+064144Y+121545X0160Y         S0      
317PEX3_SPARE6      VIA   -    MD0080PA00X+161919Y+121545X0160Y    R270 S0      
327PEX3_SPARE6      PEX3  -L28        A01X+161732Y+121732X0180Y         S1      
327PEX3_SPARE6      VIA   -    M      A18X+170228Y+123228X0260Y         S2      
327PEX3_SPARE6      R1456 -2          A01X+173366Y+119857X0198Y0197R090 S1      
327PEX3_SPARE6      R1445 -1          A01X+173366Y+120344X0198Y0197R090 S1      
317PEX3_SPARE6      VIA   -    MD0100PA00X+173366Y+120104X0200Y         S0      
327m1704            R4105 -2          A01X+056279Y+153453X0198Y0197R270 S1      
317m1704            VIA   -    MD0100PA00X+057243Y+152146X0200Y         S0      
317m1704            VIA   -    MD0100PA00X+079285Y+141472X0200Y         S0      
317m1704            VIA   -    MD0100PA00X+090291Y+129983X0200Y         S0      
317m1704            VIA   -    MD0100PA00X+091300Y+096960X0200Y         S0      
317m1704            VIA   -    MD0100PA00X+120203Y+099835X0200Y         S0      
327m1704            VIA   -    M      A18X+119348Y+098305X0260Y    R270 S2      
327m1704            R4104 -1          A18X+120722Y+097086X0198Y0197R090 S2      
327m1704            U318  -7   M      A18X+119336Y+097672X0170Y0460R180 S2      
327m1704            R4098 -1   M      A18X+119322Y+099286X0198Y0197R090 S2      
317m1705            VIA   -    MD0100PA00X+136100Y+083932X0180Y         S0      
327m1705            U6    -W15        A01X+135942Y+084089X0160Y         S1      
327m1705            R4606 -2          A01X+141558Y+074100X0198Y0197     S1      
327m1705            R4644 -2          A01X+142042Y+074100X0198Y0197R180 S1      
317m1705            VIA   -    M      A01X+141800Y+074000X0200Y         S2      
017m1705            VIA   -    M      A18X+141800Y+074000X0260Y         S2      
017m1705                  -    MD0100PA00X+141800Y+074000                       
327PEX1_DBG_MODE4   PEX1  -AW34       A01X+072559Y+111260X0180Y         S1      
317PEX1_DBG_MODE4   VIA   -    MD0080PA00X+072746Y+111447X0160Y         S0      
317PEX1_DBG_MODE4   VIA   -    M      A01X+060892Y+098881X0200Y         S2      
017PEX1_DBG_MODE4   VIA   -    M      A18X+060892Y+098881X0260Y         S2      
017PEX1_DBG_MODE4         -    MD0100PA00X+060892Y+098881                       
327PEX1_DBG_MODE4   R1268 -1          A01X+060892Y+098611X0198Y0197R270 S1      
327PEX1_DBG_MODE4   R1288 -2          A01X+060892Y+099196X0198Y0197R270 S1      
317m1706            VIA   -    MD0080PA00X+156683Y+121919X0160Y         S0      
327m1706            R1462 -1          A01X+150000Y+121707X0198Y0197R225 S1      
317m1706            VIA   -    MD0100PA00X+150769Y+122447X0200Y         S0      
327m1706            VIA   -    M      A18X+151155Y+122426X0260Y         S2      
327m1706            PEX3  -L15        A01X+156870Y+121732X0180Y         S1      
317m1707            J5    -A5   D0122PA00X+066421Y+162240X0282Y    R180 S3      
327m1707            C4099 -2          A01X+058786Y+152389X0198Y0197R090 S1      
317m1707            VIA   -    M      A01X+058781Y+152839X0200Y         S2      
017m1707            VIA   -    M      A18X+058781Y+152839X0260Y         S2      
017m1707                  -    MD0100PA00X+058781Y+152839                       
327m1707            R1841 -2          A01X+058781Y+153543X0198Y0197R270 S1      
327m1708            PU65  -8          A01X+150370Y+022506X0110Y0240     S1      
317m1708            VIA   -    M      A01X+150522Y+022782X0200Y    R090 S2      
017m1708            VIA   -    M      A18X+150522Y+022782X0260Y    R090 S2      
017m1708                  -    MD0100PA00X+150522Y+022782                       
327m1708            R4503 -1          A01X+150437Y+024168X0198Y0197     S1      
327m1708            R897  -2   M      A01X+150582Y+023298X0198Y0197R270 S1      
327PEX0_MODE_SEL1   PEX0  -AW38       A01X+028346Y+111260X0180Y         S1      
317PEX0_MODE_SEL1   VIA   -    MD0080PA00X+028533Y+111447X0160Y         S0      
327PEX0_MODE_SEL1   R6429 -2          A01X+161658Y+076143X0198Y0197R270 S1      
317PEX0_MODE_SEL1   VIA   -    MD0100PA00X+161257Y+076143X0200Y         S0      
317PEX0_MODE_SEL1   VIA   -    MD0100PA00X+116265Y+069949X0200Y         S0      
317PEX0_MODE_SEL1   VIA   -    MD0100PA00X+088446Y+074476X0200Y         S0      
317PEX0_MODE_SEL1   VIA   -    MD0100PA00X+071322Y+079331X0200Y         S0      
317PEX0_MODE_SEL1   VIA   -    M      A01X+015984Y+098881X0200Y         S2      
017PEX0_MODE_SEL1   VIA   -    M      A18X+015984Y+098881X0260Y         S2      
017PEX0_MODE_SEL1         -    MD0100PA00X+015984Y+098881                       
327PEX0_MODE_SEL1   R1191 -2          A01X+015984Y+099196X0198Y0197R270 S1      
327PEX0_MODE_SEL1   R1153 -1          A01X+015984Y+098611X0198Y0197R270 S1      
317PEX1_DBG_SEL0    VIA   -    M      A01X+056914Y+121437X0200Y    R315 S2      
017PEX1_DBG_SEL0    VIA   -    M      A18X+056914Y+121437X0260Y    R315 S2      
017PEX1_DBG_SEL0          -    MD0100PA00X+056914Y+121437                       
327PEX1_DBG_SEL0    R1282 -2          A01X+056885Y+121011X0198Y0197R045 S1      
327PEX1_DBG_SEL0    R1262 -1   M      A01X+056602Y+121294X0198Y0197R225 S1      
327PEX1_DBG_SEL0    PEX1  -L18        A01X+066575Y+121732X0180Y         S1      
317PEX1_DBG_SEL0    VIA   -    MD0080PA00X+066388Y+121545X0160Y         S0      
317TP_PEX3_TDO      VIA   -    MD0080PA00X+158553Y+121545X0160Y    R180 S0      
327TP_PEX3_TDO      PEX3  -L19        A01X+158366Y+121732X0180Y         S1      
327TP_PEX3_TDO      VIA   -           A18X+158366Y+121732X0260Y         S2      
317m1709            J11   -F9   D0122PA00X+035240Y+159681X0282Y    R180 S3      
317m1709            VIA   -    M      A01X+024594Y+152424X0200Y         S2      
017m1709            VIA   -    M      A18X+024594Y+152424X0260Y         S2      
017m1709                  -    MD0100PA00X+024594Y+152424                       
327m1709            R1829 -2          A01X+023262Y+152658X0198Y0197     S1      
327m1709            C4041 -2   M      A01X+024084Y+152731X0198Y0197R270 S1      
327m1710            VIA   -    M      A01X+136838Y+081431X0300Y         S1      
327m1710            U6    -AA15       A01X+135942Y+083460X0160Y         S1      
327m1710            R4149 -2          A01X+136900Y+080958X0198Y0197R090 S1      
327m1711            PU62  -8          A01X+094492Y+021023X0110Y0240     S1      
317m1711            VIA   -    M      A01X+094623Y+021339X0200Y    R090 S2      
017m1711            VIA   -    M      A18X+094623Y+021339X0260Y    R090 S2      
017m1711                  -    MD0100PA00X+094623Y+021339                       
327m1711            R4498 -1          A01X+094559Y+022685X0198Y0197     S1      
327m1711            R894  -2   M      A01X+094704Y+021816X0198Y0197R270 S1      
327PEX1_DBG_MODE2   PEX1  -AW30       A01X+071063Y+111260X0180Y         S1      
317PEX1_DBG_MODE2   VIA   -    MD0080PA00X+071250Y+111447X0160Y         S0      
327PEX1_DBG_MODE2   R1286 -2          A01X+058892Y+099196X0198Y0197R270 S1      
327PEX1_DBG_MODE2   R1266 -1          A01X+058892Y+098611X0198Y0197R270 S1      
317PEX1_DBG_MODE2   VIA   -    MD0100PA00X+058892Y+098881X0200Y         S0      
327PEX1_DBG_MODE2   VIA   -    M      A18X+069768Y+105332X0260Y         S2      
317PEX3_DFT_IDDT    VIA   -    MD0080PA00X+157057Y+121171X0160Y         S0      
317PEX3_DFT_IDDT    VIA   -    M      A01X+148979Y+120774X0200Y    R315 S2      
017PEX3_DFT_IDDT    VIA   -    M      A18X+148979Y+120774X0260Y    R315 S2      
017PEX3_DFT_IDDT          -    MD0100PA00X+148979Y+120774                       
327PEX3_DFT_IDDT    PEX3  -M16        A01X+157244Y+121358X0180Y         S1      
327PEX3_DFT_IDDT    R1444 -1          A01X+148868Y+120445X0198Y0197R225 S1      
327PEX3_DFT_IDDT    R1455 -2   M      A01X+148585Y+120728X0198Y0197R045 S1      
327SMB_NIC7_R_SDA   R1532 -1   M      A01X+083008Y+076250X0198Y0197R180 S1      
327SMB_NIC7_R_SDA   U122  -2          A01X+083670Y+076328X0140Y0590R270 S1      
317SMB_NIC7_R_SDA   VIA   -    M      A01X+081758Y+076422X0200Y         S2      
017SMB_NIC7_R_SDA   VIA   -    M      A18X+081758Y+076422X0260Y         S2      
017SMB_NIC7_R_SDA         -    MD0100PA00X+081758Y+076422                       
327SMB_NIC7_R_SDA   R1535 -2          A18X+083500Y+076292X0198Y0197R090 S2      
317SMB_NIC7_R_SDA   VIA   -    MD0100PA00X+085124Y+084746X0200Y         S0      
327SMB_NIC7_R_SDA   R1505 -2          A01X+085368Y+084746X0198Y0197R180 S1      
327m1712            VIA   -           A18X+035324Y+163420X0260Y         S2      
317m1712            J11   -I9   D0122PA00X+035240Y+158146X0282Y    R180 S3      
317m1713            VIA   -    MD0100PA00X+135785Y+084562X0180Y         S0      
327m1713            U6    -U14        A01X+135628Y+084719X0160Y         S1      
327m1713            R6182 -2          A01X+094063Y+092255X0198Y0197R270 S1      
327m1713            R4514 -2          A01X+094063Y+091266X0198Y0197R090 S1      
317m1713            VIA   -    MD0100PA00X+094063Y+091524X0200Y         S0      
317m1713            VIA   -    M      A01X+105339Y+083279X0200Y         S2      
017m1713            VIA   -    M      A18X+105339Y+083279X0260Y         S2      
017m1713                  -    MD0100PA00X+105339Y+083279                       
327m1714            PU67  -8          A01X+160607Y+022506X0110Y0240     S1      
317m1714            VIA   -    M      A01X+160758Y+022782X0200Y    R090 S2      
017m1714            VIA   -    M      A18X+160758Y+022782X0260Y    R090 S2      
017m1714                  -    MD0100PA00X+160758Y+022782                       
327m1714            R4506 -1          A01X+160674Y+024168X0198Y0197     S1      
327m1714            R899  -2   M      A01X+160818Y+023298X0198Y0197R270 S1      
317m1715            VIA   -    M      A01X+073878Y+159787X0200Y    R090 S2      
017m1715            VIA   -    M      A18X+073878Y+159787X0260Y    R090 S2      
017m1715                  -    MD0100PA00X+073878Y+159787                       
327m1715            U338  -1          A01X+074222Y+159442X0250Y0480R180 S1      
327m1715            R4417 -1          A01X+073539Y+159919X0198Y0197R090 S1      
317PEX0_MODE_SEL0   VIA   -    M      A01X+011984Y+098881X0200Y         S2      
017PEX0_MODE_SEL0   VIA   -    M      A18X+011984Y+098881X0260Y         S2      
017PEX0_MODE_SEL0         -    MD0100PA00X+011984Y+098881                       
327PEX0_MODE_SEL0   R1190 -2          A01X+011984Y+099196X0198Y0197R270 S1      
327PEX0_MODE_SEL0   R1152 -1          A01X+011984Y+098611X0198Y0197R270 S1      
327PEX0_MODE_SEL0   PEX0  -AW27       A01X+024232Y+111260X0180Y         S1      
317PEX0_MODE_SEL0   VIA   -    MD0080PA00X+024419Y+111447X0160Y         S0      
327PEX1_MODE_SEL4   PEX1  -AW28       A01X+070315Y+111260X0180Y         S1      
317PEX1_MODE_SEL4   VIA   -    MD0080PA00X+070502Y+111447X0160Y         S0      
327PEX1_MODE_SEL4   VIA   -    M      A18X+068741Y+105004X0260Y         S2      
317PEX1_MODE_SEL4   VIA   -    MD0100PA00X+058092Y+098881X0200Y         S0      
327PEX1_MODE_SEL4   R1293 -2          A01X+058092Y+099196X0198Y0197R270 S1      
327PEX1_MODE_SEL4   R1273 -1          A01X+058092Y+098611X0198Y0197R270 S1      
317PU_PEX3_TR_TCK   VIA   -    MD0080PA00X+158927Y+121545X0160Y    R090 S0      
327PU_PEX3_TR_TCK   R1461 -1          A01X+147686Y+122660X0198Y0197R270 S1      
317PU_PEX3_TR_TCK   VIA   -    M      A01X+150681Y+123492X0200Y         S2      
017PU_PEX3_TR_TCK   VIA   -    M      A18X+150681Y+123492X0260Y         S2      
017PU_PEX3_TR_TCK         -    MD0100PA00X+150681Y+123492                       
327PU_PEX3_TR_TCK   PEX3  -L20        A01X+158740Y+121732X0180Y         S1      
317SMB_NIC3_R_SDA   VIA   -    MD0100PA00X+072210Y+044660X0200Y         S0      
327SMB_NIC3_R_SDA   J23   -A8         A01X+072739Y+044660X0140Y0480R090 S1      
317SMB_NIC3_R_SDA   VIA   -    M      A01X+083428Y+053608X0300Y         S1      
017SMB_NIC3_R_SDA   VIA   -    M      A18X+083428Y+053608X0200Y         S1      
017SMB_NIC3_R_SDA         -    MD0100PA00X+083428Y+053608                       
327SMB_NIC3_R_SDA   R163  -1          A18X+072587Y+044661X0198Y0197R180 S2      
317SMB_NIC3_R_SDA   VIA   -    MD0100PA00X+083728Y+088346X0200Y         S0      
327SMB_NIC3_R_SDA   R1488 -2          A01X+083979Y+088749X0198Y0197R180 S1      
317m1716            VIA   -    MD0100PA00X+136415Y+082987X0180Y         S0      
327m1716            R6184 -2          A18X+092063Y+092255X0198Y0197R090 S2      
327m1716            R4516 -2          A18X+091929Y+091191X0198Y0197R270 S2      
317m1716            VIA   -    MD0100PA00X+092063Y+091804X0200Y         S0      
317m1716            VIA   -    M      A01X+104363Y+083656X0200Y         S2      
017m1716            VIA   -    M      A18X+104363Y+083656X0260Y         S2      
017m1716                  -    MD0100PA00X+104363Y+083656                       
327m1716            U6    -AB16       A01X+136257Y+083144X0160Y         S1      
327m1717            PU68  -8          A01X+170843Y+022506X0110Y0240     S1      
317m1717            VIA   -    M      A01X+170994Y+022875X0200Y    R090 S2      
017m1717            VIA   -    M      A18X+170994Y+022875X0260Y    R090 S2      
017m1717                  -    MD0100PA00X+170994Y+022875                       
327m1717            R4510 -1          A01X+170910Y+024168X0198Y0197     S1      
327m1717            R900  -2   M      A01X+171055Y+023298X0198Y0197R270 S1      
317TP_PEX3_TCK      VIA   -    MD0080PA00X+156683Y+121545X0160Y         S0      
327TP_PEX3_TCK      VIA   -           A18X+156496Y+121732X0260Y         S2      
327TP_PEX3_TCK      PEX3  -M15        A01X+156870Y+121358X0180Y         S1      
327SMB_NIC0_R_SCL   J20   -A7         A01X+019938Y+056128X0140Y0480R270 S1      
327SMB_NIC0_R_SCL   R9    -1          A01X+021842Y+056280X0198Y0197     S1      
317SMB_NIC0_R_SCL   VIA   -    MD0100PA00X+020467Y+056142X0200Y    R180 S0      
317SMB_NIC0_R_SCL   VIA   -    M      A01X+025529Y+082434X0200Y         S2      
017SMB_NIC0_R_SCL   VIA   -    M      A18X+025529Y+082434X0260Y         S2      
017SMB_NIC0_R_SCL         -    MD0100PA00X+025529Y+082434                       
327SMB_NIC0_R_SCL   R1477 -2          A18X+087529Y+091191X0198Y0197R270 S2      
317SMB_NIC0_R_SCL   VIA   -    MD0100PA00X+087663Y+091804X0200Y         S0      
327m1718            C4097 -2   M      A01X+059186Y+152999X0198Y0197R090 S1      
327m1718            R1839 -2          A01X+059181Y+153543X0198Y0197R270 S1      
317m1718            VIA   -    M      A01X+061374Y+154651X0200Y         S2      
017m1718            VIA   -    M      A18X+061374Y+154651X0260Y         S2      
017m1718                  -    MD0100PA00X+061374Y+154651                       
317m1718            J5    -A3   D0122PA00X+064689Y+162240X0282Y    R180 S3      
327m1719            R4153 -2          A01X+138100Y+080958X0198Y0197R090 S1      
327m1719            VIA   -    M      A01X+138054Y+081525X0300Y         S1      
327m1719            U6    -AA20       A01X+137517Y+083460X0160Y         S1      
317PEX3_MODE_SEL6   VIA   -    MD0080PA00X+163041Y+111821X0160Y         S0      
327PEX3_MODE_SEL6   R1431 -2          A01X+151510Y+099196X0198Y0197R270 S1      
327PEX3_MODE_SEL6   R1411 -1          A01X+151510Y+098611X0198Y0197R270 S1      
317PEX3_MODE_SEL6   VIA   -    M      A01X+151510Y+098881X0200Y         S2      
017PEX3_MODE_SEL6   VIA   -    M      A18X+151510Y+098881X0260Y         S2      
017PEX3_MODE_SEL6         -    MD0100PA00X+151510Y+098881                       
327PEX3_MODE_SEL6   PEX3  -AV31       A01X+162854Y+111634X0180Y         S1      
317SMB_NIC5_SCL     VIA   -    MD0100PA00X+085946Y+085946X0200Y         S0      
327SMB_NIC5_SCL     VIA   -    M      A01X+086812Y+086030X0300Y         S1      
327SMB_NIC5_SCL     R1500 -1          A01X+085683Y+085946X0198Y0197R180 S1      
327SMB_NIC5_SCL     U5    -J14        A01X+088609Y+086262X0160Y    R180 S1      
317SMB_NIC5_SCL     VIA   -    MD0100PA00X+084357Y+085942X0200Y         S0      
327SMB_NIC5_SCL     R4875 -2          A01X+083640Y+086042X0198Y0197R270 S1      
317m1720            VIA   -    MD0100PA00X+041281Y+033062X0200Y         S0      
327m1720            U115  -11         A01X+041689Y+033141X0070Y0340R270 S1      
317m1720            VIA   -    M      A01X+031851Y+032432X0200Y         S2      
017m1720            VIA   -    M      A18X+031851Y+032432X0260Y         S2      
017m1720                  -    MD0100PA00X+031851Y+032432                       
327m1720            R3586 -2          A01X+133450Y+092308X0198Y0197R090 S1      
317m1720            VIA   -    MD0100PA00X+038339Y+080400X0200Y         S0      
317m1720            VIA   -    MD0100PA00X+133450Y+092550X0200Y         S0      
317m1721            VIA   -    MD0100PA00X+139358Y+039731X0200Y         S0      
317m1721            VIA   -    MD0100PA00X+134998Y+082900X0200Y         S0      
327m1721            U5    -N1         A01X+092704Y+087521X0160Y    R180 S1      
317m1721            VIA   -    MD0100PA00X+092861Y+087679X0180Y    R270 S0      
317m1721            VIA   -    MD0100PA00X+105391Y+083772X0200Y         S0      
317m1721            VIA   -    MD0100PA00X+096734Y+082890X0200Y         S0      
327m1721            U6    -AB12       A01X+134998Y+083144X0160Y         S1      
317m1721            VIA   -    M      A01X+170746Y+014376X0200Y         S2      
017m1721            VIA   -    M      A18X+170746Y+014376X0260Y         S2      
017m1721                  -    MD0100PA00X+170746Y+014376                       
317m1721            VIA   -    MD0100PA00X+171355Y+010656X0200Y         S0      
327m1721            R4082 -2          A01X+170634Y+010250X0198Y0197     S1      
327m1721            C2778 -1   M      A01X+170634Y+010650X0198Y0197R180 S1      
327m1721            R4083 -1   M      A01X+171032Y+010656X0198Y0197R270 S1      
327m1721            R5586 -2          A01X+170424Y+014376X0198Y0197R270 S1      
317m1721            VIA   -    MD0100PA00X+165477Y+035209X0200Y         S0      
327PEX1_MODE_SEL0   PEX1  -AW27       A01X+069941Y+111260X0180Y         S1      
317PEX1_MODE_SEL0   VIA   -    MD0080PA00X+070128Y+111447X0160Y         S0      
317PEX1_MODE_SEL0   VIA   -    M      A01X+057692Y+098881X0200Y         S2      
017PEX1_MODE_SEL0   VIA   -    M      A18X+057692Y+098881X0260Y         S2      
017PEX1_MODE_SEL0         -    MD0100PA00X+057692Y+098881                       
327PEX1_MODE_SEL0   R1289 -2          A01X+057692Y+099196X0198Y0197R270 S1      
327PEX1_MODE_SEL0   R1269 -1          A01X+057692Y+098611X0198Y0197R270 S1      
317m1722            VIA   -    MD0080PA00X+163415Y+111821X0160Y         S0      
327m1722            VIA   -    M      A18X+163699Y+106461X0260Y         S2      
327m1722            PEX3  -AV32       A01X+163228Y+111634X0180Y         S1      
317m1722            VIA   -    MD0100PA00X+151910Y+098881X0200Y         S0      
327m1722            R1435 -2          A01X+151910Y+099196X0198Y0197R270 S1      
327m1722            R1415 -1          A01X+151910Y+098611X0198Y0197R270 S1      
327m1723            PU56  -8          A01X+013244Y+022506X0110Y0240     S1      
317m1723            VIA   -    M      A01X+013396Y+022782X0200Y    R090 S2      
017m1723            VIA   -    M      A18X+013396Y+022782X0260Y    R090 S2      
017m1723                  -    MD0100PA00X+013396Y+022782                       
327m1723            R4486 -1          A01X+013311Y+024168X0198Y0197     S1      
327m1723            R888  -2   M      A01X+013456Y+023298X0198Y0197R270 S1      
317SSD15_PWR_EN     VIA   -    M      A01X+134500Y+079600X0200Y    R180 S2      
017SSD15_PWR_EN     VIA   -    M      A18X+134500Y+079600X0260Y    R180 S2      
017SSD15_PWR_EN           -    MD0100PA00X+134500Y+079600                       
327SSD15_PWR_EN     R4143 -2          A01X+134500Y+079358X0198Y0197R090 S1      
317SSD15_PWR_EN     VIA   -    MD0100PA00X+135470Y+084562X0180Y         S0      
327SSD15_PWR_EN     U6    -U13        A01X+135312Y+084719X0160Y         S1      
327m1724            VIA   -           A18X+043493Y+031723X0260Y         S2      
327m1724            VIA   -           A18X+042646Y+031712X0260Y         S2      
327m1724            U115  -38         A01X+043559Y+035011X0070Y0340R180 S1      
327m1724            C2668 -1          A18X+043813Y+034968X0198Y0197     S2      
317m1724            VIA   -    MD0100PA00X+043589Y+035387X0200Y         S0      
327m1724            U115  -42         A01X+042929Y+035011X0070Y0340R180 S1      
327m1724            C2665 -1          A18X+042812Y+034970X0198Y0197R180 S2      
317m1724            VIA   -    MD0100PA00X+042842Y+035358X0200Y         S0      
327m1724            R1128 -1          A01X+040073Y+034994X0280Y0320R270 S1      
317m1724            VIA   -    MD0100PA00X+040073Y+035315X0200Y         S0      
327m1724            U115  -34         A01X+044011Y+034401X0070Y0340R090 S1      
327m1724            C2664 -1          A18X+043924Y+034287X0198Y0197     S2      
317m1724            VIA   -    MD0100PA00X+044348Y+034401X0200Y         S0      
327m1724            C2669 -1          A18X+043891Y+033391X0198Y0197     S2      
317m1724            VIA   -    M      A01X+044342Y+033299X0200Y         S2      
017m1724            VIA   -    M      A18X+044342Y+033299X0260Y         S2      
017m1724                  -    MD0100PA00X+044342Y+033299                       
327m1724            U115  -27         A01X+044011Y+033299X0070Y0340R090 S1      
327m1724            C2666 -1          A18X+041800Y+033452X0198Y0197R180 S2      
317m1724            VIA   -    MD0100PA00X+041267Y+033342X0200Y         S0      
327m1724            U115  -10         A01X+041689Y+033299X0070Y0340R270 S1      
327m1724            C2667 -1          A18X+043096Y+032801X0198Y0197R270 S2      
317m1724            VIA   -    MD0100PA00X+043036Y+032319X0200Y         S0      
327m1724            U115  -19         A01X+042929Y+032689X0070Y0340     S1      
327m1724            C2663 -1          A18X+042402Y+032806X0198Y0197R270 S2      
317m1724            VIA   -    MD0100PA00X+041513Y+032518X0200Y         S0      
317m1724            VIA   -    M      A01X+042299Y+032363X0200Y         S2      
017m1724            VIA   -    M      A18X+042299Y+032363X0260Y         S2      
017m1724                  -    MD0100PA00X+042299Y+032363                       
327m1724            U115  -15         A01X+042299Y+032689X0070Y0340     S1      
327m1724            L13   -2          A18X+040493Y+032438X0280Y0320     S2      
327m1724            C2662 -1          A18X+041096Y+032548X0400Y0500R270 S2      
327PEX1_MODE_SEL2   PEX1  -AV25       A01X+069193Y+111634X0180Y         S1      
317PEX1_MODE_SEL2   VIA   -    MD0080PA00X+069380Y+111821X0160Y         S0      
317PEX1_MODE_SEL2   VIA   -    MD0100PA00X+161163Y+078033X0200Y         S0      
327PEX1_MODE_SEL2   R6435 -2          A01X+160848Y+078033X0198Y0197R270 S1      
317PEX1_MODE_SEL2   VIA   -    MD0100PA00X+115765Y+069949X0200Y         S0      
317PEX1_MODE_SEL2   VIA   -    MD0100PA00X+088498Y+074089X0200Y         S0      
317PEX1_MODE_SEL2   VIA   -    MD0100PA00X+073368Y+082898X0200Y         S0      
317PEX1_MODE_SEL2   VIA   -    MD0100PA00X+060896Y+096641X0200Y         S0      
327PEX1_MODE_SEL2   R1271 -1          A01X+056092Y+098611X0198Y0197R270 S1      
327PEX1_MODE_SEL2   R1291 -2          A01X+056092Y+099196X0198Y0197R270 S1      
317PEX1_MODE_SEL2   VIA   -    M      A01X+056092Y+098881X0200Y         S2      
017PEX1_MODE_SEL2   VIA   -    M      A18X+056092Y+098881X0260Y         S2      
017PEX1_MODE_SEL2         -    MD0100PA00X+056092Y+098881                       
317PEX3_DBG_MODE3   VIA   -    MD0080PA00X+161171Y+111447X0160Y         S0      
327PEX3_DBG_MODE3   R1423 -2          A01X+148310Y+099196X0198Y0197R270 S1      
327PEX3_DBG_MODE3   R1403 -1          A01X+148310Y+098611X0198Y0197R270 S1      
317PEX3_DBG_MODE3   VIA   -    M      A01X+148310Y+098881X0200Y         S2      
017PEX3_DBG_MODE3   VIA   -    M      A18X+148310Y+098881X0260Y         S2      
017PEX3_DBG_MODE3         -    MD0100PA00X+148310Y+098881                       
327PEX3_DBG_MODE3   PEX3  -AW26       A01X+160984Y+111260X0180Y         S1      
317m1725            VIA   -    M      A01X+141800Y+070100X0200Y         S2      
017m1725            VIA   -    M      A18X+141800Y+070100X0260Y         S2      
017m1725                  -    MD0100PA00X+141800Y+070100                       
327m1725            R4676 -1          A01X+141558Y+070500X0198Y0197R180 S1      
327m1725            R4663 -2   M      A01X+141558Y+070100X0198Y0197     S1      
327m1725            R4706 -2          A01X+142042Y+070100X0198Y0197R180 S1      
327m1725            U6    -Y19        A01X+137202Y+083774X0160Y         S1      
317m1725            VIA   -    MD0100PA00X+137360Y+083617X0180Y         S0      
327m1726            VIA   -           A18X+041844Y+035155X0260Y         S2      
327m1726            VIA   -           A18X+040999Y+035104X0260Y         S2      
327m1726            U115  -3          A01X+041689Y+034401X0070Y0340R270 S1      
327m1726            R1128 -2          A01X+040653Y+034994X0280Y0320R270 S1      
327m1726            C2670 -1   M      A01X+040653Y+034444X0280Y0320R090 S1      
317m1726            VIA   -    M      A01X+041069Y+034474X0200Y         S2      
017m1726            VIA   -    M      A18X+041069Y+034474X0260Y         S2      
017m1726                  -    MD0100PA00X+041069Y+034474                       
317m1726            VIA   -    MD0100PA00X+042614Y+035508X0200Y         S0      
327m1726            C2672 -1   M      A18X+042390Y+035056X0198Y0197R090 S2      
327m1726            U115  -44         A01X+042614Y+035011X0070Y0340R180 S1      
327m1726            C2671 -1   M      A18X+041757Y+034300X0198Y0197R180 S2      
317PEX3_DBG_MODE1   VIA   -    MD0080PA00X+156309Y+121545X0160Y    R180 S0      
327PEX3_DBG_MODE1   R1401 -1   M      A01X+150283Y+121424X0198Y0197R225 S1      
327PEX3_DBG_MODE1   R1421 -2          A01X+150566Y+121141X0198Y0197R045 S1      
317PEX3_DBG_MODE1   VIA   -    M      A01X+150836Y+122007X0200Y         S2      
017PEX3_DBG_MODE1   VIA   -    M      A18X+150836Y+122007X0260Y         S2      
017PEX3_DBG_MODE1         -    MD0100PA00X+150836Y+122007                       
327PEX3_DBG_MODE1   PEX3  -L13        A01X+156122Y+121732X0180Y         S1      
327SMB_NIC1_SCL     VIA   -    M      A18X+088329Y+090194X0260Y         S2      
327SMB_NIC1_SCL     R1479 -1          A18X+088329Y+090876X0198Y0197R270 S2      
327SMB_NIC1_SCL     U5    -P13        A01X+088924Y+087836X0160Y    R180 S1      
317SMB_NIC1_SCL     VIA   -    MD0100PA00X+088767Y+087994X0180Y    R270 S0      
327m1727            C4096 -2          A01X+059491Y+149366X0198Y0197R180 S1      
317m1727            VIA   -    M      A01X+058886Y+149090X0200Y         S2      
017m1727            VIA   -    M      A18X+058886Y+149090X0260Y         S2      
017m1727                  -    MD0100PA00X+058886Y+149090                       
327m1727            R1838 -2          A01X+058851Y+149369X0198Y0197     S1      
317m1727            J5    -Z2   D0122PA00X+063823Y+145272X0282Y    R180 S3      
327m1728            VIA   -    M      A18X+136150Y+083150X0260Y         S2      
327m1728            U6    -V15        A01X+135942Y+084404X0160Y         S1      
317m1728            VIA   -    MD0100PA00X+136100Y+084247X0180Y         S0      
327m1728            R4150 -2          A18X+136450Y+081958X0198Y0197R270 S2      
327m1729            J37   -B15        A01X+082427Y+010705X0150Y0500R090 S1      
317m1729            VIA   -    MD0100PA00X+083103Y+010765X0200Y         S0      
327m1729            R1150 -1          A01X+043502Y+036509X0198Y0197R270 S1      
317m1729            VIA   -    MD0100PA00X+043492Y+037031X0200Y    R090 S0      
317m1730            VIA   -    M      A01X+054509Y+101368X0200Y         S2      
017m1730            VIA   -    M      A18X+054509Y+101368X0260Y         S2      
017m1730                  -    MD0100PA00X+054509Y+101368                       
327m1730            R6154 -1          A01X+053672Y+100940X0198Y0197R270 S1      
327m1730            R1322 -2          A01X+054438Y+102105X0198Y0197     S1      
327m1730            Q14   -2   M      A01X+054177Y+101221X0160Y0240R270 S1      
317PEX3_DBG_MODE2   VIA   -    MD0100PA00X+150310Y+098881X0200Y         S0      
327PEX3_DBG_MODE2   R1422 -2          A01X+150310Y+099196X0198Y0197R270 S1      
327PEX3_DBG_MODE2   R1402 -1          A01X+150310Y+098611X0198Y0197R270 S1      
327PEX3_DBG_MODE2   PEX3  -AW30       A01X+162480Y+111260X0180Y         S1      
327PEX3_DBG_MODE2   VIA   -    M      A18X+161186Y+105332X0260Y         S2      
317PEX3_DBG_MODE2   VIA   -    MD0080PA00X+162667Y+111447X0160Y         S0      
317SMB_NIC5_R_SDA   VIA   -    MD0100PA00X+084838Y+085146X0200Y         S0      
327SMB_NIC5_R_SDA   U120  -2          A01X+083670Y+079928X0140Y0590R270 S1      
327SMB_NIC5_R_SDA   R1518 -1   M      A01X+083008Y+079850X0198Y0197R180 S1      
317SMB_NIC5_R_SDA   VIA   -    M      A01X+082450Y+080050X0200Y         S2      
017SMB_NIC5_R_SDA   VIA   -    M      A18X+082450Y+080050X0260Y         S2      
017SMB_NIC5_R_SDA         -    MD0100PA00X+082450Y+080050                       
327SMB_NIC5_R_SDA   R1521 -2          A18X+083500Y+079892X0198Y0197R090 S2      
327SMB_NIC5_R_SDA   R1501 -2          A01X+085368Y+085546X0198Y0197R180 S1      
327SSD0_PWRDIS_R    J30   -B12        A01X+006010Y+009996X0150Y0500R090 S1      
317SSD0_PWRDIS_R    VIA   -    M      A01X+005587Y+009996X0200Y         S2      
017SSD0_PWRDIS_R    VIA   -    M      A18X+005587Y+009996X0260Y         S2      
017SSD0_PWRDIS_R          -    MD0100PA00X+005587Y+009996                       
317SSD0_PWRDIS_R    VIA   -    MD0100PA00X+007780Y+009588X0200Y         S0      
317SSD0_PWRDIS_R    VIA   -    MD0100PA00X+013342Y+085730X0200Y         S0      
317SSD0_PWRDIS_R    VIA   -    MD0100PA00X+132727Y+098827X0200Y         S0      
327SSD0_PWRDIS_R    R3582 -2          A01X+135795Y+094918X0198Y0197R090 S1      
327SSD0_PWRDIS_R    R6198 -2          A01X+008481Y+010045X0198Y0197R270 S1      
327m1731            R1091 -2          A01X+050946Y+067323X0198Y0197R090 S1      
327m1731            U114  -M3         A01X+051563Y+068858X0090Y         S1      
327m1732            J36   -B15        A01X+072191Y+010705X0150Y0500R090 S1      
317m1732            VIA   -    MD0100PA00X+046395Y+034841X0200Y         S0      
327m1732            R1148 -1          A01X+045573Y+034831X0198Y0197R180 S1      
317m1732            VIA   -    MD0100PA00X+072867Y+010765X0200Y         S0      
327PEX1_MODE_SEL1   PEX1  -AW38       A01X+074055Y+111260X0180Y         S1      
317PEX1_MODE_SEL1   VIA   -    MD0080PA00X+074242Y+111447X0160Y         S0      
317PEX1_MODE_SEL1   VIA   -    MD0100PA00X+161280Y+070590X0200Y         S0      
327PEX1_MODE_SEL1   R6434 -2          A01X+161103Y+069992X0198Y0197R180 S1      
317PEX1_MODE_SEL1   VIA   -    MD0100PA00X+115515Y+069949X0200Y         S0      
317PEX1_MODE_SEL1   VIA   -    MD0100PA00X+088210Y+074156X0200Y         S0      
317PEX1_MODE_SEL1   VIA   -    MD0100PA00X+073088Y+082892X0200Y         S0      
317PEX1_MODE_SEL1   VIA   -    M      A01X+061692Y+098881X0200Y         S2      
017PEX1_MODE_SEL1   VIA   -    M      A18X+061692Y+098881X0260Y         S2      
017PEX1_MODE_SEL1         -    MD0100PA00X+061692Y+098881                       
327PEX1_MODE_SEL1   R1290 -2          A01X+061692Y+099196X0198Y0197R270 S1      
327PEX1_MODE_SEL1   R1270 -1          A01X+061692Y+098611X0198Y0197R270 S1      
317PEX3_DBG_MODE4   VIA   -    MD0080PA00X+164163Y+111447X0160Y         S0      
327PEX3_DBG_MODE4   PEX3  -AW34       A01X+163976Y+111260X0180Y         S1      
317PEX3_DBG_MODE4   VIA   -    M      A01X+152310Y+098881X0200Y         S2      
017PEX3_DBG_MODE4   VIA   -    M      A18X+152310Y+098881X0260Y         S2      
017PEX3_DBG_MODE4         -    MD0100PA00X+152310Y+098881                       
327PEX3_DBG_MODE4   R1424 -2          A01X+152310Y+099196X0198Y0197R270 S1      
327PEX3_DBG_MODE4   R1404 -1          A01X+152310Y+098611X0198Y0197R270 S1      
317m1733            J5    -A1   D0122PA00X+062957Y+162240X0282Y0282R180 S3      
317m1733            VIA   -    M      A01X+059581Y+153213X0200Y         S2      
017m1733            VIA   -    M      A18X+059581Y+153213X0260Y         S2      
017m1733                  -    MD0100PA00X+059581Y+153213                       
317m1733            VIA   -    MD0100PA00X+062173Y+155680X0200Y         S0      
327m1733            R1837 -1          A01X+059581Y+153543X0198Y0197R090 S1      
327P3V3_SSD7_OCP    PU61  -9          A01X+079229Y+022506X0110Y0240     S1      
317P3V3_SSD7_OCP    VIA   -    M      A01X+079151Y+023056X0200Y    R090 S2      
017P3V3_SSD7_OCP    VIA   -    M      A18X+079151Y+023056X0260Y    R090 S2      
017P3V3_SSD7_OCP          -    MD0100PA00X+079151Y+023056                       
327P3V3_SSD7_OCP    PR269 -1          A01X+079214Y+023296X0198Y0197R090 S1      
327m1734            R1087 -2          A01X+049851Y+069701X0198Y0197     S1      
327m1734            U114  -J1         A01X+051170Y+069449X0090Y         S1      
327m1735            J33   -B15        A01X+036718Y+010705X0150Y0500R090 S1      
317m1735            VIA   -    MD0100PA00X+037394Y+010765X0200Y         S0      
317m1735            VIA   -    MD0100PA00X+046095Y+032478X0200Y         S0      
327m1735            R1142 -1          A01X+045573Y+032468X0198Y0197R180 S1      
327PEX1_MODE_SEL6   PEX1  -AV31       A01X+071437Y+111634X0180Y         S1      
317PEX1_MODE_SEL6   VIA   -    MD0080PA00X+071624Y+111821X0160Y         S0      
327PEX1_MODE_SEL6   R1295 -2          A01X+060092Y+099196X0198Y0197R270 S1      
327PEX1_MODE_SEL6   R1275 -1          A01X+060092Y+098611X0198Y0197R270 S1      
317PEX1_MODE_SEL6   VIA   -    M      A01X+060092Y+098881X0200Y         S2      
017PEX1_MODE_SEL6   VIA   -    M      A18X+060092Y+098881X0260Y         S2      
017PEX1_MODE_SEL6         -    MD0100PA00X+060092Y+098881                       
327SMB_NIC3_R_SCL   J23   -A7         A01X+072739Y+044423X0140Y0480R090 S1      
317SMB_NIC3_R_SCL   VIA   -    MD0100PA00X+083395Y+053062X0200Y         S0      
317SMB_NIC3_R_SCL   VIA   -    M      A01X+072100Y+044286X0200Y         S2      
017SMB_NIC3_R_SCL   VIA   -    M      A18X+072100Y+044286X0260Y         S2      
017SMB_NIC3_R_SCL         -    MD0100PA00X+072100Y+044286                       
327SMB_NIC3_R_SCL   R162  -1          A18X+072587Y+044261X0198Y0197R180 S2      
327SMB_NIC3_R_SCL   R1486 -2          A01X+085368Y+088776X0198Y0197R180 S1      
317SMB_NIC3_R_SCL   VIA   -    MD0100PA00X+085090Y+088836X0200Y         S0      
317PRSNT_SSD0_R_N   VIA   -    M      A01X+002656Y+017745X0200Y         S2      
017PRSNT_SSD0_R_N   VIA   -    M      A18X+002656Y+017745X0260Y         S2      
017PRSNT_SSD0_R_N         -    MD0100PA00X+002656Y+017745                       
317PRSNT_SSD0_R_N   VIA   -    MD0100PA00X+003521Y+010656X0200Y         S0      
327PRSNT_SSD0_R_N   U6    -B9         A01X+134053Y+089444X0160Y         S1      
317PRSNT_SSD0_R_N   VIA   -    MD0100PA00X+134000Y+090300X0200Y         S0      
317PRSNT_SSD0_R_N   VIA   -    MD0100PA00X+012967Y+085751X0200Y         S0      
327PRSNT_SSD0_R_N   U5    -T1         A01X+092704Y+088466X0160Y    R180 S1      
317PRSNT_SSD0_R_N   VIA   -    MD0100PA00X+093080Y+090484X0200Y         S0      
317PRSNT_SSD0_R_N   VIA   -    MD0100PA00X+092861Y+088624X0180Y    R270 S0      
327PRSNT_SSD0_R_N   R4055 -2          A01X+002799Y+010250X0198Y0197     S1      
327PRSNT_SSD0_R_N   C2764 -1   M      A01X+002799Y+010650X0198Y0197R180 S1      
327PRSNT_SSD0_R_N   R4051 -1   M      A01X+003197Y+010656X0198Y0197R270 S1      
327PRSNT_SSD0_R_N   R5539 -2          A01X+002936Y+017745X0198Y0197R180 S1      
317m1736            VIA   -    M      A01X+140687Y+078327X0200Y         S2      
017m1736            VIA   -    M      A18X+140687Y+078327X0260Y         S2      
017m1736                  -    MD0100PA00X+140687Y+078327                       
327m1736            R4688 -2          A01X+143742Y+078250X0198Y0197R180 S1      
327m1736            R4667 -2   M      A01X+143258Y+078250X0198Y0197     S1      
327m1736            U6    -AA18       A01X+136887Y+083460X0160Y         S1      
317m1736            VIA   -    MD0100PA00X+137045Y+083302X0180Y         S0      
327m1737            J33   -B14        A01X+036718Y+010468X0150Y0500R090 S1      
317m1737            VIA   -    MD0100PA00X+046095Y+032818X0200Y         S0      
327m1737            R1143 -1          A01X+045573Y+032828X0198Y0197R180 S1      
317m1737            VIA   -    MD0100PA00X+037394Y+010425X0200Y         S0      
327PEX1_MODE_SEL5   PEX1  -AW25       A01X+069193Y+111260X0180Y         S1      
317PEX1_MODE_SEL5   VIA   -    MD0080PA00X+069380Y+111447X0160Y         S0      
327PEX1_MODE_SEL5   R1294 -2          A01X+056492Y+099196X0198Y0197R270 S1      
327PEX1_MODE_SEL5   R1274 -1          A01X+056492Y+098611X0198Y0197R270 S1      
317PEX1_MODE_SEL5   VIA   -    MD0100PA00X+056492Y+098881X0200Y         S0      
327PEX1_MODE_SEL5   VIA   -    M      A18X+068126Y+105598X0260Y         S2      
327PEX3_MODE_SEL8   R1413 -1          A01X+149910Y+098611X0198Y0197R270 S1      
327PEX3_MODE_SEL8   R1433 -2          A01X+149910Y+099196X0198Y0197R270 S1      
317PEX3_MODE_SEL8   VIA   -    M      A01X+149910Y+098881X0200Y         S2      
017PEX3_MODE_SEL8   VIA   -    M      A18X+149910Y+098881X0260Y         S2      
017PEX3_MODE_SEL8         -    MD0100PA00X+149910Y+098881                       
327PEX3_MODE_SEL8   PEX3  -AW29       A01X+162106Y+111260X0180Y         S1      
317PEX3_MODE_SEL8   VIA   -    MD0080PA00X+162293Y+111447X0160Y         S0      
317SMB_FIO_SDA      VIA   -    MD0100PA00X+085961Y+088785X0200Y         S0      
327SMB_FIO_SDA      VIA   -    M      A18X+086894Y+088746X0260Y         S2      
317SMB_FIO_SDA      VIA   -    MD0100PA00X+088137Y+087679X0180Y    R270 S0      
327SMB_FIO_SDA      R1492 -1          A18X+085686Y+088771X0198Y0197     S2      
327SMB_FIO_SDA      U5    -N15        A01X+088294Y+087521X0160Y    R180 S1      
317SMB_FIO_SDA      VIA   -    MD0100PA00X+084596Y+088749X0200Y         S0      
327SMB_FIO_SDA      R4872 -2          A18X+084294Y+088749X0198Y0197R180 S2      
327m1738            C4082 -2          A01X+058529Y+151404X0198Y0197     S1      
317m1738            J12   -Z10  D0122PA00X+053429Y+145272X0282Y    R180 S3      
317m1738            VIA   -    M      A01X+058180Y+150969X0200Y         S2      
017m1738            VIA   -    M      A18X+058180Y+150969X0260Y         S2      
017m1738                  -    MD0100PA00X+058180Y+150969                       
327m1738            R1848 -2   M      A01X+058536Y+150969X0198Y0197R180 S1      
327m1739            PU37  -8          A01X+085924Y+021120X0110Y0240R270 S1      
317m1739            VIA   -    M      A01X+086314Y+020704X0200Y         S2      
017m1739            VIA   -    M      A18X+086314Y+020704X0260Y         S2      
017m1739                  -    MD0100PA00X+086314Y+020704                       
327m1739            R868  -2          A01X+086602Y+020486X0198Y0197R180 S1      
327m1739            R4465 -1   M      A01X+086602Y+020886X0198Y0197     S1      
327m1740            R4605 -2          A01X+143258Y+081050X0198Y0197     S1      
327m1740            R4629 -2          A01X+143742Y+081050X0198Y0197R180 S1      
317m1740            VIA   -    M      A01X+143500Y+080950X0200Y         S2      
017m1740            VIA   -    M      A18X+143500Y+080950X0260Y         S2      
017m1740                  -    MD0100PA00X+143500Y+080950                       
327m1740            U6    -Y14        A01X+135628Y+083774X0160Y         S1      
317m1740            VIA   -    MD0100PA00X+135785Y+083617X0180Y         S0      
317m1741            VIA   -    MD0100PA00X+006686Y+010765X0200Y         S0      
327m1741            J30   -B15        A01X+006010Y+010705X0150Y0500R090 S1      
317m1741            VIA   -    MD0100PA00X+041578Y+030447X0200Y    R270 S0      
327m1741            R1136 -1          A01X+041568Y+031269X0198Y0197R090 S1      
317PEX3_DBG_SEL0    VIA   -    MD0080PA00X+157805Y+121545X0160Y         S0      
317PEX3_DBG_SEL0    VIA   -    M      A01X+148331Y+121437X0200Y    R315 S2      
017PEX3_DBG_SEL0    VIA   -    M      A18X+148331Y+121437X0260Y    R315 S2      
017PEX3_DBG_SEL0          -    MD0100PA00X+148331Y+121437                       
327PEX3_DBG_SEL0    R1418 -2          A01X+148302Y+121011X0198Y0197R045 S1      
327PEX3_DBG_SEL0    R1398 -1   M      A01X+148020Y+121294X0198Y0197R225 S1      
327PEX3_DBG_SEL0    PEX3  -L18        A01X+157992Y+121732X0180Y         S1      
327SMB_NIC6_SDA     VIA   -    M      A01X+086183Y+084620X0300Y         S1      
327SMB_NIC6_SDA     R1503 -1   M      A01X+085683Y+084346X0198Y0197R180 S1      
327SMB_NIC6_SDA     U5    -G15        A01X+088294Y+085632X0160Y    R180 S1      
327SMB_NIC6_SDA     R4878 -2          A01X+084384Y+084379X0198Y0197     S1      
317m1742            VIA   -    M      A01X+132650Y+094350X0200Y         S2      
017m1742            VIA   -    M      A18X+132650Y+094350X0260Y         S2      
017m1742                  -    MD0100PA00X+132650Y+094350                       
327m1742            U144  -4          A01X+132694Y+094806X0140Y0440R180 S1      
327m1742            R1795 -1          A01X+132650Y+094108X0198Y0197R270 S1      
327SSD7_PWR_EN_R    PU37  -11         A01X+085924Y+021710X0110Y0240R270 S1      
327SSD7_PWR_EN_R    C2868 -1   M      A01X+086602Y+022186X0198Y0197     S1      
317SSD7_PWR_EN_R    VIA   -    M      A01X+086602Y+022454X0200Y         S2      
017SSD7_PWR_EN_R    VIA   -    M      A18X+086602Y+022454X0260Y         S2      
017SSD7_PWR_EN_R          -    MD0100PA00X+086602Y+022454                       
327SSD7_PWR_EN_R    R5981 -1          A01X+084494Y+025954X0198Y0197R090 S1      
317SSD7_PWR_EN_R    VIA   -    MD0100PA00X+084494Y+025630X0200Y         S0      
327SSD7_PWR_EN_R    R6834 -1          A01X+138256Y+093425X0198Y0197R090 S1      
327SSD7_PWR_EN_R    R3592 -1          A01X+138250Y+092308X0198Y0197R270 S1      
317SSD7_PWR_EN_R    VIA   -    MD0100PA00X+087407Y+097793X0200Y         S0      
317SSD7_PWR_EN_R    VIA   -    MD0100PA00X+138250Y+092550X0200Y         S0      
317m1743            VIA   -    MD0100PA00X+094703Y+091524X0200Y         S0      
327m1743            R6183 -2          A01X+094463Y+092255X0198Y0197R270 S1      
327m1743            R4515 -2          A01X+094463Y+091266X0198Y0197R090 S1      
317m1743            VIA   -    M      A01X+104831Y+083310X0200Y         S2      
017m1743            VIA   -    M      A18X+104831Y+083310X0260Y         S2      
017m1743                  -    MD0100PA00X+104831Y+083310                       
327m1743            U6    -W14        A01X+135628Y+084089X0160Y         S1      
317m1743            VIA   -    MD0100PA00X+135785Y+083932X0180Y         S0      
327m1744            J37   -B14        A01X+082427Y+010468X0150Y0500R090 S1      
317m1744            VIA   -    MD0100PA00X+083103Y+010425X0200Y         S0      
327m1744            R1151 -1          A01X+043142Y+036509X0198Y0197R270 S1      
317m1744            VIA   -    MD0100PA00X+043152Y+037031X0200Y    R090 S0      
327PEX1_MODE_SEL8   PEX1  -AW29       A01X+070689Y+111260X0180Y         S1      
317PEX1_MODE_SEL8   VIA   -    MD0080PA00X+070876Y+111447X0160Y         S0      
317PEX1_MODE_SEL8   VIA   -    M      A01X+058492Y+098881X0200Y         S2      
017PEX1_MODE_SEL8   VIA   -    M      A18X+058492Y+098881X0260Y         S2      
017PEX1_MODE_SEL8         -    MD0100PA00X+058492Y+098881                       
327PEX1_MODE_SEL8   R1297 -2          A01X+058492Y+099196X0198Y0197R270 S1      
327PEX1_MODE_SEL8   R1277 -1          A01X+058492Y+098611X0198Y0197R270 S1      
317PEX3_MODE_SEL2   VIA   -    MD0080PA00X+160797Y+111821X0160Y         S0      
327PEX3_MODE_SEL2   R1427 -2          A01X+147510Y+099196X0198Y0197R270 S1      
327PEX3_MODE_SEL2   R1407 -1          A01X+147510Y+098611X0198Y0197R270 S1      
317PEX3_MODE_SEL2   VIA   -    M      A01X+147510Y+098881X0200Y         S2      
017PEX3_MODE_SEL2   VIA   -    M      A18X+147510Y+098881X0260Y         S2      
017PEX3_MODE_SEL2         -    MD0100PA00X+147510Y+098881                       
327PEX3_MODE_SEL2   PEX3  -AV25       A01X+160610Y+111634X0180Y         S1      
317PEX3_MODE_SEL2   VIA   -    MD0100PA00X+161103Y+072243X0200Y         S0      
327PEX3_MODE_SEL2   R6447 -2          A01X+161103Y+071782X0198Y0197R180 S1      
317m1745            VIA   -    MD0100PA00X+085961Y+088380X0200Y         S0      
327m1745            VIA   -    M      A18X+086363Y+088346X0260Y         S2      
317m1745            VIA   -    MD0100PA00X+087780Y+087650X0180Y    R270 S0      
327m1745            R1494 -1          A18X+085683Y+088346X0198Y0197     S2      
327m1745            U5    -N16        A01X+087979Y+087521X0160Y    R180 S1      
317m1745            VIA   -    MD0100PA00X+084563Y+088349X0200Y         S0      
327m1745            R4113 -2          A18X+084303Y+088346X0198Y0197R180 S2      
317m1746            VIA   -    M      A01X+132300Y+093408X0200Y         S2      
017m1746            VIA   -    M      A18X+132300Y+093408X0260Y         S2      
017m1746                  -    MD0100PA00X+132300Y+093408                       
327m1746            R1795 -2          A01X+132650Y+093792X0198Y0197R270 S1      
327m1746            R1793 -2   M      A01X+132650Y+093408X0198Y0197R090 S1      
317m1746            VIA   -    MD0100PA00X+133265Y+088341X0180Y         S0      
327m1746            U6    -F7         A01X+133423Y+088184X0160Y         S1      
327m1747            PU36  -8          A01X+040215Y+021120X0110Y0240R270 S1      
317m1747            VIA   -    M      A01X+040605Y+020704X0200Y         S2      
017m1747            VIA   -    M      A18X+040605Y+020704X0260Y         S2      
017m1747                  -    MD0100PA00X+040605Y+020704                       
327m1747            R867  -2          A01X+040893Y+020486X0198Y0197R180 S1      
327m1747            R4464 -1   M      A01X+040893Y+020886X0198Y0197     S1      
327m1748            VIA   -    M      A18X+136900Y+082450X0260Y         S2      
327m1748            R4151 -2          A18X+136900Y+081958X0198Y0197R270 S2      
327m1748            U6    -V16        A01X+136257Y+084404X0160Y         S1      
317m1748            VIA   -    MD0100PA00X+136415Y+084247X0180Y         S0      
327m1749            J36   -B14        A01X+072191Y+010468X0150Y0500R090 S1      
317m1749            VIA   -    MD0100PA00X+046395Y+035181X0200Y         S0      
327m1749            R1149 -1          A01X+045573Y+035191X0198Y0197R180 S1      
317m1749            VIA   -    MD0100PA00X+072867Y+010425X0200Y         S0      
317PEX3_MODE_SEL4   VIA   -    MD0100PA00X+149510Y+098881X0200Y         S0      
327PEX3_MODE_SEL4   R1429 -2          A01X+149510Y+099196X0198Y0197R270 S1      
327PEX3_MODE_SEL4   R1409 -1          A01X+149510Y+098611X0198Y0197R270 S1      
327PEX3_MODE_SEL4   PEX3  -AW28       A01X+161732Y+111260X0180Y         S1      
327PEX3_MODE_SEL4   VIA   -    M      A18X+160158Y+105004X0260Y         S2      
317PEX3_MODE_SEL4   VIA   -    MD0080PA00X+161919Y+111447X0160Y         S0      
327SMB_NIC1_R_SDA   R1480 -2          A18X+087929Y+091191X0198Y0197R270 S2      
317SMB_NIC1_R_SDA   VIA   -    MD0100PA00X+088063Y+091804X0200Y         S0      
327SMB_NIC1_R_SDA   R61   -2          A18X+026879Y+044661X0198Y0197     S2      
317SMB_NIC1_R_SDA   VIA   -    MD0100PA00X+026501Y+044660X0200Y         S0      
317SMB_NIC1_R_SDA   VIA   -    M      A01X+079389Y+040950X0200Y         S2      
017SMB_NIC1_R_SDA   VIA   -    M      A18X+079389Y+040950X0260Y         S2      
017SMB_NIC1_R_SDA         -    MD0100PA00X+079389Y+040950                       
327SMB_NIC1_R_SDA   J21   -A8         A01X+027030Y+044660X0140Y0480R090 S1      
327m1750            U115  -18         A01X+042771Y+032689X0070Y0340     S1      
317m1750            VIA   -    MD0100PA00X+042771Y+032196X0200Y         S0      
317m1750            VIA   -    MD0100PA00X+035113Y+032220X0200Y         S0      
317m1750            VIA   -    MD0100PA00X+132920Y+093382X0200Y         S0      
317m1750            VIA   -    M      A01X+046050Y+087033X0200Y         S2      
017m1750            VIA   -    M      A18X+046050Y+087033X0260Y         S2      
017m1750                  -    MD0100PA00X+046050Y+087033                       
327m1750            R3599 -2          A18X+133850Y+092108X0198Y0197R270 S2      
317m1751            VIA   -    M      A01X+044657Y+033792X0200Y         S2      
017m1751            VIA   -    M      A18X+044657Y+033792X0260Y         S2      
017m1751                  -    MD0100PA00X+044657Y+033792                       
327m1751            U115  -31         A01X+044011Y+033929X0070Y0340R090 S1      
317m1751            VIA   -    MD0100PA00X+031531Y+035671X0200Y         S0      
317m1751            VIA   -    MD0100PA00X+137050Y+092550X0200Y         S0      
317m1751            VIA   -    MD0100PA00X+047107Y+093024X0200Y         S0      
327m1751            R3570 -1          A01X+137050Y+092308X0198Y0197R270 S1      
327m1752            R4675 -1          A01X+143258Y+077450X0198Y0197R180 S1      
327m1752            R4662 -2   M      A01X+143258Y+077050X0198Y0197     S1      
327m1752            R4691 -2          A01X+143742Y+077050X0198Y0197R180 S1      
317m1752            VIA   -    M      A01X+143500Y+077050X0200Y         S2      
017m1752            VIA   -    M      A18X+143500Y+077050X0260Y         S2      
017m1752                  -    MD0100PA00X+143500Y+077050                       
317m1752            VIA   -    MD0100PA00X+137360Y+083302X0180Y         S0      
327m1752            U6    -AA19       A01X+137202Y+083460X0160Y         S1      
327P3V3_SSD11_OCP   PU69  -9          A01X+124937Y+022506X0110Y0240     S1      
317P3V3_SSD11_OCP   VIA   -    M      A01X+124860Y+023056X0200Y    R090 S2      
017P3V3_SSD11_OCP   VIA   -    M      A18X+124860Y+023056X0260Y    R090 S2      
017P3V3_SSD11_OCP         -    MD0100PA00X+124860Y+023056                       
327P3V3_SSD11_OCP   PR286 -1          A01X+124922Y+023296X0198Y0197R090 S1      
317m1753            VIA   -    M      A01X+087989Y+078472X0200Y         S2      
017m1753            VIA   -    M      A18X+087989Y+078472X0260Y         S2      
017m1753                  -    MD0100PA00X+087989Y+078472                       
327m1753            U305  -2          A01X+087747Y+077590X0140Y0520R180 S1      
327m1753            R1025 -2          A18X+088005Y+078027X0198Y0197R270 S2      
317m1754            VIA   -    MD0100PA00X+006686Y+010425X0200Y         S0      
327m1754            J30   -B14        A01X+006010Y+010468X0150Y0500R090 S1      
317m1754            VIA   -    MD0100PA00X+041918Y+030447X0200Y    R270 S0      
327m1754            R1137 -1          A01X+041928Y+031269X0198Y0197R090 S1      
317PEX3_MODE_SEL1   VIA   -    MD0080PA00X+165659Y+111447X0160Y         S0      
327PEX3_MODE_SEL1   PEX3  -AW38       A01X+165472Y+111260X0180Y         S1      
317PEX3_MODE_SEL1   VIA   -    M      A01X+153110Y+098881X0200Y         S2      
017PEX3_MODE_SEL1   VIA   -    M      A18X+153110Y+098881X0260Y         S2      
017PEX3_MODE_SEL1         -    MD0100PA00X+153110Y+098881                       
327PEX3_MODE_SEL1   R1426 -2          A01X+153110Y+099196X0198Y0197R270 S1      
327PEX3_MODE_SEL1   R1406 -1   M      A01X+153110Y+098611X0198Y0197R270 S1      
327PEX3_MODE_SEL1   R6446 -2          A01X+160828Y+080913X0198Y0197R270 S1      
327SMB_NIC0_SDA     VIA   -    M      A18X+089139Y+089950X0260Y         S2      
327SMB_NIC0_SDA     R1478 -1          A18X+089129Y+090876X0198Y0197R270 S2      
327SMB_NIC0_SDA     U5    -P12        A01X+089239Y+087836X0160Y    R180 S1      
317SMB_NIC0_SDA     VIA   -    MD0100PA00X+089082Y+087994X0180Y    R270 S0      
327m1755            C4078 -2   M      A01X+057194Y+154421X0198Y0197R270 S1      
317m1755            J12   -H10  D0122PA00X+053429Y+158579X0282Y    R180 S3      
317m1755            VIA   -    M      A01X+057251Y+154138X0200Y         S2      
017m1755            VIA   -    M      A18X+057251Y+154138X0260Y         S2      
017m1755                  -    MD0100PA00X+057251Y+154138                       
327m1755            R1847 -2          A01X+057581Y+153858X0198Y0197R090 S1      
327MB_SWB_PWR_EN    R6448 -1          A01X+142625Y+141085X0198Y0197R270 S1      
317MB_SWB_PWR_EN    VIA   -    MD0100PA00X+143226Y+141460X0200Y         S0      
327MB_SWB_PWR_EN    C4164 -2   M      A01X+143226Y+141089X0198Y0197R090 S1      
317MB_SWB_PWR_EN    J14   -Z2   D0122PA00X+148697Y+145272X0282Y    R180 S3      
317MB_SWB_PWR_EN    VIA   -    MD0100PA00X+131077Y+128241X0200Y         S0      
317MB_SWB_PWR_EN    VIA   -    M      A01X+132555Y+096044X0200Y         S2      
017MB_SWB_PWR_EN    VIA   -    M      A18X+132555Y+096044X0260Y         S2      
017MB_SWB_PWR_EN          -    MD0100PA00X+132555Y+096044                       
327MB_SWB_PWR_EN    U144  -3          A01X+132694Y+095594X0140Y0440R180 S1      
327MB_SWB_PWR_EN    R1791 -2          A01X+132700Y+096392X0198Y0197R270 S1      
317MB_SWB_PWR_EN    VIA   -    MD0100PA00X+132277Y+104060X0200Y         S0      
327m1756            R4106 -2          A01X+055879Y+153453X0198Y0197R270 S1      
317m1756            VIA   -    MD0100PA00X+057285Y+151870X0200Y         S0      
317m1756            VIA   -    MD0100PA00X+079530Y+141700X0200Y         S0      
317m1756            VIA   -    MD0100PA00X+090651Y+129919X0200Y         S0      
317m1756            VIA   -    MD0100PA00X+091826Y+096974X0200Y         S0      
317m1756            VIA   -    MD0100PA00X+119630Y+099860X0200Y         S0      
327m1756            VIA   -    M      A18X+118771Y+098479X0260Y    R270 S2      
327m1756            R4099 -1   M      A18X+118922Y+099286X0198Y0197R090 S2      
327m1756            R4103 -1          A18X+120272Y+097086X0198Y0197R090 S2      
327m1756            U318  -6   M      A18X+119080Y+097672X0170Y0460R180 S2      
327PRSNT_SSD7_R_N   U6    -B20        A01X+137517Y+089444X0160Y         S1      
317PRSNT_SSD7_R_N   VIA   -    MD0100PA00X+137671Y+090100X0200Y         S0      
317PRSNT_SSD7_R_N   VIA   -    MD0100PA00X+091419Y+094532X0200Y         S0      
317PRSNT_SSD7_R_N   VIA   -    MD0100PA00X+091916Y+088309X0180Y    R270 S0      
327PRSNT_SSD7_R_N   U5    -R4         A01X+091759Y+088151X0160Y    R180 S1      
317PRSNT_SSD7_R_N   VIA   -    MD0100PA00X+079938Y+010656X0200Y         S0      
317PRSNT_SSD7_R_N   VIA   -    M      A01X+079329Y+014376X0200Y         S2      
017PRSNT_SSD7_R_N   VIA   -    M      A18X+079329Y+014376X0260Y         S2      
017PRSNT_SSD7_R_N         -    MD0100PA00X+079329Y+014376                       
327PRSNT_SSD7_R_N   R5562 -2          A01X+079006Y+014376X0198Y0197R270 S1      
327PRSNT_SSD7_R_N   R4067 -1   M      A01X+079614Y+010656X0198Y0197R270 S1      
327PRSNT_SSD7_R_N   R4066 -2          A01X+079216Y+010250X0198Y0197     S1      
327PRSNT_SSD7_R_N   C2770 -1   M      A01X+079216Y+010650X0198Y0197R180 S1      
317PRSNT_SSD7_R_N   VIA   -    MD0100PA00X+082597Y+034510X0200Y         S0      
327SSD10_PWR_EN     VIA   -    M      A01X+132900Y+081420X0300Y         S1      
327SSD10_PWR_EN     U6    -AB6        A01X+133108Y+083144X0160Y         S1      
327SSD10_PWR_EN     R4123 -1          A01X+132900Y+080958X0198Y0197R270 S1      
327P3V3_SSD9_OCP    PU64  -9          A01X+104465Y+022506X0110Y0240     S1      
317P3V3_SSD9_OCP    VIA   -    M      A01X+104388Y+023056X0200Y    R090 S2      
017P3V3_SSD9_OCP    VIA   -    M      A18X+104388Y+023056X0260Y    R090 S2      
017P3V3_SSD9_OCP          -    MD0100PA00X+104388Y+023056                       
327P3V3_SSD9_OCP    PR277 -1          A01X+104450Y+023296X0198Y0197R090 S1      
327m1757            J35   -B15        A01X+061955Y+010705X0150Y0500R090 S1      
317m1757            VIA   -    MD0100PA00X+046095Y+034053X0200Y         S0      
327m1757            R1146 -1          A01X+045573Y+034043X0198Y0197R180 S1      
317m1757            VIA   -    MD0100PA00X+062630Y+010765X0200Y         S0      
327PEX0_DBG_MODE4   PEX0  -AW34       A01X+026850Y+111260X0180Y         S1      
317PEX0_DBG_MODE4   VIA   -    MD0080PA00X+027037Y+111447X0160Y         S0      
317PEX0_DBG_MODE4   VIA   -    M      A01X+015184Y+098881X0200Y         S2      
017PEX0_DBG_MODE4   VIA   -    M      A18X+015184Y+098881X0260Y         S2      
017PEX0_DBG_MODE4         -    MD0100PA00X+015184Y+098881                       
327PEX0_DBG_MODE4   R1189 -2          A01X+015184Y+099196X0198Y0197R270 S1      
327PEX0_DBG_MODE4   R1127 -1          A01X+015184Y+098611X0198Y0197R270 S1      
317PEX3_MODE_SEL7   VIA   -    MD0080PA00X+161171Y+111821X0160Y         S0      
327PEX3_MODE_SEL7   R1432 -2          A01X+147110Y+099196X0198Y0197R270 S1      
327PEX3_MODE_SEL7   R1412 -1          A01X+147110Y+098611X0198Y0197R270 S1      
317PEX3_MODE_SEL7   VIA   -    MD0100PA00X+147130Y+098881X0200Y         S0      
327PEX3_MODE_SEL7   VIA   -    M      A18X+159626Y+106285X0260Y         S2      
327PEX3_MODE_SEL7   PEX3  -AV26       A01X+160984Y+111634X0180Y         S1      
327SMB_NIC3_SCL     VIA   -    M      A01X+086812Y+088030X0300Y         S1      
327SMB_NIC3_SCL     R1486 -1          A01X+085683Y+088776X0198Y0197R180 S1      
327SMB_NIC3_SCL     U5    -P15        A01X+088294Y+087836X0160Y    R180 S1      
327m1758            PU35  -8          A01X+075688Y+021120X0110Y0240R270 S1      
317m1758            VIA   -    M      A01X+076078Y+020704X0200Y         S2      
017m1758            VIA   -    M      A18X+076078Y+020704X0260Y         S2      
017m1758                  -    MD0100PA00X+076078Y+020704                       
327m1758            R866  -2          A01X+076365Y+020486X0198Y0197R180 S1      
327m1758            R4463 -1   M      A01X+076365Y+020886X0198Y0197     S1      
327SSD13_PWR_EN     VIA   -    M      A18X+133746Y+082404X0260Y         S2      
327SSD13_PWR_EN     R4135 -1          A18X+133300Y+081958X0198Y0197R090 S2      
327SSD13_PWR_EN     U6    -Y9         A01X+134053Y+083774X0160Y         S1      
317SSD13_PWR_EN     VIA   -    MD0100PA00X+133895Y+083617X0180Y         S0      
327P3V3_SSD13_OCP   PU65  -9          A01X+150174Y+022506X0110Y0240     S1      
317P3V3_SSD13_OCP   VIA   -    M      A01X+150096Y+023056X0200Y    R090 S2      
017P3V3_SSD13_OCP   VIA   -    M      A18X+150096Y+023056X0260Y    R090 S2      
017P3V3_SSD13_OCP         -    MD0100PA00X+150096Y+023056                       
327P3V3_SSD13_OCP   PR278 -1          A01X+150159Y+023296X0198Y0197R090 S1      
327m1759            U305  -3          A01X+087491Y+077590X0140Y0520R180 S1      
317m1759            VIA   -    M      A01X+087000Y+078000X0200Y         S2      
017m1759            VIA   -    M      A18X+087000Y+078000X0260Y         S2      
017m1759                  -    MD0100PA00X+087000Y+078000                       
327m1759            R1024 -2          A18X+087485Y+078028X0198Y0197R270 S2      
327m1760            VIA   -    M      A18X+052028Y+068262X0260Y         S2      
327m1760            R1468 -1          A18X+051778Y+067653X0198Y0197R090 S2      
317m1760            VIA   -    MD0100PA00X+052080Y+069238X0180Y         S0      
327m1760            U114  -L5         A01X+051957Y+069055X0090Y         S1      
327m1761            J35   -B14        A01X+061955Y+010468X0150Y0500R090 S1      
317m1761            VIA   -    MD0100PA00X+046095Y+034393X0200Y         S0      
327m1761            R1147 -1          A01X+045573Y+034403X0198Y0197R180 S1      
317m1761            VIA   -    MD0100PA00X+062630Y+010425X0200Y         S0      
317m1762            VIA   -    M      A01X+145927Y+101368X0200Y         S2      
017m1762            VIA   -    M      A18X+145927Y+101368X0260Y         S2      
017m1762                  -    MD0100PA00X+145927Y+101368                       
327m1762            R6156 -1          A01X+145596Y+100454X0198Y0197R270 S1      
327m1762            Q20   -2   M      A01X+145594Y+101221X0160Y0240R270 S1      
327m1762            R1458 -2          A01X+145855Y+102105X0198Y0197     S1      
317SMB_NIC7_SDA     VIA   -    MD0100PA00X+085916Y+084873X0200Y         S0      
327SMB_NIC7_SDA     VIA   -    M      A01X+086557Y+084988X0300Y         S1      
327SMB_NIC7_SDA     U5    -G16        A01X+087979Y+085632X0160Y    R180 S1      
327SMB_NIC7_SDA     R1505 -1          A01X+085683Y+084746X0198Y0197R180 S1      
317SMB_NIC7_SDA     VIA   -    MD0100PA00X+084624Y+084749X0200Y         S0      
327SMB_NIC7_SDA     R4880 -2          A01X+084384Y+084749X0198Y0197     S1      
317SSD1_PWR_EN_R    VIA   -    MD0100PA00X+018313Y+025630X0200Y         S0      
317SSD1_PWR_EN_R    VIA   -    MD0100PA00X+134250Y+092550X0200Y         S0      
317SSD1_PWR_EN_R    VIA   -    MD0100PA00X+023759Y+081527X0200Y         S0      
327SSD1_PWR_EN_R    R3594 -2          A01X+134250Y+092308X0198Y0197R090 S1      
327SSD1_PWR_EN_R    R5834 -1          A01X+018313Y+025954X0198Y0197R090 S1      
317SSD1_PWR_EN_R    VIA   -    M      A01X+020620Y+022863X0200Y         S2      
017SSD1_PWR_EN_R    VIA   -    M      A18X+020620Y+022863X0260Y         S2      
017SSD1_PWR_EN_R          -    MD0100PA00X+020620Y+022863                       
327SSD1_PWR_EN_R    R6840 -1   M      A01X+020420Y+022572X0198Y0197     S1      
327SSD1_PWR_EN_R    C2863 -1   M      A01X+020420Y+022186X0198Y0197     S1      
327SSD1_PWR_EN_R    PU32  -11         A01X+019743Y+021710X0110Y0240R270 S1      
327m1763            PU55  -8          A01X+048717Y+022506X0110Y0240     S1      
317m1763            VIA   -    M      A01X+048868Y+022782X0200Y    R090 S2      
017m1763            VIA   -    M      A18X+048868Y+022782X0260Y    R090 S2      
017m1763                  -    MD0100PA00X+048868Y+022782                       
327m1763            R4483 -1          A01X+048784Y+024168X0198Y0197     S1      
327m1763            R887  -2   M      A01X+048929Y+023298X0198Y0197R270 S1      
317m1764            VIA   -    M      A01X+112411Y+020886X0200Y         S2      
017m1764            VIA   -    M      A18X+112411Y+020886X0260Y         S2      
017m1764                  -    MD0100PA00X+112411Y+020886                       
317m1764            VIA   -    MD0100PA00X+132320Y+083302X0180Y         S0      
327m1764            U6    -AA4        A01X+132478Y+083460X0160Y         S1      
327m1764            R4468 -2          A01X+112153Y+020886X0198Y0197     S1      
317m1764            VIA   -    MD0100PA00X+107452Y+025888X0200Y         S0      
327m1764            R5995 -2          A01X+103025Y+024208X0198Y0197R180 S1      
317m1765            VIA   -    MD0100PA00X+042705Y+030747X0200Y    R270 S0      
327m1765            R1139 -1          A01X+042715Y+031269X0198Y0197R090 S1      
317m1765            VIA   -    MD0100PA00X+016922Y+010425X0200Y         S0      
327m1765            J31   -B14        A01X+016246Y+010468X0150Y0500R090 S1      
327PEX0_DBG_MODE3   R1188 -2          A01X+011184Y+099196X0198Y0197R270 S1      
327PEX0_DBG_MODE3   R1126 -1          A01X+011184Y+098611X0198Y0197R270 S1      
317PEX0_DBG_MODE3   VIA   -    M      A01X+011184Y+098881X0200Y         S2      
017PEX0_DBG_MODE3   VIA   -    M      A18X+011184Y+098881X0260Y         S2      
017PEX0_DBG_MODE3         -    MD0100PA00X+011184Y+098881                       
327PEX0_DBG_MODE3   PEX0  -AW26       A01X+023858Y+111260X0180Y         S1      
317PEX0_DBG_MODE3   VIA   -    MD0080PA00X+024045Y+111447X0160Y         S0      
317PEX3_MODE_SEL0   VIA   -    M      A01X+149110Y+098881X0200Y         S2      
017PEX3_MODE_SEL0   VIA   -    M      A18X+149110Y+098881X0260Y         S2      
017PEX3_MODE_SEL0         -    MD0100PA00X+149110Y+098881                       
327PEX3_MODE_SEL0   R1425 -2          A01X+149110Y+099196X0198Y0197R270 S1      
327PEX3_MODE_SEL0   R1405 -1          A01X+149110Y+098611X0198Y0197R270 S1      
327PEX3_MODE_SEL0   PEX3  -AW27       A01X+161358Y+111260X0180Y         S1      
317PEX3_MODE_SEL0   VIA   -    MD0080PA00X+161545Y+111447X0160Y         S0      
327SMB_NIC0_SCL     VIA   -    M      A18X+087708Y+088738X0260Y         S2      
317SMB_NIC0_SCL     VIA   -    MD0100PA00X+088137Y+088309X0180Y    R270 S0      
327SMB_NIC0_SCL     R1477 -1          A18X+087529Y+090876X0198Y0197R270 S2      
327SMB_NIC0_SCL     U5    -R15        A01X+088294Y+088151X0160Y    R180 S1      
317m1766            VIA   -    M      A01X+133600Y+094350X0200Y         S2      
017m1766            VIA   -    M      A18X+133600Y+094350X0260Y         S2      
017m1766                  -    MD0100PA00X+133600Y+094350                       
327m1766            U144  -6          A01X+133206Y+094806X0140Y0440R180 S1      
327m1766            R1794 -1          A01X+133600Y+094108X0198Y0197R270 S1      
327SSD1_PWRDIS_R    J31   -B12        A01X+016246Y+009996X0150Y0500R090 S1      
317SSD1_PWRDIS_R    VIA   -    MD0100PA00X+015823Y+009996X0200Y         S0      
327SSD1_PWRDIS_R    R6199 -2          A01X+019947Y+011449X0198Y0197R180 S1      
317SSD1_PWRDIS_R    VIA   -    MD0100PA00X+019738Y+011208X0200Y         S0      
317SSD1_PWRDIS_R    VIA   -    MD0100PA00X+133850Y+092550X0200Y         S0      
317SSD1_PWRDIS_R    VIA   -    M      A01X+025630Y+081225X0200Y         S2      
017SSD1_PWRDIS_R    VIA   -    M      A18X+025630Y+081225X0260Y         S2      
017SSD1_PWRDIS_R          -    MD0100PA00X+025630Y+081225                       
327SSD1_PWRDIS_R    R3596 -2          A01X+133850Y+092308X0198Y0197R090 S1      
327m1767            PU58  -8          A01X+069189Y+022506X0110Y0240     S1      
317m1767            VIA   -    M      A01X+069341Y+022782X0200Y    R090 S2      
017m1767            VIA   -    M      A18X+069341Y+022782X0260Y    R090 S2      
017m1767                  -    MD0100PA00X+069341Y+022782                       
327m1767            R4490 -1          A01X+069256Y+024168X0198Y0197     S1      
327m1767            R891  -2   M      A01X+069401Y+023298X0198Y0197R270 S1      
317m1768            VIA   -    MD0100PA00X+161119Y+010656X0200Y         S0      
317m1768            VIA   -    MD0100PA00X+160214Y+035105X0200Y         S0      
327m1768            R4080 -2          A01X+160397Y+010250X0198Y0197     S1      
327m1768            C2777 -1   M      A01X+160397Y+010650X0198Y0197R180 S1      
327m1768            R4081 -1   M      A01X+160796Y+010656X0198Y0197R270 S1      
317m1768            VIA   -    M      A01X+160510Y+014376X0200Y         S2      
017m1768            VIA   -    M      A18X+160510Y+014376X0260Y         S2      
017m1768                  -    MD0100PA00X+160510Y+014376                       
327m1768            R5580 -2          A01X+160187Y+014376X0198Y0197R270 S1      
317m1768            VIA   -    MD0100PA00X+139957Y+039742X0200Y         S0      
327m1768            U6    -T11        A01X+134683Y+085034X0160Y         S1      
317m1768            VIA   -    MD0100PA00X+134525Y+084877X0180Y         S0      
317m1768            VIA   -    MD0100PA00X+097835Y+073077X0200Y         S0      
327m1768            U5    -N2         A01X+092389Y+087521X0160Y    R180 S1      
317m1768            VIA   -    MD0100PA00X+092546Y+087679X0180Y    R270 S0      
327P3V3_SSD13_SS    PU65  -7          A01X+150567Y+022506X0110Y0240     S1      
317P3V3_SSD13_SS    VIA   -    M      A01X+150981Y+023012X0200Y    R090 S2      
017P3V3_SSD13_SS    VIA   -    M      A18X+150981Y+023012X0260Y    R090 S2      
017P3V3_SSD13_SS          -    MD0100PA00X+150981Y+023012                       
327P3V3_SSD13_SS    PC567 -1          A01X+150982Y+023298X0198Y0197R090 S1      
327m1769            R1023 -2          A18X+088511Y+078027X0198Y0197R270 S2      
317m1769            VIA   -    M      A01X+089204Y+078451X0200Y         S2      
017m1769            VIA   -    M      A18X+089204Y+078451X0260Y         S2      
017m1769                  -    MD0100PA00X+089204Y+078451                       
327m1769            U305  -1          A01X+088003Y+077590X0140Y0520R180 S1      
327m1770            J34   -B14        A01X+051718Y+010468X0150Y0500R090 S1      
317m1770            VIA   -    MD0100PA00X+046395Y+033606X0200Y         S0      
327m1770            R1145 -1          A01X+045573Y+033616X0198Y0197R180 S1      
317m1770            VIA   -    MD0100PA00X+052394Y+010425X0200Y         S0      
317SMB_NIC4_SCL     VIA   -    MD0100PA00X+085960Y+086357X0200Y         S0      
327SMB_NIC4_SCL     VIA   -    M      A01X+086278Y+086247X0300Y         S1      
327SMB_NIC4_SCL     U5    -J16        A01X+087979Y+086262X0160Y    R180 S1      
327SMB_NIC4_SCL     R1498 -1          A01X+085683Y+086346X0198Y0197R180 S1      
317SMB_NIC4_SCL     VIA   -    MD0100PA00X+084582Y+086341X0200Y         S0      
327SMB_NIC4_SCL     R4873 -2          A01X+084331Y+086341X0198Y0197     S1      
317m1771            VIA   -    M      A01X+040966Y+033159X0200Y         S2      
017m1771            VIA   -    M      A18X+040966Y+033159X0260Y         S2      
017m1771                  -    MD0100PA00X+040966Y+033159                       
327m1771            R1470 -1          A01X+040713Y+033159X0198Y0197R180 S1      
327m1771            U115  -7          A01X+041689Y+033771X0070Y0340R270 S1      
317m1772            VIA   -    MD0100PA00X+133645Y+076568X0200Y         S0      
317m1772            VIA   -    MD0100PA00X+146082Y+072796X0200Y         S0      
327m1772            R4240 -2          A01X+133922Y+076568X0198Y0197R180 S1      
317m1772            VIA   -           A01X+128254Y+074608X0200Y         S2      
017m1772            VIA   -           A18X+128254Y+074608X0260Y         S2      
017m1772                  -     D0100PA00X+128254Y+074608                       
327m1772            U324  -20         A01X+132128Y+076632X0160Y0540R270 S1      
327m1772            R3555 -2          A01X+133050Y+092308X0198Y0197R090 S1      
317m1772            VIA   -    MD0100PA00X+133050Y+092550X0200Y         S0      
327m1773            U115  -30         A01X+044011Y+033771X0070Y0340R090 S1      
317m1773            VIA   -    MD0100PA00X+044351Y+033771X0200Y         S0      
317m1773            VIA   -    M      A01X+031850Y+035652X0200Y         S2      
017m1773            VIA   -    M      A18X+031850Y+035652X0260Y         S2      
017m1773                  -    MD0100PA00X+031850Y+035652                       
327m1773            R3556 -1          A18X+135050Y+092108X0198Y0197R090 S2      
317m1773            VIA   -    MD0100PA00X+047111Y+092158X0200Y         S0      
317m1773            VIA   -    MD0100PA00X+134650Y+093050X0200Y         S0      
317m1774            VIA   -    M      A01X+140038Y+014376X0200Y         S2      
017m1774            VIA   -    M      A18X+140038Y+014376X0260Y         S2      
017m1774                  -    MD0100PA00X+140038Y+014376                       
317m1774            VIA   -    MD0100PA00X+140647Y+010656X0200Y         S0      
327m1774            R4077 -1   M      A01X+140323Y+010656X0198Y0197R270 S1      
327m1774            R4076 -2          A01X+139925Y+010250X0198Y0197     S1      
327m1774            C2775 -1   M      A01X+139925Y+010650X0198Y0197R180 S1      
327m1774            R5568 -2          A01X+139715Y+014376X0198Y0197R270 S1      
317m1774            VIA   -    MD0100PA00X+137517Y+042474X0200Y         S0      
317m1774            VIA   -    MD0100PA00X+133580Y+083302X0180Y         S0      
327m1774            U5    -M1         A01X+092704Y+087206X0160Y    R180 S1      
317m1774            VIA   -    MD0100PA00X+092861Y+087364X0180Y    R270 S0      
317m1774            VIA   -    MD0100PA00X+097108Y+072264X0200Y         S0      
327m1774            U6    -AA8        A01X+133738Y+083460X0160Y         S1      
327P3V3_SSD15_OCP   PU68  -9          A01X+170646Y+022506X0110Y0240     S1      
317P3V3_SSD15_OCP   VIA   -    M      A01X+170569Y+023056X0200Y    R090 S2      
017P3V3_SSD15_OCP   VIA   -    M      A18X+170569Y+023056X0260Y    R090 S2      
017P3V3_SSD15_OCP         -    MD0100PA00X+170569Y+023056                       
327P3V3_SSD15_OCP   PR285 -1          A01X+170631Y+023296X0198Y0197R090 S1      
317m1775            VIA   -    MD0100PA00X+042365Y+030747X0200Y    R270 S0      
327m1775            R1138 -1          A01X+042355Y+031269X0198Y0197R090 S1      
317m1775            VIA   -    MD0100PA00X+016922Y+010765X0200Y         S0      
327m1775            J31   -B15        A01X+016246Y+010705X0150Y0500R090 S1      
327PEX0_DBG_MODE2   PEX0  -AW30       A01X+025354Y+111260X0180Y         S1      
317PEX0_DBG_MODE2   VIA   -    MD0080PA00X+025541Y+111447X0160Y         S0      
327PEX0_DBG_MODE2   R1187 -2          A01X+013184Y+099196X0198Y0197R270 S1      
327PEX0_DBG_MODE2   R1119 -1          A01X+013184Y+098611X0198Y0197R270 S1      
317PEX0_DBG_MODE2   VIA   -    MD0100PA00X+013184Y+098881X0200Y         S0      
327PEX0_DBG_MODE2   VIA   -    M      A18X+024060Y+105332X0260Y         S2      
327SMB_NIC6_SCL     VIA   -    M      A01X+086166Y+085314X0300Y         S1      
327SMB_NIC6_SCL     R1502 -1   M      A01X+085683Y+085146X0198Y0197R180 S1      
327SMB_NIC6_SCL     U5    -H15        A01X+088294Y+085946X0160Y    R180 S1      
327SMB_NIC6_SCL     R4877 -2          A01X+084588Y+085146X0198Y0197     S1      
317m1776            VIA   -    M      A01X+041009Y+033680X0200Y         S2      
017m1776            VIA   -    M      A18X+041009Y+033680X0260Y         S2      
017m1776                  -    MD0100PA00X+041009Y+033680                       
327m1776            R1469 -1          A01X+040713Y+033559X0198Y0197R180 S1      
327m1776            U115  -6          A01X+041689Y+033929X0070Y0340R270 S1      
327m1777            PU59  -8          A01X+023481Y+022506X0110Y0240     S1      
317m1777            VIA   -    M      A01X+023632Y+022782X0200Y    R090 S2      
017m1777            VIA   -    M      A18X+023632Y+022782X0260Y    R090 S2      
017m1777                  -    MD0100PA00X+023632Y+022782                       
327m1777            R4491 -1          A01X+023548Y+024168X0198Y0197     S1      
327m1777            R890  -2   M      A01X+023692Y+023298X0198Y0197R270 S1      
327SSD12_PWRDIS     VIA   -    M      A01X+133700Y+081420X0300Y         S1      
327SSD12_PWRDIS     U6    -AA9        A01X+134053Y+083460X0160Y         S1      
327SSD12_PWRDIS     R4132 -1          A01X+133700Y+080958X0198Y0197R270 S1      
327P3V3_SSD14_OCP   PU67  -9          A01X+160410Y+022506X0110Y0240     S1      
317P3V3_SSD14_OCP   VIA   -    M      A01X+160332Y+023056X0200Y    R090 S2      
017P3V3_SSD14_OCP   VIA   -    M      A18X+160332Y+023056X0260Y    R090 S2      
017P3V3_SSD14_OCP         -    MD0100PA00X+160332Y+023056                       
327P3V3_SSD14_OCP   PR282 -1          A01X+160395Y+023296X0198Y0197R090 S1      
327m1778            J32   -B14        A01X+026482Y+010468X0150Y0500R090 S1      
317m1778            VIA   -    MD0100PA00X+043492Y+030447X0200Y    R270 S0      
327m1778            R1141 -1          A01X+043502Y+031269X0198Y0197R090 S1      
317m1778            VIA   -    MD0100PA00X+027158Y+010425X0200Y         S0      
317PEX3_MODE_SEL5   VIA   -    MD0080PA00X+160797Y+111447X0160Y         S0      
327PEX3_MODE_SEL5   R1430 -2          A01X+147910Y+099196X0198Y0197R270 S1      
327PEX3_MODE_SEL5   R1410 -1          A01X+147910Y+098611X0198Y0197R270 S1      
317PEX3_MODE_SEL5   VIA   -    MD0100PA00X+147910Y+098881X0200Y         S0      
327PEX3_MODE_SEL5   VIA   -    M      A18X+159543Y+105598X0260Y         S2      
327PEX3_MODE_SEL5   PEX3  -AW25       A01X+160610Y+111260X0180Y         S1      
327SMB_NIC1_SDA     VIA   -    M      A18X+087929Y+089518X0260Y         S2      
327SMB_NIC1_SDA     R1480 -1          A18X+087929Y+090876X0198Y0197R270 S2      
327SMB_NIC1_SDA     U5    -N14        A01X+088609Y+087521X0160Y    R180 S1      
317SMB_NIC1_SDA     VIA   -    MD0100PA00X+088452Y+087679X0180Y    R270 S0      
327GPU_BASE_ID1     C4037 -2          A01X+023061Y+149436X0198Y0197     S1      
317GPU_BASE_ID1     VIA   -    M      A01X+023317Y+149145X0200Y         S2      
017GPU_BASE_ID1     VIA   -    M      A18X+023317Y+149145X0260Y         S2      
017GPU_BASE_ID1           -    MD0100PA00X+023317Y+149145                       
317GPU_BASE_ID1     J11   -Z8   D0122PA00X+034374Y+145272X0282Y    R180 S3      
327GPU_BASE_ID1     R1825 -2   M      A01X+023062Y+149044X0198Y0197     S1      
317m1779            J12   -C9   D0122PA00X+052563Y+161217X0282Y    R180 S3      
327m1779            R1845 -1          A01X+057981Y+153858X0198Y0197R270 S1      
317m1779            VIA   -    M      A01X+057757Y+154401X0200Y         S2      
017m1779            VIA   -    M      A18X+057757Y+154401X0260Y         S2      
017m1779                  -    MD0100PA00X+057757Y+154401                       
317m1780            VIA   -    MD0100PA00X+132950Y+088656X0180Y         S0      
327m1780            U6    -E6         A01X+133108Y+088499X0160Y         S1      
317m1780            VIA   -    M      A01X+133313Y+093378X0200Y         S2      
017m1780            VIA   -    M      A18X+133313Y+093378X0260Y         S2      
017m1780                  -    MD0100PA00X+133313Y+093378                       
327m1780            R1794 -2          A01X+133600Y+093792X0198Y0197R270 S1      
327m1780            R1792 -2   M      A01X+133600Y+093408X0198Y0197R090 S1      
317CLK_25M_FPGA_R   VIA   -    M      A01X+130250Y+082475X0200Y    R180 S2      
017CLK_25M_FPGA_R   VIA   -    M      A18X+130250Y+082475X0260Y    R180 S2      
017CLK_25M_FPGA_R         -    MD0100PA00X+130250Y+082475                       
327CLK_25M_FPGA_R   R4405 -1          A01X+129891Y+081867X0198Y0197R270 S1      
327CLK_25M_FPGA_R   U6    -U2         A01X+131848Y+084719X0160Y         S1      
327m1781            VIA   -    M      A01X+134100Y+081750X0300Y         S1      
327m1781            U6    -AB9        A01X+134053Y+083144X0160Y         S1      
327m1781            R4133 -1          A01X+134100Y+080958X0198Y0197R270 S1      
327m1782            J32   -B15        A01X+026482Y+010705X0150Y0500R090 S1      
317m1782            VIA   -    MD0100PA00X+043152Y+030447X0200Y    R270 S0      
327m1782            R1140 -1          A01X+043142Y+031269X0198Y0197R090 S1      
317m1782            VIA   -    MD0100PA00X+027158Y+010765X0200Y         S0      
317PEX0_DBG_MODE1   VIA   -    MD0080PA00X+018996Y+121732X0160Y    R180 S0      
317PEX0_DBG_MODE1   VIA   -    M      A01X+013576Y+122141X0200Y         S2      
017PEX0_DBG_MODE1   VIA   -    M      A18X+013576Y+122141X0260Y         S2      
017PEX0_DBG_MODE1         -    MD0100PA00X+013576Y+122141                       
327PEX0_DBG_MODE1   R1118 -1   M      A01X+013157Y+121424X0198Y0197R225 S1      
327PEX0_DBG_MODE1   R1186 -2          A01X+013440Y+121141X0198Y0197R045 S1      
327PEX0_DBG_MODE1   PEX0  -L13        A01X+018996Y+121732X0180Y         S1      
317PEX3_MODE_SEL9   VIA   -    MD0080PA00X+161919Y+111821X0160Y         S0      
327PEX3_MODE_SEL9   R1434 -2          A01X+146710Y+099196X0198Y0197R270 S1      
327PEX3_MODE_SEL9   R1414 -1          A01X+146710Y+098611X0198Y0197R270 S1      
317PEX3_MODE_SEL9   VIA   -    M      A01X+146710Y+098881X0200Y         S2      
017PEX3_MODE_SEL9   VIA   -    M      A18X+146710Y+098881X0260Y         S2      
017PEX3_MODE_SEL9         -    MD0100PA00X+146710Y+098881                       
327PEX3_MODE_SEL9   PEX3  -AV28       A01X+161732Y+111634X0180Y         S1      
317SMB_NIC2_SDA     VIA   -    MD0100PA00X+084710Y+089121X0200Y         S2      
327SMB_NIC2_SDA     R1484 -1          A01X+084425Y+089256X0198Y0197R180 S1      
327SMB_NIC2_SDA     U5    -R16        A01X+087979Y+088151X0160Y    R180 S1      
327m1783            J31   -B10        A01X+016246Y+009524X0150Y0500R090 S1      
317m1783            VIA   -    MD0100PA00X+015828Y+009524X0200Y         S0      
327m1783            R3598 -2          A01X+135395Y+094918X0198Y0197R090 S1      
317m1783            VIA   -    MD0100PA00X+132474Y+098997X0200Y         S0      
317m1783            VIA   -    M      A01X+027512Y+084787X0200Y         S2      
017m1783            VIA   -    M      A18X+027512Y+084787X0260Y         S2      
017m1783                  -    MD0100PA00X+027512Y+084787                       
327SSD7_PWRDIS_R    J37   -B12        A01X+082427Y+009996X0150Y0500R090 S1      
317SSD7_PWRDIS_R    VIA   -    M      A01X+082004Y+009996X0200Y         S2      
017SSD7_PWRDIS_R    VIA   -    M      A18X+082004Y+009996X0260Y         S2      
017SSD7_PWRDIS_R          -    MD0100PA00X+082004Y+009996                       
317SSD7_PWRDIS_R    VIA   -    MD0100PA00X+085919Y+011208X0200Y         S0      
327SSD7_PWRDIS_R    R6205 -2          A01X+086128Y+011449X0198Y0197R180 S1      
317SSD7_PWRDIS_R    VIA   -    MD0100PA00X+087662Y+029372X0200Y         S0      
317SSD7_PWRDIS_R    VIA   -    MD0100PA00X+140292Y+032240X0200Y         S0      
317SSD7_PWRDIS_R    VIA   -    MD0100PA00X+140100Y+092579X0200Y         S0      
327SSD7_PWRDIS_R    R3593 -1          A01X+140100Y+092308X0198Y0197R270 S1      
327m1784            VIA   -    M      A18X+134150Y+083100X0260Y         S2      
327m1784            R4129 -1          A18X+133750Y+081958X0198Y0197R090 S2      
327m1784            U6    -V9         A01X+134053Y+084404X0160Y         S1      
317m1784            VIA   -    MD0100PA00X+133895Y+084247X0180Y         S0      
327m1785            J34   -B15        A01X+051718Y+010705X0150Y0500R090 S1      
317m1785            VIA   -    MD0100PA00X+052394Y+010765X0200Y         S0      
317m1785            VIA   -    MD0100PA00X+046395Y+033266X0200Y         S0      
327m1785            R1144 -1          A01X+045573Y+033256X0198Y0197R180 S1      
317m1786            VIA   -    M      A01X+150710Y+098881X0200Y         S2      
017m1786            VIA   -    M      A18X+150710Y+098881X0260Y         S2      
017m1786                  -    MD0100PA00X+150710Y+098881                       
327m1786            R1436 -2          A01X+150710Y+099196X0198Y0197R270 S1      
327m1786            R1416 -1          A01X+150710Y+098611X0198Y0197R270 S1      
327m1786            PEX3  -AW31       A01X+162854Y+111260X0180Y         S1      
317m1786            VIA   -    MD0080PA00X+163041Y+111447X0160Y         S0      
327SMB_NIC6_R_SDA   R1525 -1   M      A01X+083008Y+078050X0198Y0197R180 S1      
327SMB_NIC6_R_SDA   U121  -2          A01X+083670Y+078128X0140Y0590R270 S1      
317SMB_NIC6_R_SDA   VIA   -    M      A01X+082450Y+078250X0200Y         S2      
017SMB_NIC6_R_SDA   VIA   -    M      A18X+082450Y+078250X0260Y         S2      
017SMB_NIC6_R_SDA         -    MD0100PA00X+082450Y+078250                       
327SMB_NIC6_R_SDA   R1528 -2          A18X+083500Y+078092X0198Y0197R090 S2      
327SMB_NIC6_R_SDA   R1503 -2          A01X+085368Y+084346X0198Y0197R180 S1      
317SMB_NIC6_R_SDA   VIA   -    MD0100PA00X+084838Y+084346X0200Y         S0      
317UART_MB_BIC_RX   VIA   -           A01X+141771Y+130173X0200Y         S2      
017UART_MB_BIC_RX   VIA   -           A18X+141771Y+130173X0260Y         S2      
017UART_MB_BIC_RX         -     D0100PA00X+141771Y+130173                       
327UART_MB_BIC_RX   R6297 -1   M      A18X+155715Y+141881X0198Y0197R180 S2      
327UART_MB_BIC_RX   R5472 -2          A18X+155130Y+141885X0198Y0197R180 S2      
317UART_MB_BIC_RX   J14   -Z10 MD0122PA00X+155626Y+145272X0282Y    R180 S3      
317PRSNT_SSD2_R_N   VIA   -    MD0100PA00X+023384Y+014376X0200Y         S0      
317PRSNT_SSD2_R_N   VIA   -    MD0100PA00X+023993Y+010656X0200Y         S0      
317PRSNT_SSD2_R_N   VIA   -    M      A01X+023326Y+035919X0200Y         S2      
017PRSNT_SSD2_R_N   VIA   -    M      A18X+023326Y+035919X0260Y         S2      
017PRSNT_SSD2_R_N         -    MD0100PA00X+023326Y+035919                       
317PRSNT_SSD2_R_N   VIA   -    MD0100PA00X+044839Y+038264X0200Y         S0      
317PRSNT_SSD2_R_N   VIA   -    MD0100PA00X+043230Y+078507X0200Y    R270 S0      
317PRSNT_SSD2_R_N   VIA   -    MD0100PA00X+097619Y+078982X0200Y         S0      
317PRSNT_SSD2_R_N   VIA   -    MD0100PA00X+092546Y+088624X0180Y    R270 S0      
327PRSNT_SSD2_R_N   U5    -T2         A01X+092389Y+088466X0160Y    R180 S1      
327PRSNT_SSD2_R_N   R4056 -2          A01X+023271Y+010250X0198Y0197     S1      
327PRSNT_SSD2_R_N   C2765 -1   M      A01X+023271Y+010650X0198Y0197R180 S1      
327PRSNT_SSD2_R_N   R4057 -1   M      A01X+023670Y+010656X0198Y0197R270 S1      
327PRSNT_SSD2_R_N   R5547 -2          A01X+023061Y+014376X0198Y0197R270 S1      
327PRSNT_SSD2_R_N   U6    -A4         A01X+132478Y+089759X0160Y         S1      
317PRSNT_SSD2_R_N   VIA   -    MD0100PA00X+132400Y+090100X0200Y         S0      
317PRSNT_SSD2_R_N   VIA   -    MD0100PA00X+131132Y+092892X0200Y         S0      
327m1787            U6    -V6         A01X+133108Y+084404X0160Y         S1      
317m1787            VIA   -    MD0100PA00X+132950Y+084247X0180Y         S0      
327m1787            R6082 -2          A01X+090011Y+014125X0198Y0197     S1      
327m1787            U391  -1          A01X+092045Y+014265X0240Y0240     S1      
317m1787            VIA   -    MD0100PA00X+090304Y+014125X0200Y         S0      
317m1787            VIA   -    MD0100PA00X+094997Y+029155X0200Y         S0      
317m1787            VIA   -    MD0100PA00X+125600Y+033800X0200Y         S0      
317m1787            VIA   -    M      A01X+094874Y+022947X0200Y    R090 S2      
017m1787            VIA   -    M      A18X+094874Y+022947X0260Y    R090 S2      
017m1787                  -    MD0100PA00X+094874Y+022947                       
327m1787            R4498 -2          A01X+094874Y+022685X0198Y0197     S1      
317PEX0_DBG_MODE0   VIA   -    MD0080PA00X+018622Y+121732X0160Y         S0      
317PEX0_DBG_MODE0   VIA   -    MD0100PA00X+012925Y+122765X0200Y         S0      
327PEX0_DBG_MODE0   R1169 -2          A01X+012591Y+121990X0198Y0197R045 S1      
327PEX0_DBG_MODE0   R1111 -1          A01X+012308Y+122272X0198Y0197R225 S1      
327PEX0_DBG_MODE0   VIA   -    M      A18X+013610Y+121484X0260Y         S2      
327PEX0_DBG_MODE0   PEX0  -L12        A01X+018622Y+121732X0180Y         S1      
327SMB_NIC7_R_SCL   U122  -3          A01X+083670Y+076072X0140Y0590R270 S1      
327SMB_NIC7_R_SCL   R1533 -1   M      A01X+083008Y+075850X0198Y0197R180 S1      
317SMB_NIC7_R_SCL   VIA   -    M      A01X+082450Y+075600X0200Y         S2      
017SMB_NIC7_R_SCL   VIA   -    M      A18X+082450Y+075600X0260Y         S2      
017SMB_NIC7_R_SCL         -    MD0100PA00X+082450Y+075600                       
327SMB_NIC7_R_SCL   R1534 -2          A18X+083500Y+075908X0198Y0197R270 S2      
317SMB_NIC7_R_SCL   VIA   -    MD0100PA00X+084634Y+085546X0200Y         S0      
327SMB_NIC7_R_SCL   R1504 -2          A18X+085368Y+085946X0198Y0197     S2      
327m1788            PU33  -8          A01X+065452Y+021120X0110Y0240R270 S1      
317m1788            VIA   -    M      A01X+065842Y+020704X0200Y         S2      
017m1788            VIA   -    M      A18X+065842Y+020704X0260Y         S2      
017m1788                  -    MD0100PA00X+065842Y+020704                       
327m1788            R864  -2          A01X+066129Y+020486X0198Y0197R180 S1      
327m1788            R4461 -1   M      A01X+066129Y+020886X0198Y0197     S1      
317m1789            VIA   -    MD0100PA00X+133580Y+083617X0180Y         S0      
327m1789            U6    -Y8         A01X+133738Y+083774X0160Y         S1      
327m1789            U395  -1          A01X+137754Y+014265X0240Y0240     S1      
327m1789            R6106 -2          A01X+135720Y+014125X0198Y0197     S1      
317m1789            VIA   -    M      A01X+136012Y+014125X0200Y         S2      
017m1789            VIA   -    M      A18X+136012Y+014125X0260Y         S2      
017m1789                  -    MD0100PA00X+136012Y+014125                       
317m1789            VIA   -    MD0100PA00X+140516Y+024430X0200Y    R090 S0      
327m1789            R4499 -2          A01X+140516Y+024168X0198Y0197     S1      
317m1789            VIA   -    MD0100PA00X+134842Y+026522X0200Y         S0      
317PEX3_MODE_SEL3   VIA   -    MD0080PA00X+161545Y+111821X0160Y         S0      
327PEX3_MODE_SEL3   VIA   -    M      A18X+160426Y+105876X0260Y         S2      
327PEX3_MODE_SEL3   PEX3  -AV27       A01X+161358Y+111634X0180Y         S1      
317PEX3_MODE_SEL3   VIA   -    MD0100PA00X+148710Y+098881X0200Y         S0      
327PEX3_MODE_SEL3   R1428 -2          A01X+148710Y+099196X0198Y0197R270 S1      
327PEX3_MODE_SEL3   R1408 -1          A01X+148710Y+098611X0198Y0197R270 S1      
327SMB_NIC0_R_SDA   J20   -A8         A01X+019938Y+055892X0140Y0480R270 S1      
327SMB_NIC0_R_SDA   R10   -1          A01X+021842Y+055880X0198Y0197     S1      
317SMB_NIC0_R_SDA   VIA   -    MD0100PA00X+020467Y+055892X0200Y    R180 S0      
317SMB_NIC0_R_SDA   VIA   -    M      A01X+024856Y+082400X0200Y         S2      
017SMB_NIC0_R_SDA   VIA   -    M      A18X+024856Y+082400X0260Y         S2      
017SMB_NIC0_R_SDA         -    MD0100PA00X+024856Y+082400                       
327SMB_NIC0_R_SDA   R1478 -2          A18X+089129Y+091191X0198Y0197R270 S2      
317SMB_NIC0_R_SDA   VIA   -    MD0100PA00X+088918Y+090562X0200Y         S0      
317I3C_MB_BMC_SDA   J14   -H10  D0122PA00X+155626Y+158579X0282Y    R180 S3      
317I3C_MB_BMC_SDA   VIA   -    M      A01X+160150Y+151450X0200Y         S2      
017I3C_MB_BMC_SDA   VIA   -    M      A18X+160150Y+151450X0260Y         S2      
017I3C_MB_BMC_SDA         -    MD0100PA00X+160150Y+151450                       
327I3C_MB_BMC_SDA   R6279 -2          A01X+160150Y+151208X0198Y0197R090 S1      
317m1790            VIA   -    MD0100PA00X+051301Y+009524X0200Y         S0      
327m1790            J34   -B10        A01X+051718Y+009524X0150Y0500R090 S1      
317m1790            VIA   -    MD0100PA00X+136250Y+092550X0200Y         S0      
317m1790            VIA   -    M      A01X+060472Y+091464X0200Y         S2      
017m1790            VIA   -    M      A18X+060472Y+091464X0260Y         S2      
017m1790                  -    MD0100PA00X+060472Y+091464                       
327m1790            R3554 -1          A01X+136250Y+092308X0198Y0197R270 S1      
317SSD12_CLK_EN_N   VIA   -    M      A01X+133300Y+079900X0200Y    R180 S2      
017SSD12_CLK_EN_N   VIA   -    M      A18X+133300Y+079900X0260Y    R180 S2      
017SSD12_CLK_EN_N         -    MD0100PA00X+133300Y+079900                       
327SSD12_CLK_EN_N   R4134 -1          A01X+133300Y+079358X0198Y0197R270 S1      
317SSD12_CLK_EN_N   VIA   -    MD0100PA00X+134210Y+084877X0180Y         S0      
327SSD12_CLK_EN_N   U6    -T10        A01X+134368Y+085034X0160Y         S1      
327PEX0_DBG_SEL1    PEX0  -M19        A01X+021240Y+121358X0180Y         S1      
317PEX0_DBG_SEL1    VIA   -    MD0080PA00X+021053Y+121545X0160Y         S0      
317PEX0_DBG_SEL1    VIA   -    M      A01X+012643Y+123041X0200Y         S2      
017PEX0_DBG_SEL1    VIA   -    M      A18X+012643Y+123041X0260Y         S2      
017PEX0_DBG_SEL1          -    MD0100PA00X+012643Y+123041                       
327PEX0_DBG_SEL1    R1168 -2   M      A01X+011743Y+122838X0198Y0197R045 S1      
327PEX0_DBG_SEL1    R1093 -1          A01X+010960Y+122660X0198Y0197R270 S1      
317PEX3_DBG_MODE0   VIA   -    MD0080PA00X+155561Y+121545X0160Y         S0      
327PEX3_DBG_MODE0   R1420 -2          A01X+149717Y+121990X0198Y0197R045 S1      
327PEX3_DBG_MODE0   R1400 -1          A01X+149434Y+122272X0198Y0197R225 S1      
317PEX3_DBG_MODE0   VIA   -    MD0100PA00X+150068Y+122730X0200Y         S0      
327PEX3_DBG_MODE0   VIA   -    M      A18X+150723Y+121497X0260Y         S2      
327PEX3_DBG_MODE0   PEX3  -L12        A01X+155748Y+121732X0180Y         S1      
327SMB_NIC1_R_SCL   R1479 -2          A18X+088329Y+091191X0198Y0197R270 S2      
317SMB_NIC1_R_SCL   VIA   -    MD0100PA00X+088463Y+091804X0200Y         S0      
327SMB_NIC1_R_SCL   R60   -2          A18X+026879Y+044261X0198Y0197     S2      
317SMB_NIC1_R_SCL   VIA   -    MD0100PA00X+026330Y+044423X0200Y         S0      
317SMB_NIC1_R_SCL   VIA   -    M      A01X+078958Y+040501X0200Y         S2      
017SMB_NIC1_R_SCL   VIA   -    M      A18X+078958Y+040501X0260Y         S2      
017SMB_NIC1_R_SCL         -    MD0100PA00X+078958Y+040501                       
327SMB_NIC1_R_SCL   J21   -A7         A01X+027030Y+044423X0140Y0480R090 S1      
317m1791            VIA   -    MD0100PA00X+088452Y+085474X0180Y    R270 S0      
327m1791            U5    -G14        A01X+088609Y+085632X0160Y    R180 S1      
317m1791            VIA   -    MD0100PA00X+090892Y+090563X0200Y         S0      
317m1791            VIA   -    MD0100PA00X+132983Y+098813X0200Y         S0      
327m1791            R3540 -1          A01X+136195Y+094918X0198Y0197R270 S1      
317m1791            VIA   -    M      A01X+132126Y+094382X0200Y         S2      
017m1791            VIA   -    M      A18X+132126Y+094382X0260Y         S2      
017m1791                  -    MD0100PA00X+132126Y+094382                       
327SSD3_PWRDIS_R    R3537 -1          A18X+134650Y+092108X0198Y0197R090 S2      
317SSD3_PWRDIS_R    VIA   -    MD0100PA00X+058306Y+090329X0200Y         S0      
317SSD3_PWRDIS_R    VIA   -    MD0100PA00X+134250Y+093050X0200Y         S0      
327SSD3_PWRDIS_R    R6201 -2          A01X+040419Y+011449X0198Y0197R180 S1      
317SSD3_PWRDIS_R    VIA   -    MD0100PA00X+040210Y+011208X0200Y         S0      
317SSD3_PWRDIS_R    VIA   -    M      A01X+036296Y+009996X0200Y         S2      
017SSD3_PWRDIS_R    VIA   -    M      A18X+036296Y+009996X0260Y         S2      
017SSD3_PWRDIS_R          -    MD0100PA00X+036296Y+009996                       
327SSD3_PWRDIS_R    J33   -B12        A01X+036718Y+009996X0150Y0500R090 S1      
327SSD8_CLK_EN_N    VIA   -    M      A18X+131728Y+082678X0260Y         S2      
327SSD8_CLK_EN_N    R4118 -1          A18X+131500Y+081958X0198Y0197R090 S2      
327SSD8_CLK_EN_N    U6    -Y4         A01X+132478Y+083774X0160Y         S1      
317SSD8_CLK_EN_N    VIA   -    MD0100PA00X+132320Y+083617X0180Y         S0      
327m1792            U114  -K1         A01X+051170Y+069252X0090Y         S1      
327m1792            R1088 -2          A01X+049851Y+069301X0198Y0197     S1      
317m1793            VIA   -    MD0100PA00X+151110Y+098881X0200Y         S0      
327m1793            R1437 -2          A01X+151110Y+099196X0198Y0197R270 S1      
327m1793            R1417 -1          A01X+151110Y+098611X0198Y0197R270 S1      
327m1793            PEX3  -AW32       A01X+163228Y+111260X0180Y         S1      
327m1793            VIA   -    M      A18X+162142Y+105579X0260Y         S2      
317m1793            VIA   -    MD0080PA00X+163415Y+111447X0160Y         S0      
327SMB_NIC4_R_SCL   R1513 -2          A18X+083500Y+081308X0198Y0197R270 S2      
317SMB_NIC4_R_SCL   VIA   -    M      A01X+081850Y+081014X0200Y         S2      
017SMB_NIC4_R_SCL   VIA   -    M      A18X+081850Y+081014X0260Y         S2      
017SMB_NIC4_R_SCL         -    MD0100PA00X+081850Y+081014                       
327SMB_NIC4_R_SCL   R1512 -1   M      A01X+083008Y+081250X0198Y0197R180 S1      
327SMB_NIC4_R_SCL   U119  -3          A01X+083670Y+081472X0140Y0590R270 S1      
317SMB_NIC4_R_SCL   VIA   -    MD0100PA00X+084838Y+086346X0200Y         S0      
327SMB_NIC4_R_SCL   R1498 -2          A01X+085368Y+086346X0198Y0197R180 S1      
327m1794            C4064 -2          A01X+058374Y+154471X0198Y0197R270 S1      
317m1794            J12   -A7   D0122PA00X+050831Y+162240X0282Y    R180 S3      
317m1794            VIA   -    M      A01X+058381Y+154161X0200Y         S2      
017m1794            VIA   -    M      A18X+058381Y+154161X0260Y         S2      
017m1794                  -    MD0100PA00X+058381Y+154161                       
327m1794            R1843 -2          A01X+058381Y+153858X0198Y0197R090 S1      
317m1795            VIA   -    M      A01X+146566Y+100665X0200Y         S2      
017m1795            VIA   -    M      A18X+146566Y+100665X0260Y         S2      
017m1795                  -    MD0100PA00X+146566Y+100665                       
327m1795            R1463 -2          A01X+146887Y+101082X0198Y0197R270 S1      
327m1795            D4    -A          A01X+146566Y+100335X0240Y0280R180 S1      
317I3C_MB_BMC_SCL   J14   -F9   D0122PA00X+154760Y+159681X0282Y    R180 S3      
327I3C_MB_BMC_SCL   R6280 -2          A01X+159800Y+151208X0198Y0197R090 S1      
317I3C_MB_BMC_SCL   VIA   -    M      A01X+160400Y+151900X0200Y         S2      
017I3C_MB_BMC_SCL   VIA   -    M      A18X+160400Y+151900X0260Y         S2      
017I3C_MB_BMC_SCL         -    MD0100PA00X+160400Y+151900                       
317PRSNT_SSD3_R_N   VIA   -    M      A01X+033620Y+014376X0200Y         S2      
017PRSNT_SSD3_R_N   VIA   -    M      A18X+033620Y+014376X0260Y         S2      
017PRSNT_SSD3_R_N         -    MD0100PA00X+033620Y+014376                       
317PRSNT_SSD3_R_N   VIA   -    MD0100PA00X+034229Y+010656X0200Y         S0      
317PRSNT_SSD3_R_N   VIA   -    MD0100PA00X+096038Y+039281X0200Y         S0      
317PRSNT_SSD3_R_N   VIA   -    MD0100PA00X+092231Y+088624X0180Y    R270 S0      
327PRSNT_SSD3_R_N   U5    -T3         A01X+092074Y+088466X0160Y    R180 S1      
317PRSNT_SSD3_R_N   VIA   -    MD0100PA00X+047080Y+039459X0200Y         S0      
327PRSNT_SSD3_R_N   R4059 -1   M      A01X+033906Y+010656X0198Y0197R270 S1      
327PRSNT_SSD3_R_N   R4058 -2          A01X+033508Y+010250X0198Y0197     S1      
327PRSNT_SSD3_R_N   C2766 -1   M      A01X+033508Y+010650X0198Y0197R180 S1      
327PRSNT_SSD3_R_N   R5550 -2          A01X+033298Y+014376X0198Y0197R270 S1      
317PRSNT_SSD3_R_N   VIA   -    MD0100PA00X+135470Y+088341X0180Y         S0      
327PRSNT_SSD3_R_N   U6    -F13        A01X+135312Y+088184X0160Y         S1      
327m1796            U390  -1          A01X+102282Y+014265X0240Y0240     S1      
327m1796            R6083 -2          A01X+100247Y+014125X0198Y0197     S1      
317m1796            VIA   -    M      A01X+100540Y+014125X0200Y         S2      
017m1796            VIA   -    M      A18X+100540Y+014125X0260Y         S2      
017m1796                  -    MD0100PA00X+100540Y+014125                       
317m1796            VIA   -    MD0100PA00X+105044Y+024430X0200Y    R090 S0      
317m1796            VIA   -    MD0100PA00X+108230Y+034077X0200Y         S0      
327m1796            R4502 -2          A01X+105044Y+024168X0198Y0197     S1      
327m1796            U6    -AB4        A01X+132478Y+083144X0160Y         S1      
317m1796            VIA   -    MD0100PA00X+132320Y+082987X0180Y         S0      
317m1796            VIA   -    MD0100PA00X+121718Y+036992X0200Y         S0      
327PEX0_DBG_SEL0    PEX0  -L18        A01X+020866Y+121732X0180Y         S1      
317PEX0_DBG_SEL0    VIA   -    MD0080PA00X+020866Y+121732X0160Y         S0      
317PEX0_DBG_SEL0    VIA   -    M      A01X+011205Y+121437X0200Y    R315 S2      
017PEX0_DBG_SEL0    VIA   -    M      A18X+011205Y+121437X0260Y    R315 S2      
017PEX0_DBG_SEL0          -    MD0100PA00X+011205Y+121437                       
327PEX0_DBG_SEL0    R1167 -2          A01X+011176Y+121011X0198Y0197R045 S1      
327PEX0_DBG_SEL0    R1086 -1   M      A01X+010894Y+121294X0198Y0197R225 S1      
317PEX3_DBG_SEL1    VIA   -    MD0080PA00X+158179Y+121545X0160Y         S0      
317PEX3_DBG_SEL1    VIA   -    M      A01X+149769Y+123041X0200Y         S2      
017PEX3_DBG_SEL1    VIA   -    M      A18X+149769Y+123041X0260Y         S2      
017PEX3_DBG_SEL1          -    MD0100PA00X+149769Y+123041                       
327PEX3_DBG_SEL1    PEX3  -M19        A01X+158366Y+121358X0180Y         S1      
327PEX3_DBG_SEL1    R1419 -2   M      A01X+148869Y+122838X0198Y0197R045 S1      
327PEX3_DBG_SEL1    R1399 -1          A01X+148086Y+122660X0198Y0197R270 S1      
327SMB_NIC2_R_SDA   R112  -2          A01X+067551Y+055880X0198Y0197R180 S1      
327SMB_NIC2_R_SDA   R1484 -2          A01X+084110Y+089256X0198Y0197R180 S1      
317SMB_NIC2_R_SDA   VIA   -    MD0100PA00X+083607Y+089496X0200Y         S0      
317SMB_NIC2_R_SDA   VIA   -    M      A01X+072869Y+088665X0200Y         S2      
017SMB_NIC2_R_SDA   VIA   -    M      A18X+072869Y+088665X0260Y         S2      
017SMB_NIC2_R_SDA         -    MD0100PA00X+072869Y+088665                       
327SMB_NIC2_R_SDA   J22   -A8         A01X+065647Y+055892X0140Y0480R270 S1      
317SMB_NIC2_R_SDA   VIA   -    MD0100PA00X+066176Y+055892X0200Y    R180 S0      
317m1797            VIA   -    M      A01X+023318Y+148644X0200Y         S2      
017m1797            VIA   -    M      A18X+023318Y+148644X0260Y         S2      
017m1797                  -    MD0100PA00X+023318Y+148644                       
317m1797            J11   -Z6   D0122PA00X+032642Y+145272X0282Y    R180 S3      
327m1797            R1824 -1          A01X+023062Y+148644X0198Y0197R180 S1      
317m1798            VIA   -    M      A01X+145889Y+100752X0200Y         S2      
017m1798            VIA   -    M      A18X+145889Y+100752X0260Y         S2      
017m1798                  -    MD0100PA00X+145889Y+100752                       
327m1798            Q20   -3          A01X+145594Y+100926X0240Y0240R270 S1      
327m1798            D4    -C          A01X+146192Y+100335X0240Y0280R180 S1      
327SSD0_PWR_EN_R    R3581 -2          A01X+134595Y+094918X0198Y0197R090 S1      
317SSD0_PWR_EN_R    VIA   -    MD0100PA00X+131987Y+098986X0200Y         S0      
317SSD0_PWR_EN_R    VIA   -    MD0100PA00X+012243Y+085754X0200Y         S0      
317SSD0_PWR_EN_R    VIA   -    MD0100PA00X+008077Y+025630X0200Y         S0      
327SSD0_PWR_EN_R    R5835 -1          A01X+008077Y+025954X0198Y0197R090 S1      
317SSD0_PWR_EN_R    VIA   -    M      A01X+010384Y+022863X0200Y         S2      
017SSD0_PWR_EN_R    VIA   -    M      A18X+010384Y+022863X0260Y         S2      
017SSD0_PWR_EN_R          -    MD0100PA00X+010384Y+022863                       
327SSD0_PWR_EN_R    R6841 -1   M      A01X+010184Y+022572X0198Y0197     S1      
327SSD0_PWR_EN_R    C2861 -1   M      A01X+010184Y+022186X0198Y0197     S1      
327SSD0_PWR_EN_R    PU30  -11         A01X+009507Y+021710X0110Y0240R270 S1      
317m1799            VIA   -    MD0100PA00X+036301Y+009524X0200Y         S0      
327m1799            J33   -B10        A01X+036718Y+009524X0150Y0500R090 S1      
317m1799            VIA   -    MD0100PA00X+135050Y+092550X0200Y         S0      
317m1799            VIA   -    M      A01X+058614Y+090894X0200Y         S2      
017m1799            VIA   -    M      A18X+058614Y+090894X0260Y         S2      
017m1799                  -    MD0100PA00X+058614Y+090894                       
327m1799            R3539 -1          A01X+135050Y+092308X0198Y0197R270 S1      
327SSD10_CLK_EN_N   VIA   -    M      A01X+133300Y+081750X0300Y         S1      
327SSD10_CLK_EN_N   U6    -AA7        A01X+133423Y+083460X0160Y         S1      
327SSD10_CLK_EN_N   R4126 -1          A01X+133300Y+080958X0198Y0197R270 S1      
317m1800            VIA   -    MD0100PA00X+174927Y+091841X0200Y         S0      
327m1800            R6605 -1          A01X+174927Y+091545X0198Y0197     S1      
317m1800            VIA   -    MD0100PA00X+164776Y+091927X0200Y         S0      
327m1800            R6618 -1          A01X+164417Y+091724X0198Y0197R180 S1      
317m1800            VIA   -    M      A01X+148041Y+097506X0200Y         S2      
017m1800            VIA   -    M      A18X+148041Y+097506X0260Y         S2      
017m1800                  -    MD0100PA00X+148041Y+097506                       
327m1800            R970  -1          A18X+148657Y+097718X0198Y0197R180 S2      
327m1800            U103  -4          A18X+147258Y+097674X0140Y0440R270 S2      
327m1801            R1212 -2          A01X+092606Y+058558X0198Y0197R180 S1      
327m1801            U117  -A24        A01X+091524Y+058421X0070Y0220R090 S1      
327SMB_NIC2_SCL     VIA   -    M      A01X+086812Y+088530X0300Y         S1      
327SMB_NIC2_SCL     R1481 -1          A01X+085683Y+089296X0198Y0197R180 S1      
327SMB_NIC2_SCL     U5    -T16        A01X+087979Y+088466X0160Y    R180 S1      
317m1802            VIA   -    M      A01X+146302Y+101831X0200Y         S2      
017m1802            VIA   -    M      A18X+146302Y+101831X0260Y         S2      
017m1802                  -    MD0100PA00X+146302Y+101831                       
327m1802            Q20   -6   M      A01X+146302Y+101517X0240Y0240R270 S1      
327m1802            Q20   -5          A01X+146302Y+101221X0160Y0240R270 S1      
327m1802            R5802 -1          A01X+146232Y+102523X0198Y0197R090 S1      
327m1802            R1464 -1   M      A01X+146270Y+102118X0198Y0197     S1      
317m1803            J14   -C9   D0122PA00X+154760Y+161217X0282Y    R180 S3      
317m1803            VIA   -    MD0100PA00X+142124Y+130171X0200Y         S0      
317m1803            VIA   -    MD0100PA00X+094389Y+130661X0200Y         S0      
327m1803            R2742 -1          A01X+083264Y+089616X0198Y0197R270 S1      
317m1803            VIA   -    M      A01X+083006Y+089850X0200Y    R270 S2      
017m1803            VIA   -    M      A18X+083006Y+089850X0260Y    R270 S2      
017m1803                  -    MD0100PA00X+083006Y+089850                       
317PRSNT_SSD1_R_N   VIA   -    M      A01X+013148Y+014376X0200Y         S2      
017PRSNT_SSD1_R_N   VIA   -    M      A18X+013148Y+014376X0260Y         S2      
017PRSNT_SSD1_R_N         -    MD0100PA00X+013148Y+014376                       
327PRSNT_SSD1_R_N   C2763 -1   M      A01X+013036Y+010650X0198Y0197R180 S1      
327PRSNT_SSD1_R_N   R4054 -2          A01X+013035Y+010250X0198Y0197     S1      
327PRSNT_SSD1_R_N   R4052 -1   M      A01X+013433Y+010656X0198Y0197R270 S1      
317PRSNT_SSD1_R_N   VIA   -    MD0100PA00X+013757Y+010656X0200Y         S0      
317PRSNT_SSD1_R_N   VIA   -    MD0100PA00X+023084Y+031389X0200Y         S0      
317PRSNT_SSD1_R_N   VIA   -    MD0100PA00X+134000Y+090600X0200Y         S0      
317PRSNT_SSD1_R_N   VIA   -    MD0100PA00X+025406Y+081985X0200Y         S0      
317PRSNT_SSD1_R_N   VIA   -    MD0100PA00X+092231Y+088309X0180Y    R270 S0      
327PRSNT_SSD1_R_N   U5    -R3         A01X+092074Y+088151X0160Y    R180 S1      
317PRSNT_SSD1_R_N   VIA   -    MD0100PA00X+092145Y+090380X0200Y         S0      
327PRSNT_SSD1_R_N   U6    -A10        A01X+134368Y+089759X0160Y         S1      
317PRSNT_SSD1_R_N   VIA   -    MD0100PA00X+017022Y+031167X0200Y         S0      
327PRSNT_SSD1_R_N   R5544 -2          A01X+012825Y+014376X0198Y0197R270 S1      
317PRSNT_SSD5_R_N   VIA   -    MD0100PA00X+058857Y+014376X0200Y         S0      
317PRSNT_SSD5_R_N   VIA   -    MD0100PA00X+059466Y+010656X0200Y         S0      
317PRSNT_SSD5_R_N   VIA   -    MD0100PA00X+072318Y+072822X0200Y         S0      
317PRSNT_SSD5_R_N   VIA   -    M      A01X+073645Y+089055X0200Y         S2      
017PRSNT_SSD5_R_N   VIA   -    M      A18X+073645Y+089055X0260Y         S2      
017PRSNT_SSD5_R_N         -    MD0100PA00X+073645Y+089055                       
317PRSNT_SSD5_R_N   VIA   -    MD0100PA00X+081714Y+089033X0200Y         S0      
327PRSNT_SSD5_R_N   U5    -P6         A01X+091129Y+087836X0160Y    R180 S1      
317PRSNT_SSD5_R_N   VIA   -    MD0100PA00X+091286Y+087994X0180Y    R270 S0      
317PRSNT_SSD5_R_N   VIA   -    MD0100PA00X+057656Y+072822X0200Y         S0      
327PRSNT_SSD5_R_N   R4062 -2          A01X+058744Y+010250X0198Y0197     S1      
327PRSNT_SSD5_R_N   C2768 -1   M      A01X+058744Y+010650X0198Y0197R180 S1      
327PRSNT_SSD5_R_N   R4063 -1   M      A01X+059142Y+010656X0198Y0197R270 S1      
327PRSNT_SSD5_R_N   R5556 -2          A01X+058534Y+014376X0198Y0197R270 S1      
317PRSNT_SSD5_R_N   VIA   -    MD0100PA00X+136100Y+088971X0180Y         S0      
327PRSNT_SSD5_R_N   U6    -D15        A01X+135942Y+088814X0160Y         S1      
317SSD14_PWRDIS     VIA   -    M      A01X+133700Y+079600X0200Y    R180 S2      
017SSD14_PWRDIS     VIA   -    M      A18X+133700Y+079600X0260Y    R180 S2      
017SSD14_PWRDIS           -    MD0100PA00X+133700Y+079600                       
327SSD14_PWRDIS     R4140 -1          A01X+133700Y+079358X0198Y0197R270 S1      
317SSD14_PWRDIS     VIA   -    MD0100PA00X+134525Y+084247X0180Y         S0      
327SSD14_PWRDIS     U6    -V11        A01X+134683Y+084404X0160Y         S1      
317m1804            VIA   -    MD0100PA00X+174688Y+088465X0200Y         S0      
327m1804            R6606 -1          A01X+175003Y+088465X0198Y0197     S1      
317m1804            VIA   -    M      A01X+147920Y+097000X0200Y         S2      
017m1804            VIA   -    M      A18X+147920Y+097000X0260Y         S2      
017m1804                  -    MD0100PA00X+147920Y+097000                       
327m1804            R966  -1          A18X+148692Y+096800X0198Y0197R180 S2      
327m1804            U103  -6          A18X+147258Y+097162X0140Y0440R270 S2      
317m1804            VIA   -    MD0100PA00X+164747Y+095212X0200Y         S0      
327m1804            R6620 -1          A01X+164393Y+095212X0198Y0197R180 S1      
327SPI2_DI_BUF      U305  -6          A01X+087491Y+076133X0140Y0520R180 S1      
317SPI2_DI_BUF      VIA   -    M      A01X+087373Y+075269X0200Y         S2      
017SPI2_DI_BUF      VIA   -    M      A18X+087373Y+075269X0260Y         S2      
017SPI2_DI_BUF            -    MD0100PA00X+087373Y+075269                       
327SPI2_DI_BUF      R1028 -1          A18X+088005Y+075811X0198Y0197R270 S2      
327m1805            VIA   -    M      A18X+051458Y+068132X0260Y         S2      
327m1805            R1467 -1          A18X+051378Y+067653X0198Y0197R090 S2      
317m1805            VIA   -    MD0100PA00X+051830Y+069238X0180Y         S0      
327m1805            U114  -L4         A01X+051760Y+069055X0090Y         S1      
327m1806            R1211 -2          A01X+092606Y+058958X0198Y0197R180 S1      
327m1806            U117  -A25        A01X+091524Y+058618X0070Y0220R090 S1      
327SMB_FIO_SCL      VIA   -    M      A18X+086287Y+089147X0260Y         S2      
327SMB_FIO_SCL      U5    -M13        A01X+088924Y+087206X0160Y    R180 S1      
317SMB_FIO_SCL      VIA   -    MD0100PA00X+088767Y+087364X0180Y    R270 S0      
327SMB_FIO_SCL      R1490 -1   M      A18X+085687Y+089274X0198Y0197     S2      
327SMB_FIO_SCL      R4871 -2          A18X+084294Y+089150X0198Y0197R180 S2      
317m1807            VIA   -    M      A01X+001595Y+014127X0200Y         S2      
017m1807            VIA   -    M      A18X+001595Y+014127X0260Y         S2      
017m1807                  -    MD0100PA00X+001595Y+014127                       
327m1807            R1641 -2          A01X+001595Y+013887X0198Y0197R090 S1      
317m1807            VIA   -    MD0100PA00X+001514Y+011558X0200Y         S0      
327m1807            U126  -3   M      A01X+001387Y+011171X0170Y0460R180 S1      
327m1807            R1633 -2          A01X+001830Y+009659X0198Y0197R270 S1      
327m1807            R1639 -2   M      A01X+001429Y+009979X0198Y0197R090 S1      
317m1808            J12   -Z6   D0122PA00X+049965Y+145272X0282Y    R180 S3      
317m1808            VIA   -    M      A01X+058203Y+150280X0200Y         S2      
017m1808            VIA   -    M      A18X+058203Y+150280X0260Y         S2      
017m1808                  -    MD0100PA00X+058203Y+150280                       
327m1808            R1842 -1          A01X+058536Y+150169X0198Y0197     S1      
317m1809            VIA   -    M      A01X+047961Y+095219X0200Y         S2      
017m1809            VIA   -    M      A18X+047961Y+095219X0260Y         S2      
017m1809                  -    MD0100PA00X+047961Y+095219                       
317m1809            VIA   -    MD0100PA00X+133240Y+098822X0200Y         S0      
327m1809            R3525 -2          A01X+136595Y+094918X0198Y0197R090 S1      
317m1809            VIA   -    MD0100PA00X+026064Y+009524X0200Y         S0      
327m1809            J32   -B10        A01X+026482Y+009524X0150Y0500R090 S1      
327SSD10_PWRDIS     VIA   -    M      A18X+132197Y+082504X0260Y         S2      
327SSD10_PWRDIS     R4124 -1          A18X+131950Y+081958X0198Y0197R090 S2      
327SSD10_PWRDIS     U6    -W6         A01X+133108Y+084089X0160Y         S1      
317SSD10_PWRDIS     VIA   -    MD0100PA00X+132950Y+083932X0180Y         S0      
317m1810            VIA   -    MD0080PA00X+166033Y+114065X0160Y    R090 S0      
327m1810            VIA   -    M      A18X+166220Y+114252X0260Y         S2      
327m1810            R969  -1          A18X+166938Y+114222X0198Y0197R090 S2      
327m1810            PEX3  -AL39       A01X+165846Y+114252X0180Y         S1      
327SPI2_DO_BUF      U305  -5          A01X+087235Y+076133X0140Y0520R180 S1      
317SPI2_DO_BUF      VIA   -    M      A01X+087002Y+075731X0200Y         S2      
017SPI2_DO_BUF      VIA   -    M      A18X+087002Y+075731X0260Y         S2      
017SPI2_DO_BUF            -    MD0100PA00X+087002Y+075731                       
327SPI2_DO_BUF      R1027 -1          A18X+087485Y+075811X0198Y0197R270 S2      
327m1811            R1210 -2          A01X+092608Y+059433X0198Y0197R180 S1      
327m1811            U117  -A27        A01X+091524Y+059012X0070Y0220R090 S1      
317SMB_NIC4_SDA     VIA   -    MD0100PA00X+085946Y+086612X0200Y         S0      
327SMB_NIC4_SDA     VIA   -    M      A01X+086812Y+086530X0300Y         S1      
327SMB_NIC4_SDA     R1499 -1          A01X+085683Y+086746X0198Y0197R180 S1      
327SMB_NIC4_SDA     U5    -J15        A01X+088294Y+086262X0160Y    R180 S1      
317SMB_NIC4_SDA     VIA   -    MD0100PA00X+084582Y+086741X0200Y         S0      
327SMB_NIC4_SDA     R4874 -2          A01X+084331Y+086741X0198Y0197     S1      
317m1812            VIA   -    MD0100PA00X+001200Y+014142X0200Y         S0      
327m1812            R1643 -2          A01X+001200Y+013894X0198Y0197R090 S1      
317m1812            VIA   -    M      A01X+001013Y+011547X0200Y         S2      
017m1812            VIA   -    M      A18X+001013Y+011547X0260Y         S2      
017m1812                  -    MD0100PA00X+001013Y+011547                       
327m1812            U126  -2   M      A01X+001131Y+011171X0170Y0460R180 S1      
327m1812            R1632 -2          A01X+000630Y+009659X0198Y0197R270 S1      
327m1812            R1637 -2   M      A01X+001029Y+009979X0198Y0197R090 S1      
317m1813            VIA   -    MD0100PA00X+041100Y+145100X0200Y         S0      
317m1813            VIA   -    M      A01X+024550Y+151703X0200Y         S2      
017m1813            VIA   -    M      A18X+024550Y+151703X0260Y         S2      
017m1813                  -    MD0100PA00X+024550Y+151703                       
317m1813            J11   -A5   D0122PA00X+031776Y+162240X0282Y    R180 S3      
327m1813            C4034 -2   M      A01X+024861Y+151796X0198Y0197R180 S1      
327m1813            R6300 -1          A01X+024649Y+151417X0198Y0197     S1      
317m1813            VIA   -    MD0100PA00X+078582Y+142599X0200Y         S0      
317m1813            VIA   -    MD0100PA00X+090574Y+130926X0200Y         S0      
317m1813            VIA   -    MD0100PA00X+094636Y+095118X0200Y         S0      
317m1813            VIA   -    MD0100PA00X+130050Y+096000X0200Y         S0      
327m1813            R1785 -2          A01X+130050Y+096392X0198Y0197R270 S1      
327m1813            U143  -3          A01X+130135Y+095610X0140Y0440R180 S1      
317PRSNT_SSD4_R_N   VIA   -    MD0100PA00X+049229Y+010656X0200Y         S0      
317PRSNT_SSD4_R_N   VIA   -    MD0100PA00X+056200Y+073283X0200Y         S0      
317PRSNT_SSD4_R_N   VIA   -    MD0100PA00X+092835Y+068634X0200Y         S0      
327PRSNT_SSD4_R_N   R4061 -1   M      A01X+048906Y+010656X0198Y0197R270 S1      
327PRSNT_SSD4_R_N   R4060 -2          A01X+048508Y+010250X0198Y0197     S1      
327PRSNT_SSD4_R_N   C2767 -1   M      A01X+048508Y+010650X0198Y0197R180 S1      
317PRSNT_SSD4_R_N   VIA   -    M      A01X+048621Y+014376X0200Y         S2      
017PRSNT_SSD4_R_N   VIA   -    M      A18X+048621Y+014376X0260Y         S2      
017PRSNT_SSD4_R_N         -    MD0100PA00X+048621Y+014376                       
327PRSNT_SSD4_R_N   R5553 -2          A01X+048298Y+014376X0198Y0197R270 S1      
317PRSNT_SSD4_R_N   VIA   -    MD0100PA00X+091601Y+087679X0180Y    R270 S0      
327PRSNT_SSD4_R_N   U5    -N5         A01X+091444Y+087521X0160Y    R180 S1      
317PRSNT_SSD4_R_N   VIA   -    MD0100PA00X+135785Y+089286X0180Y         S0      
327PRSNT_SSD4_R_N   U6    -C14        A01X+135628Y+089129X0160Y         S1      
327SSD12_PWR_EN     VIA   -    M      A18X+133188Y+082538X0260Y         S2      
327SSD12_PWR_EN     R4131 -1          A18X+132850Y+081958X0198Y0197R090 S2      
327SSD12_PWR_EN     U6    -W9         A01X+134053Y+084089X0160Y         S1      
317SSD12_PWR_EN     VIA   -    MD0100PA00X+133895Y+083932X0180Y         S0      
317m1814            VIA   -    MD0080PA00X+120325Y+114065X0160Y    R090 S0      
327m1814            VIA   -    M      A18X+120512Y+114252X0260Y         S2      
327m1814            R965  -1          A18X+121230Y+114222X0198Y0197R090 S2      
327m1814            PEX2  -AL39       A01X+120138Y+114252X0180Y         S1      
327SPI2_CLK_BUF     U305  -7          A01X+087747Y+076133X0140Y0520R180 S1      
317SPI2_CLK_BUF     VIA   -    M      A01X+087988Y+075361X0200Y         S2      
017SPI2_CLK_BUF     VIA   -    M      A18X+087988Y+075361X0260Y         S2      
017SPI2_CLK_BUF           -    MD0100PA00X+087988Y+075361                       
327SPI2_CLK_BUF     R1026 -1          A18X+088661Y+075811X0198Y0197R270 S2      
327m1815            R1092 -2          A01X+051746Y+067323X0198Y0197R090 S1      
327m1815            U114  -M5         A01X+051957Y+068858X0090Y         S1      
327m1816            R1209 -2          A01X+092608Y+059833X0198Y0197R180 S1      
327m1816            U117  -A28        A01X+091524Y+059209X0070Y0220R090 S1      
317m1817            VIA   -    M      A01X+001986Y+013300X0200Y    R180 S2      
017m1817            VIA   -    M      A18X+001986Y+013300X0260Y    R180 S2      
017m1817                  -    MD0100PA00X+001986Y+013300                       
327m1817            U126  -5          A01X+001673Y+012884X0240Y0460R180 S1      
327m1817            R1631 -1          A01X+001986Y+013581X0198Y0197R090 S1      
317m1818            J12   -A5   D0122PA00X+049098Y+162240X0282Y    R180 S3      
327m1818            R1841 -1          A01X+058781Y+153858X0198Y0197R270 S1      
317m1818            VIA   -    M      A01X+058781Y+154585X0200Y         S2      
017m1818            VIA   -    M      A18X+058781Y+154585X0260Y         S2      
017m1818                  -    MD0100PA00X+058781Y+154585                       
327SSD5_PWRDIS_R    R6203 -2          A01X+065655Y+011449X0198Y0197R180 S1      
317SSD5_PWRDIS_R    VIA   -    MD0100PA00X+065447Y+011208X0200Y         S0      
317SSD5_PWRDIS_R    VIA   -    MD0100PA00X+135050Y+093050X0200Y         S0      
317SSD5_PWRDIS_R    VIA   -    MD0100PA00X+072279Y+092710X0200Y         S0      
327SSD5_PWRDIS_R    R3566 -1          A18X+135450Y+092108X0198Y0197R090 S2      
317SSD5_PWRDIS_R    VIA   -    M      A01X+061532Y+009996X0200Y         S2      
017SSD5_PWRDIS_R    VIA   -    M      A18X+061532Y+009996X0260Y         S2      
017SSD5_PWRDIS_R          -    MD0100PA00X+061532Y+009996                       
327SSD5_PWRDIS_R    J35   -B12        A01X+061955Y+009996X0150Y0500R090 S1      
317SSD11_PWR_EN     VIA   -    M      A01X+134100Y+079900X0200Y    R180 S2      
017SSD11_PWR_EN     VIA   -    M      A18X+134100Y+079900X0260Y    R180 S2      
017SSD11_PWR_EN           -    MD0100PA00X+134100Y+079900                       
327SSD11_PWR_EN     R4127 -1          A01X+134100Y+079358X0198Y0197R270 S1      
317SSD11_PWR_EN     VIA   -    MD0100PA00X+133895Y+084877X0180Y         S0      
327SSD11_PWR_EN     U6    -T9         A01X+134053Y+085034X0160Y         S1      
327m1819            U117  -A31        A01X+090885Y+059455X0070Y0220     S1      
327m1819            R1208 -2          A01X+091321Y+061244X0198Y0197R270 S1      
327SMB_NIC2_R_SCL   R111  -2          A01X+067551Y+056280X0198Y0197R180 S1      
317SMB_NIC2_R_SCL   VIA   -    MD0100PA00X+084879Y+089647X0200Y         S0      
327SMB_NIC2_R_SCL   R1481 -2          A01X+085368Y+089296X0198Y0197R180 S1      
317SMB_NIC2_R_SCL   VIA   -    M      A01X+072850Y+089169X0200Y         S2      
017SMB_NIC2_R_SCL   VIA   -    M      A18X+072850Y+089169X0260Y         S2      
017SMB_NIC2_R_SCL         -    MD0100PA00X+072850Y+089169                       
327SMB_NIC2_R_SCL   J22   -A7         A01X+065647Y+056128X0140Y0480R270 S1      
317SMB_NIC2_R_SCL   VIA   -    MD0100PA00X+066176Y+056142X0200Y    R180 S0      
327m1820            C4033 -2          A01X+023650Y+147872X0198Y0197R090 S1      
317m1820            VIA   -    M      A01X+023498Y+148168X0200Y         S2      
017m1820            VIA   -    M      A18X+023498Y+148168X0260Y         S2      
017m1820                  -    MD0100PA00X+023498Y+148168                       
317m1820            J11   -Z4   D0122PA00X+030909Y+145272X0282Y    R180 S3      
327m1820            R1870 -2          A01X+023062Y+148244X0198Y0197     S1      
327SSD4_PWRDIS_R    R6202 -2          A01X+055419Y+011449X0198Y0197R180 S1      
317SSD4_PWRDIS_R    VIA   -    MD0100PA00X+055210Y+011208X0200Y         S0      
317SSD4_PWRDIS_R    VIA   -    MD0100PA00X+135850Y+092550X0200Y         S0      
317SSD4_PWRDIS_R    VIA   -    MD0100PA00X+060108Y+091354X0200Y         S0      
327SSD4_PWRDIS_R    R3552 -1          A01X+135850Y+092308X0198Y0197R270 S1      
317SSD4_PWRDIS_R    VIA   -    M      A01X+051296Y+009996X0200Y         S2      
017SSD4_PWRDIS_R    VIA   -    M      A18X+051296Y+009996X0260Y         S2      
017SSD4_PWRDIS_R          -    MD0100PA00X+051296Y+009996                       
327SSD4_PWRDIS_R    J34   -B12        A01X+051718Y+009996X0150Y0500R090 S1      
327SSD8_PWRDIS      VIA   -    M      A01X+131300Y+081420X0300Y         S1      
327SSD8_PWRDIS      U6    -AA3        A01X+132163Y+083460X0160Y         S1      
327SSD8_PWRDIS      R4116 -1          A01X+131300Y+080958X0198Y0197R270 S1      
327m1821            U117  -A32        A01X+090688Y+059455X0070Y0220     S1      
327m1821            R1207 -2          A01X+090921Y+061244X0198Y0197R270 S1      
327SMB_NIC6_R_SCL   U121  -3          A01X+083670Y+077872X0140Y0590R270 S1      
327SMB_NIC6_R_SCL   R1526 -1   M      A01X+083008Y+077650X0198Y0197R180 S1      
317SMB_NIC6_R_SCL   VIA   -    M      A01X+082450Y+077400X0200Y         S2      
017SMB_NIC6_R_SCL   VIA   -    M      A18X+082450Y+077400X0260Y         S2      
017SMB_NIC6_R_SCL         -    MD0100PA00X+082450Y+077400                       
327SMB_NIC6_R_SCL   R1527 -2          A18X+083500Y+077708X0198Y0197R270 S2      
327SMB_NIC6_R_SCL   R1502 -2          A01X+085368Y+085146X0198Y0197R180 S1      
317SMB_NIC6_R_SCL   VIA   -    MD0100PA00X+085118Y+085146X0200Y         S0      
317m1822            J12   -Z4   D0122PA00X+048232Y+145272X0282Y    R180 S3      
327m1822            R1840 -1          A01X+058536Y+149769X0198Y0197     S1      
317m1822            VIA   -    M      A01X+057886Y+149776X0200Y    R090 S2      
017m1822            VIA   -    M      A18X+057886Y+149776X0260Y    R090 S2      
017m1822                  -    MD0100PA00X+057886Y+149776                       
317SSD6_PWRDIS_R    VIA   -    MD0100PA00X+135850Y+093050X0200Y         S0      
317SSD6_PWRDIS_R    VIA   -    MD0100PA00X+073231Y+094268X0200Y         S0      
327SSD6_PWRDIS_R    R3578 -1          A18X+136250Y+092108X0198Y0197R090 S2      
327SSD6_PWRDIS_R    R6204 -2          A01X+075892Y+011449X0198Y0197R180 S1      
317SSD6_PWRDIS_R    VIA   -    MD0100PA00X+075683Y+011208X0200Y         S0      
317SSD6_PWRDIS_R    VIA   -    M      A01X+071768Y+009996X0200Y         S2      
017SSD6_PWRDIS_R    VIA   -    M      A18X+071768Y+009996X0260Y         S2      
017SSD6_PWRDIS_R          -    MD0100PA00X+071768Y+009996                       
327SSD6_PWRDIS_R    J36   -B12        A01X+072191Y+009996X0150Y0500R090 S1      
317m1823            VIA   -    MD0100PA00X+134210Y+083932X0180Y         S0      
327m1823            U6    -W10        A01X+134368Y+084089X0160Y         S1      
317m1823            VIA   -    MD0100PA00X+139318Y+042480X0200Y         S0      
327m1823            U394  -1          A01X+147990Y+014265X0240Y0240     S1      
327m1823            R6107 -2          A01X+145956Y+014125X0198Y0197     S1      
317m1823            VIA   -    M      A01X+146248Y+014125X0200Y         S2      
017m1823            VIA   -    M      A18X+146248Y+014125X0260Y         S2      
017m1823                  -    MD0100PA00X+146248Y+014125                       
317m1823            VIA   -    MD0100PA00X+146623Y+042367X0200Y         S0      
317m1823            VIA   -    MD0100PA00X+150752Y+024430X0200Y    R090 S0      
327m1823            R4503 -2          A01X+150752Y+024168X0198Y0197     S1      
327m1824            R6843 -1          A01X+093866Y+036464X0198Y0197R090 S1      
317m1824            VIA   -    M      A01X+093618Y+036482X0200Y    R090 S2      
017m1824            VIA   -    M      A18X+093618Y+036482X0260Y    R090 S2      
017m1824                  -    MD0100PA00X+093618Y+036482                       
327m1824            U112  -11         A01X+093084Y+036325X0100Y0290R090 S1      
327m1825            U117  -A33        A01X+090491Y+059455X0070Y0220     S1      
327m1825            R1206 -2          A01X+090438Y+061236X0198Y0197R270 S1      
317SMB_NIC7_SCL     VIA   -    MD0100PA00X+086211Y+085948X0200Y         S0      
327SMB_NIC7_SCL     VIA   -    M      A18X+087011Y+086219X0260Y         S2      
327SMB_NIC7_SCL     U5    -J13        A01X+088924Y+086262X0160Y    R180 S1      
317SMB_NIC7_SCL     VIA   -    MD0100PA00X+088767Y+086419X0180Y    R270 S0      
327SMB_NIC7_SCL     R1504 -1          A18X+085683Y+085946X0198Y0197     S2      
317SMB_NIC7_SCL     VIA   -    MD0100PA00X+083953Y+085941X0200Y         S0      
327SMB_NIC7_SCL     R4879 -2          A18X+083664Y+086109X0198Y0197R270 S2      
327SSD5_PWR_EN_R    R6836 -1   M      A01X+066129Y+022572X0198Y0197     S1      
327SSD5_PWR_EN_R    PU33  -11         A01X+065452Y+021710X0110Y0240R270 S1      
317SSD5_PWR_EN_R    VIA   -    MD0100PA00X+064022Y+025630X0200Y         S0      
317SSD5_PWR_EN_R    VIA   -    MD0100PA00X+135450Y+093050X0200Y         S0      
317SSD5_PWR_EN_R    VIA   -    MD0100PA00X+072027Y+093173X0200Y         S0      
327SSD5_PWR_EN_R    R3564 -1          A18X+135850Y+092108X0198Y0197R090 S2      
327SSD5_PWR_EN_R    R5971 -1          A01X+064022Y+025954X0198Y0197R090 S1      
327SSD5_PWR_EN_R    C2864 -1   M      A01X+066129Y+022186X0198Y0197     S1      
317SSD5_PWR_EN_R    VIA   -    M      A01X+066329Y+022863X0200Y         S2      
017SSD5_PWR_EN_R    VIA   -    M      A18X+066329Y+022863X0260Y         S2      
017SSD5_PWR_EN_R          -    MD0100PA00X+066329Y+022863                       
327SSD13_CLK_EN_N   VIA   -    M      A01X+134900Y+081750X0300Y         S1      
327SSD13_CLK_EN_N   U6    -AB10       A01X+134368Y+083144X0160Y         S1      
327SSD13_CLK_EN_N   R4138 -1          A01X+134900Y+080958X0198Y0197R270 S1      
317m1826            VIA   -    M      A01X+094424Y+036083X0200Y    R090 S2      
017m1826            VIA   -    M      A18X+094424Y+036083X0260Y    R090 S2      
017m1826                  -    MD0100PA00X+094424Y+036083                       
327m1826            U112  -10         A01X+093084Y+036129X0100Y0290R090 S1      
327m1826            C2622 -1   M      A01X+094168Y+036083X0198Y0197R270 S1      
327m1826            Y5    -1          A01X+094845Y+036061X0360Y0400R270 S1      
327m1827            U117  -A34        A01X+090294Y+059455X0070Y0220     S1      
327m1827            R1205 -2          A01X+090038Y+061236X0198Y0197R270 S1      
327SMB_NIC4_R_SDA   R1514 -2          A18X+083500Y+081692X0198Y0197R090 S2      
317SMB_NIC4_R_SDA   VIA   -    M      A01X+081784Y+081788X0200Y         S2      
017SMB_NIC4_R_SDA   VIA   -    M      A18X+081784Y+081788X0260Y         S2      
017SMB_NIC4_R_SDA         -    MD0100PA00X+081784Y+081788                       
327SMB_NIC4_R_SDA   U119  -2          A01X+083670Y+081728X0140Y0590R270 S1      
327SMB_NIC4_R_SDA   R1511 -1   M      A01X+083008Y+081650X0198Y0197R180 S1      
327SMB_NIC4_R_SDA   R1499 -2          A01X+085368Y+086746X0198Y0197R180 S1      
317SMB_NIC4_R_SDA   VIA   -    MD0100PA00X+084838Y+086746X0200Y         S0      
317m1828            J12   -A3   D0122PA00X+047366Y+162240X0282Y    R180 S3      
317m1828            VIA   -    M      A01X+059181Y+154241X0200Y         S2      
017m1828            VIA   -    M      A18X+059181Y+154241X0260Y         S2      
017m1828                  -    MD0100PA00X+059181Y+154241                       
327m1828            R1839 -1          A01X+059181Y+153858X0198Y0197R270 S1      
327SSD4_PWR_EN_R    C2862 -1   M      A01X+055893Y+022186X0198Y0197     S1      
327SSD4_PWR_EN_R    PU31  -11         A01X+055216Y+021710X0110Y0240R270 S1      
327SSD4_PWR_EN_R    R6837 -1   M      A01X+055893Y+022572X0198Y0197     S1      
317SSD4_PWR_EN_R    VIA   -    MD0100PA00X+053785Y+025630X0200Y         S0      
327SSD4_PWR_EN_R    R5970 -1          A01X+053785Y+025954X0198Y0197R090 S1      
317SSD4_PWR_EN_R    VIA   -    M      A01X+056093Y+022863X0200Y         S2      
017SSD4_PWR_EN_R    VIA   -    M      A18X+056093Y+022863X0260Y         S2      
017SSD4_PWR_EN_R          -    MD0100PA00X+056093Y+022863                       
317SSD4_PWR_EN_R    VIA   -    MD0100PA00X+060248Y+096576X0200Y         S0      
317SSD4_PWR_EN_R    VIA   -    MD0100PA00X+133751Y+098826X0200Y         S0      
327SSD4_PWR_EN_R    R3549 -1          A01X+137395Y+094918X0198Y0197R270 S1      
317SSD9_PWRDIS      VIA   -    M      A01X+132500Y+079900X0200Y    R180 S2      
017SSD9_PWRDIS      VIA   -    M      A18X+132500Y+079900X0260Y    R180 S2      
017SSD9_PWRDIS            -    MD0100PA00X+132500Y+079900                       
327SSD9_PWRDIS      R4120 -1          A01X+132500Y+079358X0198Y0197R270 S1      
317SSD9_PWRDIS      VIA   -    MD0100PA00X+133580Y+084877X0180Y         S0      
327SSD9_PWRDIS      U6    -T8         A01X+133738Y+085034X0160Y         S1      
317m1829            VIA   -    MD0080PA00X+151447Y+117805X0160Y         S0      
317m1829            VIA   -    MD0100PA00X+093372Y+058594X0200Y         S0      
327m1829            R1212 -1          A01X+092921Y+058558X0198Y0197R180 S1      
327m1829            PEX3  -AA1        A01X+151634Y+117992X0180Y         S1      
317m1830            VIA   -    MD0100PA00X+085923Y+087960X0200Y         S0      
327m1830            VIA   -    M      A18X+087030Y+088112X0260Y         S2      
327m1830            R1496 -1          A18X+085683Y+087946X0198Y0197     S2      
327m1830            U5    -M14        A01X+088609Y+087206X0160Y    R180 S1      
317m1830            VIA   -    MD0100PA00X+088452Y+087364X0180Y    R270 S0      
317m1830            VIA   -    MD0100PA00X+084588Y+087946X0200Y         S0      
327m1830            R4114 -2          A18X+084303Y+087946X0198Y0197R180 S2      
317m1831            VIA   -    M      A01X+050650Y+037969X0200Y         S2      
017m1831            VIA   -    M      A18X+050650Y+037969X0260Y         S2      
017m1831                  -    MD0100PA00X+050650Y+037969                       
317m1831            VIA   -    MD0100PA00X+084888Y+036085X0200Y         S0      
317m1831            VIA   -    MD0100PA00X+085118Y+083546X0200Y         S0      
327m1831            R5718 -1          A01X+085368Y+083546X0198Y0197     S1      
327m1831            U124  -3          A01X+050182Y+037969X0120Y0630R270 S1      
317m1832            VIA   -    MD0100PA00X+061537Y+009524X0200Y         S0      
327m1832            J35   -B10        A01X+061955Y+009524X0150Y0500R090 S1      
317m1832            VIA   -    MD0100PA00X+136650Y+092550X0200Y         S0      
317m1832            VIA   -    M      A01X+072519Y+094207X0200Y         S2      
017m1832            VIA   -    M      A18X+072519Y+094207X0260Y         S2      
017m1832                  -    MD0100PA00X+072519Y+094207                       
327m1832            R3568 -1          A01X+136650Y+092308X0198Y0197R270 S1      
327SSD14_PWR_EN     VIA   -    M      A01X+135300Y+081420X0300Y         S1      
327SSD14_PWR_EN     U6    -AB11       A01X+134683Y+083144X0160Y         S1      
327SSD14_PWR_EN     R4139 -1          A01X+135300Y+080958X0198Y0197R270 S1      
327SMB_NIC5_R_SCL   U120  -3          A01X+083670Y+079672X0140Y0590R270 S1      
327SMB_NIC5_R_SCL   R1519 -1   M      A01X+083008Y+079450X0198Y0197R180 S1      
317SMB_NIC5_R_SCL   VIA   -    M      A01X+082434Y+079232X0200Y         S2      
017SMB_NIC5_R_SCL   VIA   -    M      A18X+082434Y+079232X0260Y         S2      
017SMB_NIC5_R_SCL         -    MD0100PA00X+082434Y+079232                       
327SMB_NIC5_R_SCL   R1520 -2          A18X+083500Y+079508X0198Y0197R270 S2      
317SMB_NIC5_R_SCL   VIA   -    MD0100PA00X+084714Y+085946X0200Y         S0      
327SMB_NIC5_R_SCL   R1500 -2          A01X+085368Y+085946X0198Y0197R180 S1      
317m1833            J3    -I9   D0122PA00X+017917Y+158146X0282Y    R180 S3      
327m1833            R1117 -1          A01X+051128Y+072857X0198Y0197R270 S1      
317m1833            VIA   -    MD0100PA00X+050832Y+074104X0200Y    R180 S0      
317MB_SWB_PWRGD     VIA   -    M      A01X+131450Y+090500X0200Y         S2      
017MB_SWB_PWRGD     VIA   -    M      A18X+131450Y+090500X0260Y         S2      
017MB_SWB_PWRGD           -    MD0100PA00X+131450Y+090500                       
327MB_SWB_PWRGD     R1797 -1          A01X+131700Y+093092X0198Y0197R090 S1      
327MB_SWB_PWRGD     U6    -B2         A01X+131848Y+089444X0160Y         S1      
317m1834            VIA   -    MD0100PA00X+031232Y+035675X0200Y         S0      
317m1834            VIA   -    M      A01X+044054Y+035537X0200Y         S2      
017m1834            VIA   -    M      A18X+044054Y+035537X0260Y         S2      
017m1834                  -    MD0100PA00X+044054Y+035537                       
327m1834            U115  -37         A01X+043716Y+035011X0070Y0340R180 S1      
327m1834            R3583 -1          A01X+137450Y+092308X0198Y0197R270 S1      
317m1834            VIA   -    MD0100PA00X+038467Y+081410X0200Y         S0      
317m1834            VIA   -    MD0100PA00X+137437Y+092550X0200Y         S0      
327m1835            VIA   -    M      A01X+134500Y+081420X0300Y         S1      
327m1835            U6    -AA10       A01X+134368Y+083460X0160Y         S1      
327m1835            R4137 -1          A01X+134500Y+080958X0198Y0197R270 S1      
317m1836            VIA   -    MD0080PA00X+151821Y+117805X0160Y         S0      
317m1836            VIA   -    MD0100PA00X+093372Y+058934X0200Y         S0      
327m1836            R1211 -1          A01X+092921Y+058958X0198Y0197R180 S1      
327m1836            PEX3  -AA2        A01X+152008Y+117992X0180Y         S1      
327SMB_NIC5_SDA     VIA   -    M      A01X+086718Y+085526X0300Y         S1      
327SMB_NIC5_SDA     U5    -H16        A01X+087979Y+085946X0160Y    R180 S1      
327SMB_NIC5_SDA     R1501 -1   M      A01X+085683Y+085546X0198Y0197R180 S1      
327SMB_NIC5_SDA     R4876 -2          A01X+084344Y+085540X0198Y0197     S1      
317m1837            VIA   -    MD0100PA00X+040450Y+145250X0200Y         S0      
317m1837            VIA   -    M      A01X+024354Y+151147X0200Y         S2      
017m1837            VIA   -    M      A18X+024354Y+151147X0260Y         S2      
017m1837                  -    MD0100PA00X+024354Y+151147                       
327m1837            R6301 -1   M      A01X+024649Y+151014X0198Y0197     S1      
317m1837            J11   -A1   D0122PA00X+028311Y+162240X0282Y0282R180 S3      
327m1837            C4030 -2          A01X+024631Y+150606X0198Y0197R180 S1      
317m1837            VIA   -    MD0100PA00X+078865Y+142204X0200Y         S0      
317m1837            VIA   -    MD0100PA00X+090288Y+130930X0200Y         S0      
317m1837            VIA   -    MD0100PA00X+094072Y+095173X0200Y         S0      
317m1837            VIA   -    MD0100PA00X+133250Y+096150X0200Y         S0      
327m1837            U144  -1          A01X+133206Y+095594X0140Y0440R180 S1      
327m1837            R1790 -2          A01X+133200Y+096392X0198Y0197R270 S1      
317m1838            VIA   -    MD0100PA00X+034881Y+031543X0200Y         S0      
317m1838            VIA   -    M      A01X+043667Y+032258X0200Y         S2      
017m1838            VIA   -    M      A18X+043667Y+032258X0260Y         S2      
017m1838                  -    MD0100PA00X+043667Y+032258                       
327m1838            U115  -23         A01X+043559Y+032689X0070Y0340     S1      
317m1838            VIA   -    MD0100PA00X+133491Y+099034X0200Y         S0      
317m1838            VIA   -    MD0100PA00X+047399Y+095255X0200Y         S0      
327m1838            R3527 -2          A01X+136995Y+094918X0198Y0197R090 S1      
327m1839            U392  -1          A01X+122754Y+014265X0240Y0240     S1      
327m1839            R6095 -2          A01X+120720Y+014125X0198Y0197     S1      
317m1839            VIA   -    M      A01X+121012Y+014125X0200Y         S2      
017m1839            VIA   -    M      A18X+121012Y+014125X0260Y         S2      
017m1839                  -    MD0100PA00X+121012Y+014125                       
317m1839            VIA   -    MD0100PA00X+126409Y+032038X0200Y         S0      
317m1839            VIA   -    MD0100PA00X+125516Y+024430X0200Y    R090 S0      
327m1839            R4511 -2          A01X+125516Y+024168X0198Y0197     S1      
317m1839            VIA   -    MD0100PA00X+133580Y+084562X0180Y         S0      
327m1839            U6    -U8         A01X+133738Y+084719X0160Y         S1      
327m1840            R1084 -2          A01X+049851Y+068901X0198Y0197     S1      
327m1840            U114  -L1         A01X+051170Y+069055X0090Y         S1      
327m1841            R1151 -2          A01X+043142Y+036194X0198Y0197R270 S1      
327m1841            U115  -40         A01X+043244Y+035011X0070Y0340R180 S1      
327SMB_NIC3_SDA     VIA   -    M      A01X+086379Y+087780X0300Y         S1      
327SMB_NIC3_SDA     R1488 -1          A01X+084294Y+088749X0198Y0197R180 S1      
327SMB_NIC3_SDA     U5    -P16        A01X+087979Y+087836X0160Y    R180 S1      
317m1842            J3    -J9   D0122PA00X+017917Y+157634X0282Y    R180 S3      
327m1842            R1116 -1          A01X+051528Y+072857X0198Y0197R270 S1      
317m1842            VIA   -    MD0100PA00X+051172Y+074104X0200Y    R180 S0      
327MB_SWB_PWRGD_R   R6314 -1          A18X+130608Y+094400X0198Y0197     S2      
317MB_SWB_PWRGD_R   VIA   -    M      A01X+131258Y+094397X0200Y         S2      
017MB_SWB_PWRGD_R   VIA   -    M      A18X+131258Y+094397X0260Y         S2      
017MB_SWB_PWRGD_R         -    MD0100PA00X+131258Y+094397                       
327MB_SWB_PWRGD_R   R1797 -2          A01X+131700Y+093408X0198Y0197R090 S1      
327MB_SWB_PWRGD_R   R1796 -2   M      A01X+131700Y+093792X0198Y0197R270 S1      
327MB_SWB_PWRGD_R   U145  -1          A01X+131544Y+094806X0140Y0440     S1      
327m1843            PU34  -8          A01X+029979Y+021120X0110Y0240R270 S1      
317m1843            VIA   -    M      A01X+030369Y+020704X0200Y         S2      
017m1843            VIA   -    M      A18X+030369Y+020704X0260Y         S2      
017m1843                  -    MD0100PA00X+030369Y+020704                       
327m1843            R865  -2          A01X+030657Y+020486X0198Y0197R180 S1      
327m1843            R4462 -1   M      A01X+030657Y+020886X0198Y0197     S1      
317m1844            VIA   -    MD0100PA00X+132950Y+083617X0180Y         S0      
327m1844            U6    -Y6         A01X+133108Y+083774X0160Y         S1      
327m1844            R6004 -2          A01X+113261Y+024208X0198Y0197R180 S1      
317m1844            VIA   -    MD0100PA00X+117704Y+025792X0200Y         S0      
317m1844            VIA   -    M      A01X+122647Y+020886X0200Y         S2      
017m1844            VIA   -    M      A18X+122647Y+020886X0260Y         S2      
017m1844                  -    MD0100PA00X+122647Y+020886                       
317m1844            VIA   -    MD0100PA00X+126166Y+031826X0200Y         S0      
327m1844            R4470 -2          A01X+122389Y+020886X0198Y0197     S1      
327m1845            R1150 -2          A01X+043502Y+036194X0198Y0197R270 S1      
327m1845            U115  -39         A01X+043401Y+035011X0070Y0340R180 S1      
317m1846            VIA   -    MD0100PA00X+093374Y+059469X0200Y         S0      
327m1846            R1210 -1          A01X+092923Y+059433X0198Y0197R180 S1      
327m1846            PEX2  -AA1        A01X+105925Y+117992X0180Y         S1      
317m1846            VIA   -    MD0080PA00X+105738Y+117805X0160Y         S0      
317m1847            VIA   -    M      A01X+131544Y+096000X0200Y         S2      
017m1847            VIA   -    M      A18X+131544Y+096000X0260Y         S2      
017m1847                  -    MD0100PA00X+131544Y+096000                       
327m1847            R1800 -1          A01X+131500Y+096392X0198Y0197R090 S1      
327m1847            U145  -6          A01X+131544Y+095594X0140Y0440     S1      
317m1848            VIA   -    MD0100PA00X+044130Y+032506X0200Y         S0      
317m1848            VIA   -    MD0100PA00X+034835Y+031937X0200Y         S0      
327m1848            U115  -24         A01X+043716Y+032689X0070Y0340     S1      
317m1848            VIA   -    MD0100PA00X+135450Y+092550X0200Y         S0      
317m1848            VIA   -    M      A01X+047454Y+092734X0200Y         S2      
017m1848            VIA   -    M      A18X+047454Y+092734X0260Y         S2      
017m1848                  -    MD0100PA00X+047454Y+092734                       
327m1848            R3541 -1          A01X+135450Y+092308X0198Y0197R270 S1      
317m1849            VIA   -    M      A01X+168356Y+020886X0200Y         S2      
017m1849            VIA   -    M      A18X+168356Y+020886X0260Y         S2      
017m1849                  -    MD0100PA00X+168356Y+020886                       
327m1849            R4471 -2          A01X+168098Y+020886X0198Y0197     S1      
317m1849            VIA   -    MD0100PA00X+139653Y+039745X0200Y         S0      
327m1849            U6    -U11        A01X+134683Y+084719X0160Y         S1      
317m1849            VIA   -    MD0100PA00X+134525Y+084562X0180Y         S0      
317m1849            VIA   -    MD0100PA00X+163397Y+025888X0200Y         S0      
327m1849            R6024 -2          A01X+158970Y+024208X0198Y0197R180 S1      
317m1849            VIA   -    MD0100PA00X+162615Y+035103X0200Y         S0      
327m1850            R1149 -2          A01X+045258Y+035191X0198Y0197R180 S1      
327m1850            U115  -36         A01X+044011Y+034716X0070Y0340R090 S1      
317m1851            J3    -N10  D0122PA00X+018784Y+151413X0282Y    R180 S3      
317m1851            VIA   -    MD0100PA00X+051773Y+074107X0200Y    R180 S0      
327m1851            R1115 -1          A01X+051928Y+072857X0198Y0197R270 S1      
317m1852            VIA   -    MD0100PA00X+130811Y+128340X0200Y         S0      
317m1852            VIA   -    MD0100PA00X+143108Y+130170X0200Y         S0      
317m1852            J14   -A3   D0122PA00X+149563Y+162240X0282Y    R180 S3      
317m1852            VIA   -    MD0100PA00X+132055Y+103788X0200Y         S0      
317m1852            VIA   -    M      A01X+131100Y+097012X0200Y         S2      
017m1852            VIA   -    M      A18X+131100Y+097012X0260Y         S2      
017m1852                  -    MD0100PA00X+131100Y+097012                       
327m1852            R1800 -2          A01X+131500Y+096708X0198Y0197R090 S1      
327m1852            R1798 -2   M      A01X+131100Y+096708X0198Y0197R090 S1      
327m1853            PU61  -8          A01X+079426Y+022506X0110Y0240     S1      
317m1853            VIA   -    M      A01X+079577Y+022782X0200Y    R090 S2      
017m1853            VIA   -    M      A18X+079577Y+022782X0260Y    R090 S2      
017m1853                  -    MD0100PA00X+079577Y+022782                       
327m1853            R4494 -1          A01X+079492Y+024168X0198Y0197     S1      
327m1853            R892  -2   M      A01X+079637Y+023298X0198Y0197R270 S1      
317m1854            VIA   -    M      A01X+158119Y+020886X0200Y         S2      
017m1854            VIA   -    M      A18X+158119Y+020886X0260Y         S2      
017m1854                  -    MD0100PA00X+158119Y+020886                       
327m1854            R4469 -2          A01X+157861Y+020886X0198Y0197     S1      
317m1854            VIA   -    MD0100PA00X+139334Y+043110X0200Y         S0      
317m1854            VIA   -    MD0100PA00X+153161Y+025888X0200Y         S0      
327m1854            R6015 -2          A01X+148734Y+024208X0198Y0197R180 S1      
317m1854            VIA   -    MD0100PA00X+146665Y+042858X0200Y         S0      
317m1854            VIA   -    MD0100PA00X+134210Y+084247X0180Y         S0      
327m1854            U6    -V10        A01X+134368Y+084404X0160Y         S1      
327m1855            VIA   -    M      A01X+181490Y+090702X0300Y         S1      
327m1855            R6607 -1          A01X+180970Y+090702X0198Y0197R090 S1      
317m1855            VIA   -    MD0100PA00X+181990Y+090690X0200Y         S0      
317m1855            VIA   -    MD0100PA00X+155200Y+096985X0200Y         S0      
317m1855            VIA   -    MD0100PA00X+148224Y+096603X0200Y         S0      
327m1855            U101  -4          A18X+147390Y+096294X0140Y0440R270 S2      
327m1855            R936  -1          A18X+148692Y+096350X0198Y0197R180 S2      
327m1855            R6614 -1          A01X+154672Y+096974X0198Y0197R180 S1      
327m1856            R1148 -2          A01X+045258Y+034831X0198Y0197R180 S1      
327m1856            U115  -35         A01X+044011Y+034559X0070Y0340R090 S1      
327m1857            R1209 -1          A01X+092923Y+059833X0198Y0197R180 S1      
317m1857            VIA   -    MD0100PA00X+093374Y+059809X0200Y         S0      
327m1857            PEX2  -AA2        A01X+106299Y+117992X0180Y         S1      
317m1857            VIA   -    MD0080PA00X+106112Y+117805X0160Y         S0      
317m1858            J12   -F9   D0122PA00X+052563Y+159681X0282Y    R180 S3      
317m1858            VIA   -    M      A01X+056828Y+153844X0200Y         S2      
017m1858            VIA   -    M      A18X+056828Y+153844X0260Y         S2      
017m1858                  -    MD0100PA00X+056828Y+153844                       
327m1858            R1846 -1          A01X+057181Y+153858X0198Y0197R270 S1      
317m1859            VIA   -    MD0100PA00X+030895Y+035688X0200Y         S0      
317m1859            VIA   -    M      A01X+042683Y+035903X0200Y         S2      
017m1859            VIA   -    M      A18X+042683Y+035903X0260Y         S2      
017m1859                  -    MD0100PA00X+042683Y+035903                       
327m1859            U115  -41         A01X+043086Y+035011X0070Y0340R180 S1      
317m1859            VIA   -    MD0100PA00X+137450Y+093050X0200Y         S0      
317m1859            VIA   -    MD0100PA00X+038163Y+081415X0200Y         S0      
327m1859            R3597 -1          A18X+137850Y+092108X0198Y0197R090 S2      
317m1860            VIA   -    MD0100PA00X+133580Y+084247X0180Y         S0      
327m1860            U6    -V8         A01X+133738Y+084404X0160Y         S1      
317m1860            VIA   -    M      A01X+132883Y+020886X0200Y         S2      
017m1860            VIA   -    M      A18X+132883Y+020886X0260Y         S2      
017m1860                  -    MD0100PA00X+132883Y+020886                       
327m1860            R4472 -2          A01X+132625Y+020886X0198Y0197     S1      
317m1860            VIA   -    MD0100PA00X+127925Y+025888X0200Y         S0      
327m1860            R6005 -2          A01X+123497Y+024208X0198Y0197R180 S1      
317m1861            VIA   -    MD0100PA00X+179347Y+093037X0200Y         S0      
327m1861            R6608 -1          A01X+179347Y+092756X0198Y0197R270 S1      
317m1861            VIA   -    MD0100PA00X+164838Y+088677X0200Y         S0      
327m1861            R6616 -1          A01X+164382Y+088200X0198Y0197R180 S1      
317m1861            VIA   -    M      A01X+148041Y+095221X0200Y         S2      
017m1861            VIA   -    M      A18X+148041Y+095221X0260Y         S2      
017m1861                  -    MD0100PA00X+148041Y+095221                       
327m1861            U101  -6          A18X+147390Y+095782X0140Y0440R270 S2      
327m1861            R935  -1          A18X+148689Y+095838X0198Y0197R180 S2      
327m1862            R1147 -2          A01X+045258Y+034403X0198Y0197R180 S1      
327m1862            U115  -33         A01X+044011Y+034244X0070Y0340R090 S1      
317m1863            J3    -O10  D0122PA00X+018784Y+150902X0282Y    R180 S3      
317m1863            VIA   -    MD0100PA00X+052113Y+074107X0200Y    R180 S0      
327m1863            R1114 -1          A01X+052328Y+072857X0198Y0197R270 S1      
317m1864            J12   -Z2   D0122PA00X+046500Y+145272X0282Y    R180 S3      
317m1864            VIA   -    M      A01X+058180Y+149369X0200Y         S2      
017m1864            VIA   -    M      A18X+058180Y+149369X0260Y         S2      
017m1864                  -    MD0100PA00X+058180Y+149369                       
327m1864            R1838 -1          A01X+058536Y+149369X0198Y0197     S1      
327m1865            PU31  -8          A01X+055216Y+021120X0110Y0240R270 S1      
317m1865            VIA   -    M      A01X+055605Y+020704X0200Y         S2      
017m1865            VIA   -    M      A18X+055605Y+020704X0260Y         S2      
017m1865                  -    MD0100PA00X+055605Y+020704                       
327m1865            R862  -2          A01X+055893Y+020486X0198Y0197R180 S1      
327m1865            R4459 -1   M      A01X+055893Y+020886X0198Y0197     S1      
317m1866            VIA   -    MD0100PA00X+115410Y+010656X0200Y         S0      
317m1866            VIA   -    M      A01X+114802Y+014376X0200Y         S2      
017m1866            VIA   -    M      A18X+114802Y+014376X0260Y         S2      
017m1866                  -    MD0100PA00X+114802Y+014376                       
327m1866            R5577 -2          A01X+114479Y+014376X0198Y0197R270 S1      
327m1866            U6    -Y5         A01X+132793Y+083774X0160Y         S1      
317m1866            VIA   -    MD0100PA00X+132636Y+083617X0180Y         S0      
317m1866            VIA   -    MD0100PA00X+096504Y+072223X0200Y         S0      
327m1866            R4072 -2          A01X+114689Y+010250X0198Y0197     S1      
327m1866            C2773 -1   M      A01X+114689Y+010650X0198Y0197R180 S1      
327m1866            R4073 -1   M      A01X+115087Y+010656X0198Y0197R270 S1      
317m1866            VIA   -    MD0100PA00X+092231Y+087364X0180Y    R270 S0      
327m1866            U5    -M3         A01X+092074Y+087206X0160Y    R180 S1      
317m1867            VIA   -    MD0080PA00X+074616Y+114065X0160Y    R090 S0      
327m1867            VIA   -    M      A18X+074803Y+114252X0260Y         S2      
327m1867            PEX1  -AL39       A01X+074429Y+114252X0180Y         S1      
327m1867            R934  -1          A18X+075521Y+114222X0198Y0197R090 S2      
327m1868            R1146 -2          A01X+045258Y+034043X0198Y0197R180 S1      
327m1868            U115  -32         A01X+044011Y+034086X0070Y0340R090 S1      
327m1869            R1208 -1          A01X+091321Y+061559X0198Y0197R270 S1      
317m1869            VIA   -    MD0100PA00X+091291Y+062162X0200Y    R180 S0      
327m1869            PEX1  -AA1        A01X+060216Y+117992X0180Y         S1      
317m1869            VIA   -    MD0080PA00X+060029Y+117805X0160Y         S0      
317m1870            VIA   -    M      A01X+098396Y+034665X0200Y         S2      
017m1870            VIA   -    M      A18X+098396Y+034665X0260Y         S2      
017m1870                  -    MD0100PA00X+098396Y+034665                       
327m1870            R1466 -1          A01X+098118Y+034661X0198Y0197R180 S1      
327m1870            U113  -B8         A01X+101005Y+032798X0110Y0180R090 S1      
317PRSNT_SSD6_R_N   VIA   -    MD0100PA00X+136415Y+088656X0180Y         S0      
327PRSNT_SSD6_R_N   U6    -E16        A01X+136257Y+088499X0160Y         S1      
317PRSNT_SSD6_R_N   VIA   -    MD0100PA00X+091601Y+087364X0180Y    R270 S0      
327PRSNT_SSD6_R_N   U5    -M5         A01X+091444Y+087206X0160Y    R180 S1      
317PRSNT_SSD6_R_N   VIA   -    M      A01X+069093Y+014376X0200Y         S2      
017PRSNT_SSD6_R_N   VIA   -    M      A18X+069093Y+014376X0260Y         S2      
017PRSNT_SSD6_R_N         -    MD0100PA00X+069093Y+014376                       
317PRSNT_SSD6_R_N   VIA   -    MD0100PA00X+069702Y+010656X0200Y         S0      
317PRSNT_SSD6_R_N   VIA   -    MD0100PA00X+072260Y+086960X0200Y         S0      
327PRSNT_SSD6_R_N   R4065 -1   M      A01X+069378Y+010656X0198Y0197R270 S1      
327PRSNT_SSD6_R_N   R4064 -2          A01X+068980Y+010250X0198Y0197     S1      
327PRSNT_SSD6_R_N   C2769 -1   M      A01X+068980Y+010650X0198Y0197R180 S1      
327PRSNT_SSD6_R_N   R5559 -2          A01X+068770Y+014376X0198Y0197R270 S1      
317SSD9_PWR_EN      VIA   -    M      A01X+131700Y+079900X0200Y    R180 S2      
017SSD9_PWR_EN      VIA   -    M      A18X+131700Y+079900X0260Y    R180 S2      
017SSD9_PWR_EN            -    MD0100PA00X+131700Y+079900                       
327SSD9_PWR_EN      R4119 -1          A01X+131700Y+079358X0198Y0197R270 S1      
327SSD9_PWR_EN      U6    -U7         A01X+133423Y+084719X0160Y         S1      
317SSD9_PWR_EN      VIA   -    MD0100PA00X+133265Y+084562X0180Y         S0      
317m1871            VIA   -    MD0080PA00X+028907Y+114065X0160Y    R090 S0      
327m1871            VIA   -    M      A18X+029094Y+114252X0260Y         S2      
327m1871            R933  -1          A18X+029812Y+114222X0198Y0197R090 S2      
327m1871            PEX0  -AL39       A01X+028720Y+114252X0180Y         S1      
327m1872            R1145 -2          A01X+045258Y+033616X0198Y0197R180 S1      
327m1872            U115  -29         A01X+044011Y+033614X0070Y0340R090 S1      
317m1873            J3    -O9   D0122PA00X+017917Y+150980X0282Y    R180 S3      
317m1873            VIA   -    MD0100PA00X+052758Y+074159X0200Y    R180 S0      
327m1873            R1113 -1          A01X+052728Y+072857X0198Y0197R270 S1      
317m1874            VIA   -    M      A01X+098372Y+034166X0200Y         S2      
017m1874            VIA   -    M      A18X+098372Y+034166X0260Y         S2      
017m1874                  -    MD0100PA00X+098372Y+034166                       
327m1874            R1465 -1          A01X+098118Y+034311X0198Y0197R180 S1      
327m1874            U113  -A10        A01X+100709Y+032699X0070Y0220R090 S1      
327m1875            C4052 -2          A01X+060024Y+153851X0198Y0197R270 S1      
317m1875            J12   -A1   D0122PA00X+045634Y+162240X0282Y0282R180 S3      
317m1875            VIA   -    M      A01X+059581Y+154621X0200Y         S2      
017m1875            VIA   -    M      A18X+059581Y+154621X0260Y         S2      
017m1875                  -    MD0100PA00X+059581Y+154621                       
327m1875            R1837 -2   M      A01X+059581Y+153858X0198Y0197R090 S1      
327SSD2_PWR_EN_R    R5844 -1          A01X+028549Y+025954X0198Y0197R090 S1      
317SSD2_PWR_EN_R    VIA   -    MD0100PA00X+028549Y+025630X0200Y         S0      
317SSD2_PWR_EN_R    VIA   -    M      A01X+030856Y+022863X0200Y         S2      
017SSD2_PWR_EN_R    VIA   -    M      A18X+030856Y+022863X0260Y         S2      
017SSD2_PWR_EN_R          -    MD0100PA00X+030856Y+022863                       
327SSD2_PWR_EN_R    R6839 -1   M      A01X+030656Y+022572X0198Y0197     S1      
327SSD2_PWR_EN_R    C2865 -1   M      A01X+030657Y+022186X0198Y0197     S1      
327SSD2_PWR_EN_R    PU34  -11         A01X+029979Y+021710X0110Y0240R270 S1      
317SSD2_PWR_EN_R    VIA   -    MD0100PA00X+027470Y+083095X0200Y         S0      
317SSD2_PWR_EN_R    VIA   -    MD0100PA00X+131387Y+092560X0200Y         S0      
327SSD2_PWR_EN_R    R3521 -2          A01X+131450Y+092308X0198Y0197R090 S1      
317SSD8_PWR_EN      VIA   -    M      A01X+131300Y+079600X0200Y    R180 S2      
017SSD8_PWR_EN      VIA   -    M      A18X+131300Y+079600X0260Y    R180 S2      
017SSD8_PWR_EN            -    MD0100PA00X+131300Y+079600                       
327SSD8_PWR_EN      R4115 -1          A01X+131300Y+079358X0198Y0197R270 S1      
327SSD8_PWR_EN      U6    -U6         A01X+133108Y+084719X0160Y         S1      
317SSD8_PWR_EN      VIA   -    MD0100PA00X+132950Y+084562X0180Y         S0      
327m1876            R1144 -2          A01X+045258Y+033256X0198Y0197R180 S1      
327m1876            U115  -28         A01X+044011Y+033456X0070Y0340R090 S1      
327m1877            R1207 -1          A01X+090921Y+061559X0198Y0197R270 S1      
317m1877            VIA   -    MD0100PA00X+090951Y+062162X0200Y    R180 S0      
327m1877            PEX1  -AA2        A01X+060590Y+117992X0180Y         S1      
317m1877            VIA   -    MD0080PA00X+060403Y+117805X0160Y         S0      
327SSD6_PWR_EN_R    PU35  -11         A01X+075688Y+021710X0110Y0240R270 S1      
327SSD6_PWR_EN_R    C2866 -1   M      A01X+076365Y+022186X0198Y0197     S1      
317SSD6_PWR_EN_R    VIA   -    MD0100PA00X+076365Y+022454X0200Y         S0      
317SSD6_PWR_EN_R    VIA   -    MD0100PA00X+074258Y+025630X0200Y         S0      
327SSD6_PWR_EN_R    R5980 -1          A01X+074258Y+025954X0198Y0197R090 S1      
317SSD6_PWR_EN_R    VIA   -    M      A01X+137850Y+092550X0200Y         S2      
017SSD6_PWR_EN_R    VIA   -    M      A18X+137850Y+092550X0260Y         S2      
017SSD6_PWR_EN_R          -    MD0100PA00X+137850Y+092550                       
317SSD6_PWR_EN_R    VIA   -    MD0100PA00X+072712Y+095933X0200Y         S0      
327SSD6_PWR_EN_R    R3576 -1          A01X+137850Y+092308X0198Y0197R270 S1      
327SSD6_PWR_EN_R    R6835 -1          A01X+137850Y+093424X0198Y0197R090 S1      
327m1878            VIA   -    M      A01X+132100Y+081420X0300Y         S1      
327m1878            U6    -AA5        A01X+132793Y+083460X0160Y         S1      
327m1878            R4121 -1          A01X+132100Y+080958X0198Y0197R270 S1      
327m1879            R1143 -2          A01X+045258Y+032828X0198Y0197R180 S1      
327m1879            U115  -26         A01X+044011Y+033141X0070Y0340R090 S1      
317m1880            J3    -P9   D0122PA00X+017917Y+150468X0282Y    R180 S3      
317m1880            VIA   -    MD0100PA00X+053098Y+074159X0200Y    R180 S0      
327m1880            R1112 -1          A01X+053128Y+072857X0198Y0197R270 S1      
327m1881            PU57  -8          A01X+058953Y+022506X0110Y0240     S1      
317m1881            VIA   -    M      A01X+059104Y+022782X0200Y    R090 S2      
017m1881            VIA   -    M      A18X+059104Y+022782X0260Y    R090 S2      
017m1881                  -    MD0100PA00X+059104Y+022782                       
327m1881            R4487 -1          A01X+059020Y+024168X0198Y0197     S1      
327m1881            R889  -2   M      A01X+059165Y+023298X0198Y0197R270 S1      
327SSD14_CLK_EN_N   VIA   -    M      A18X+135300Y+082400X0260Y         S2      
327SSD14_CLK_EN_N   R4142 -1          A18X+135100Y+081958X0198Y0197R090 S2      
327SSD14_CLK_EN_N   U6    -Y12        A01X+134998Y+083774X0160Y         S1      
317SSD14_CLK_EN_N   VIA   -    MD0100PA00X+135155Y+083617X0180Y         S0      
327P12V_SSD2_OCP    PR217 -1          A01X+030657Y+021286X0198Y0197     S1      
327P12V_SSD2_OCP    PU34  -9          A01X+029979Y+021317X0110Y0240R270 S1      
317P12V_SSD2_OCP    VIA   -    M      A01X+030376Y+021246X0200Y         S2      
017P12V_SSD2_OCP    VIA   -    M      A18X+030376Y+021246X0260Y         S2      
017P12V_SSD2_OCP          -    MD0100PA00X+030376Y+021246                       
327m1882            R1142 -2          A01X+045258Y+032468X0198Y0197R180 S1      
327m1882            U115  -25         A01X+044011Y+032984X0070Y0340R090 S1      
327m1883            R1206 -1          A01X+090438Y+061551X0198Y0197R270 S1      
317m1883            VIA   -    MD0100PA00X+090408Y+062154X0200Y    R180 S0      
327m1883            PEX0  -AA1        A01X+014508Y+117992X0180Y         S1      
317m1883            VIA   -    MD0080PA00X+014321Y+117805X0160Y         S0      
327m1884            J37   -B10        A01X+082427Y+009524X0150Y0500R090 S1      
317m1884            VIA   -    MD0100PA00X+082009Y+009524X0200Y         S0      
317m1884            VIA   -    M      A01X+087888Y+066716X0200Y         S2      
017m1884            VIA   -    M      A18X+087888Y+066716X0260Y         S2      
017m1884                  -    MD0100PA00X+087888Y+066716                       
317m1884            VIA   -    MD0100PA00X+136650Y+093050X0200Y         S0      
317m1884            VIA   -    MD0100PA00X+100168Y+067802X0200Y         S0      
317m1884            VIA   -    MD0100PA00X+098323Y+096856X0200Y         S0      
317m1884            VIA   -    MD0100PA00X+100275Y+075717X0200Y         S0      
327m1884            R3595 -1          A18X+137050Y+092108X0198Y0197R090 S2      
317m1885            VIA   -    M      A01X+132100Y+079600X0200Y    R180 S2      
017m1885            VIA   -    M      A18X+132100Y+079600X0260Y    R180 S2      
017m1885                  -    MD0100PA00X+132100Y+079600                       
327m1885            R4125 -1          A01X+132100Y+079358X0198Y0197R270 S1      
327m1885            U6    -V7         A01X+133423Y+084404X0160Y         S1      
317m1885            VIA   -    MD0100PA00X+133265Y+084247X0180Y         S0      
327P12V_SSD2_SS     PU34  -7          A01X+029979Y+020923X0110Y0240R270 S1      
327P12V_SSD2_SS     PC386 -1          A01X+030657Y+020086X0180Y0200R180 S1      
317P12V_SSD2_SS     VIA   -    M      A01X+030367Y+020086X0200Y         S2      
017P12V_SSD2_SS     VIA   -    M      A18X+030367Y+020086X0260Y         S2      
017P12V_SSD2_SS           -    MD0100PA00X+030367Y+020086                       
327m1886            R1141 -2          A01X+043502Y+031584X0198Y0197R090 S1      
327m1886            U115  -22         A01X+043401Y+032689X0070Y0340     S1      
327m1887            R1117 -2          A01X+051128Y+072542X0198Y0197R270 S1      
327m1887            U114  -A4         A01X+051760Y+071024X0090Y         S1      
317m1888            VIA   -    M      A01X+100857Y+100665X0200Y         S2      
017m1888            VIA   -    M      A18X+100857Y+100665X0260Y         S2      
017m1888                  -    MD0100PA00X+100857Y+100665                       
327m1888            D3    -A          A01X+100857Y+100335X0240Y0280R180 S1      
327m1888            R1396 -2          A01X+101178Y+101082X0198Y0197R270 S1      
327m1889            VIA   -    M      A18X+118787Y+091653X0260Y    R090 S2      
327m1889            R1869 -1          A18X+118715Y+093046X0198Y0197R270 S2      
327m1889            R1863 -2   M      A18X+118715Y+092661X0198Y0197R270 S2      
327m1889            U309  -2          A18X+118787Y+091032X0140Y0520R180 S2      
327SSD2_PWRDIS_R    R3523 -2          A01X+131850Y+092308X0198Y0197R090 S1      
327SSD2_PWRDIS_R    R6200 -2          A01X+030183Y+011449X0198Y0197R180 S1      
317SSD2_PWRDIS_R    VIA   -    MD0100PA00X+029974Y+011208X0200Y         S0      
317SSD2_PWRDIS_R    VIA   -    MD0100PA00X+132950Y+099109X0200Y         S0      
317SSD2_PWRDIS_R    VIA   -    MD0100PA00X+047648Y+095225X0200Y         S0      
317SSD2_PWRDIS_R    VIA   -    M      A01X+026060Y+009996X0200Y         S2      
017SSD2_PWRDIS_R    VIA   -    M      A18X+026060Y+009996X0260Y         S2      
017SSD2_PWRDIS_R          -    MD0100PA00X+026060Y+009996                       
327SSD2_PWRDIS_R    J32   -B12        A01X+026482Y+009996X0150Y0500R090 S1      
317m1890            VIA   -    MD0100PA00X+132950Y+083302X0180Y         S0      
327m1890            U6    -AA6        A01X+133108Y+083460X0160Y         S1      
317m1890            VIA   -    MD0100PA00X+118138Y+031605X0200Y         S0      
317m1890            VIA   -    MD0100PA00X+140983Y+034765X0200Y         S0      
317m1890            VIA   -    MD0100PA00X+115280Y+024430X0200Y    R090 S0      
327m1890            R4507 -2          A01X+115280Y+024168X0198Y0197     S1      
317m1890            VIA   -    M      A01X+110776Y+014125X0200Y         S2      
017m1890            VIA   -    M      A18X+110776Y+014125X0260Y         S2      
017m1890                  -    MD0100PA00X+110776Y+014125                       
327m1890            R6094 -2          A01X+110483Y+014125X0198Y0197     S1      
327m1890            U393  -1          A01X+112518Y+014265X0240Y0240     S1      
327m1891            R1140 -2          A01X+043142Y+031584X0198Y0197R090 S1      
327m1891            U115  -21         A01X+043244Y+032689X0070Y0340     S1      
327m1892            R1205 -1          A01X+090038Y+061551X0198Y0197R270 S1      
317m1892            VIA   -    MD0100PA00X+090068Y+062154X0200Y    R180 S0      
327m1892            PEX0  -AA2        A01X+014882Y+117992X0180Y         S1      
317m1892            VIA   -    MD0080PA00X+014695Y+117805X0160Y         S0      
327m1893            R1116 -2          A01X+051528Y+072542X0198Y0197R270 S1      
327m1893            U114  -A5         A01X+051957Y+071024X0090Y         S1      
327m1894            R1752 -2          A01X+148312Y+032270X0198Y0197     S1      
327m1894            R1777 -1          A01X+148997Y+032270X0198Y0197     S1      
317m1894            VIA   -    MD0100PA00X+148636Y+032270X0200Y         S0      
317m1894            VIA   -    MD0100PA00X+109798Y+034048X0200Y         S0      
317m1894            VIA   -    MD0100PA00X+102260Y+029026X0200Y         S0      
317m1894            VIA   -    MD0100PA00X+094318Y+028165X0200Y         S0      
317m1894            VIA   -    M      A01X+010754Y+019266X0200Y         S2      
017m1894            VIA   -    M      A18X+010754Y+019266X0260Y         S2      
017m1894                  -    MD0100PA00X+010754Y+019266                       
317m1894            VIA   -    MD0100PA00X+020990Y+019266X0200Y         S0      
317m1894            VIA   -    MD0100PA00X+031226Y+019266X0200Y         S0      
317m1894            VIA   -    MD0100PA00X+041463Y+019266X0200Y         S0      
317m1894            VIA   -    MD0100PA00X+056463Y+019266X0200Y         S0      
317m1894            VIA   -    MD0100PA00X+066699Y+019266X0200Y         S0      
317m1894            VIA   -    MD0100PA00X+076935Y+019266X0200Y         S0      
327m1894            R589  -1          A01X+086907Y+019266X0198Y0197R180 S1      
317m1894            VIA   -    MD0100PA00X+087171Y+019266X0200Y         S0      
327m1894            R578  -1          A01X+076671Y+019266X0198Y0197R180 S1      
327m1894            R567  -1          A01X+066435Y+019266X0198Y0197R180 S1      
327m1894            R556  -1          A01X+056198Y+019266X0198Y0197R180 S1      
327m1894            R545  -1          A01X+041198Y+019266X0198Y0197R180 S1      
327m1894            R534  -1          A01X+030962Y+019266X0198Y0197R180 S1      
327m1894            R523  -1          A01X+020726Y+019266X0198Y0197R180 S1      
327m1894            R512  -1          A01X+010490Y+019266X0198Y0197R180 S1      
317m1895            VIA   -    M      A01X+100180Y+100752X0200Y         S2      
017m1895            VIA   -    M      A18X+100180Y+100752X0260Y         S2      
017m1895                  -    MD0100PA00X+100180Y+100752                       
327m1895            D3    -C          A01X+100483Y+100335X0240Y0280R180 S1      
327m1895            Q15   -3          A01X+099885Y+100926X0240Y0240R270 S1      
327m1896            U6    -C4         A01X+132478Y+089129X0160Y         S1      
317m1896            VIA   -    MD0100PA00X+132320Y+089286X0180Y         S0      
317m1896            VIA   -    MD0100PA00X+118506Y+088348X0200Y         S0      
327m1896            VIA   -    M      A18X+118260Y+087914X0260Y         S2      
327m1896            R6176 -2   M      A18X+118343Y+087439X0198Y0197R270 S2      
327m1896            R1868 -1          A18X+118743Y+087874X0198Y0197R270 S2      
327m1896            R1860 -2   M      A18X+118743Y+087439X0198Y0197R270 S2      
327m1897            PU60  -8          A01X+033717Y+022506X0110Y0240     S1      
317m1897            VIA   -    M      A01X+033868Y+022782X0200Y    R090 S2      
017m1897            VIA   -    M      A18X+033868Y+022782X0260Y    R090 S2      
017m1897                  -    MD0100PA00X+033868Y+022782                       
327m1897            R4495 -1          A01X+033784Y+024168X0198Y0197     S1      
327m1897            R893  -2   M      A01X+033929Y+023298X0198Y0197R270 S1      
327SSD11_CLK_EN_N   VIA   -    M      A18X+133085Y+083035X0260Y         S2      
327SSD11_CLK_EN_N   R4130 -1          A18X+132400Y+081958X0198Y0197R090 S2      
327SSD11_CLK_EN_N   U6    -W8         A01X+133738Y+084089X0160Y         S1      
317SSD11_CLK_EN_N   VIA   -    MD0100PA00X+133580Y+083932X0180Y         S0      
327m1898            R1139 -2          A01X+042715Y+031584X0198Y0197R090 S1      
327m1898            U115  -17         A01X+042614Y+032689X0070Y0340     S1      
317m1899            VIA   -    MD0080PA00X+019744Y+121732X0160Y         S0      
317m1899            VIA   -    MD0100PA00X+013643Y+122447X0200Y         S0      
327m1899            R1259 -1          A01X+012874Y+121707X0198Y0197R225 S1      
327m1899            VIA   -    M      A18X+013986Y+122447X0260Y         S2      
327m1899            PEX0  -L15        A01X+019744Y+121732X0180Y         S1      
327m1900            R1115 -2          A01X+051928Y+072542X0198Y0197R270 S1      
327m1900            U114  -A6         A01X+052154Y+071024X0090Y         S1      
317m1901            VIA   -    M      A01X+158565Y+008601X0200Y    R180 S2      
017m1901            VIA   -    M      A18X+158565Y+008601X0260Y    R180 S2      
017m1901                  -    MD0100PA00X+158565Y+008601                       
327m1901            R1718 -1          A01X+158565Y+008882X0198Y0197R090 S1      
327m1901            U139  -5          A01X+158252Y+008185X0240Y0460R180 S1      
327m1902            R1779 -1          A01X+087850Y+019735X0198Y0197R090 S1      
317m1902            VIA   -    MD0100PA00X+010754Y+019666X0200Y         S0      
317m1902            VIA   -    M      A01X+020990Y+019666X0200Y         S2      
017m1902            VIA   -    M      A18X+020990Y+019666X0260Y         S2      
017m1902                  -    MD0100PA00X+020990Y+019666                       
317m1902            VIA   -    MD0100PA00X+031226Y+019666X0200Y         S0      
317m1902            VIA   -    MD0100PA00X+041463Y+019666X0200Y         S0      
317m1902            VIA   -    MD0100PA00X+056463Y+019666X0200Y         S0      
317m1902            VIA   -    MD0100PA00X+066699Y+019666X0200Y         S0      
327m1902            R588  -1          A01X+086907Y+019666X0198Y0197R180 S1      
317m1902            VIA   -    MD0100PA00X+087171Y+019666X0200Y         S0      
317m1902            VIA   -    MD0100PA00X+075318Y+019867X0200Y         S0      
327m1902            R577  -1          A01X+075623Y+019662X0198Y0197     S1      
327m1902            R566  -1          A01X+066435Y+019666X0198Y0197R180 S1      
327m1902            R555  -1          A01X+056198Y+019666X0198Y0197R180 S1      
327m1902            R544  -1          A01X+041198Y+019666X0198Y0197R180 S1      
327m1902            R533  -1          A01X+030962Y+019666X0198Y0197R180 S1      
327m1902            R522  -1          A01X+020726Y+019666X0198Y0197R180 S1      
327m1902            R511  -1          A01X+010490Y+019666X0198Y0197R180 S1      
327m1902            R1753 -2   M      A01X+087453Y+019735X0198Y0197R270 S1      
317m1903            VIA   -    M      A01X+100594Y+101831X0200Y         S2      
017m1903            VIA   -    M      A18X+100594Y+101831X0260Y         S2      
017m1903                  -    MD0100PA00X+100594Y+101831                       
327m1903            Q15   -6   M      A01X+100594Y+101517X0240Y0240R270 S1      
327m1903            Q15   -5          A01X+100594Y+101221X0160Y0240R270 S1      
327m1903            R1397 -1   M      A01X+100561Y+102118X0198Y0197     S1      
327m1903            R5801 -1          A01X+100523Y+102523X0198Y0197R090 S1      
317m1904            VIA   -    MD0100PA00X+136250Y+093050X0200Y         S0      
317m1904            VIA   -    M      A01X+073380Y+095019X0200Y         S2      
017m1904            VIA   -    M      A18X+073380Y+095019X0260Y         S2      
017m1904                  -    MD0100PA00X+073380Y+095019                       
327m1904            R3580 -1          A18X+136650Y+092108X0198Y0197R090 S2      
317m1904            VIA   -    MD0100PA00X+071773Y+009524X0200Y         S0      
327m1904            J36   -B10        A01X+072191Y+009524X0150Y0500R090 S1      
327SSD13_PWRDIS     VIA   -    M      A18X+134400Y+082550X0260Y         S2      
327SSD13_PWRDIS     R4136 -1          A18X+134200Y+081958X0198Y0197R090 S2      
327SSD13_PWRDIS     U6    -Y10        A01X+134368Y+083774X0160Y         S1      
317SSD13_PWRDIS     VIA   -    MD0100PA00X+134210Y+083617X0180Y         S0      
327m1905            R1138 -2          A01X+042355Y+031584X0198Y0197R090 S1      
327m1905            U115  -16         A01X+042456Y+032689X0070Y0340     S1      
317m1906            VIA   -    M      A01X+098752Y+031409X0200Y         S2      
017m1906            VIA   -    M      A18X+098752Y+031409X0260Y         S2      
017m1906                  -    MD0100PA00X+098752Y+031409                       
327m1906            Y6    -1          A01X+098306Y+031193X0480Y0590R180 S1      
327m1906            C2636 -1   M      A01X+099040Y+031409X0198Y0197R270 S1      
327m1906            R1045 -1          A01X+099460Y+031465X0198Y0197     S1      
317PU_PEX0_TR_TCK   VIA   -    MD0080PA00X+021801Y+121545X0160Y    R090 S0      
317PU_PEX0_TR_TCK   VIA   -    M      A01X+013545Y+123492X0200Y         S2      
017PU_PEX0_TR_TCK   VIA   -    M      A18X+013545Y+123492X0260Y         S2      
017PU_PEX0_TR_TCK         -    MD0100PA00X+013545Y+123492                       
327PU_PEX0_TR_TCK   R1258 -1          A01X+010560Y+122660X0198Y0197R270 S1      
327PU_PEX0_TR_TCK   PEX0  -L20        A01X+021614Y+121732X0180Y         S1      
327m1907            R1114 -2          A01X+052328Y+072542X0198Y0197R270 S1      
327m1907            U114  -A7         A01X+052351Y+071024X0090Y         S1      
317m1908            VIA   -    M      A01X+122238Y+006051X0200Y         S2      
017m1908            VIA   -    M      A18X+122238Y+006051X0260Y         S2      
017m1908                  -    MD0100PA00X+122238Y+006051                       
317m1908            VIA   -    MD0100PA00X+122307Y+009435X0200Y         S0      
327m1908            R1713 -2          A01X+122307Y+009195X0198Y0197R090 S1      
327m1908            U136  -2   M      A01X+122238Y+006472X0170Y0460R180 S1      
327m1908            R1707 -2   M      A01X+121365Y+007259X0198Y0197     S1      
327m1908            R1702 -2          A01X+121046Y+006858X0198Y0197R180 S1      
327m1909            VIA   -    M      A18X+119715Y+088240X0260Y    R090 S2      
327m1909            U309  -5          A18X+119299Y+089575X0140Y0520R180 S2      
327m1909            R1867 -1          A18X+119243Y+087439X0198Y0197R090 S2      
327m1909            R1862 -2   M      A18X+119243Y+087874X0198Y0197R090 S2      
327JTAG_FPGA_TDI    R2537 -1          A01X+101892Y+080589X0198Y0197R270 S1      
327JTAG_FPGA_TDI    R4299 -2          A18X+100958Y+081696X0198Y0197R180 S2      
317JTAG_FPGA_TDI    VIA   -    MD0100PA00X+101478Y+081032X0200Y         S0      
327JTAG_FPGA_TDI    VIA   -    M      A18X+132447Y+090819X0280Y         S2      
327JTAG_FPGA_TDI    R2621 -1          A18X+130003Y+091148X0198Y0197     S2      
327JTAG_FPGA_TDI    U6    -E9         A01X+134053Y+088499X0160Y         S1      
317JTAG_FPGA_TDI    VIA   -    MD0100PA00X+133895Y+088656X0180Y         S0      
327SSD3_PWR_EN_R    C2867 -1   M      A01X+040893Y+022186X0198Y0197     S1      
327SSD3_PWR_EN_R    PU36  -11         A01X+040215Y+021710X0110Y0240R270 S1      
327SSD3_PWR_EN_R    R6838 -1   M      A01X+040892Y+022572X0198Y0197     S1      
317SSD3_PWR_EN_R    VIA   -    MD0100PA00X+038785Y+025630X0200Y         S0      
317SSD3_PWR_EN_R    VIA   -    MD0100PA00X+133850Y+093050X0200Y         S0      
317SSD3_PWR_EN_R    VIA   -    MD0100PA00X+047173Y+088370X0200Y         S0      
327SSD3_PWR_EN_R    R3535 -1          A18X+134250Y+092108X0198Y0197R090 S2      
327SSD3_PWR_EN_R    R5845 -1          A01X+038785Y+025954X0198Y0197R090 S1      
317SSD3_PWR_EN_R    VIA   -    M      A01X+041093Y+022863X0200Y         S2      
017SSD3_PWR_EN_R    VIA   -    M      A18X+041093Y+022863X0260Y         S2      
017SSD3_PWR_EN_R          -    MD0100PA00X+041093Y+022863                       
317m1910            VIA   -    MD0100PA00X+139321Y+042811X0200Y         S0      
317m1910            VIA   -    MD0100PA00X+159653Y+037976X0200Y         S0      
317m1910            VIA   -    MD0100PA00X+160989Y+024430X0200Y    R090 S0      
327m1910            R4506 -2          A01X+160989Y+024168X0198Y0197     S1      
317m1910            VIA   -    M      A01X+156485Y+014125X0200Y         S2      
017m1910            VIA   -    M      A18X+156485Y+014125X0260Y         S2      
017m1910                  -    MD0100PA00X+156485Y+014125                       
327m1910            R6118 -2          A01X+156192Y+014125X0198Y0197     S1      
327m1910            U397  -1          A01X+158226Y+014265X0240Y0240     S1      
317m1910            VIA   -    MD0100PA00X+134525Y+083302X0180Y         S0      
327m1910            U6    -AA11       A01X+134683Y+083460X0160Y         S1      
327m1911            R1137 -2          A01X+041928Y+031584X0198Y0197R090 S1      
327m1911            U115  -14         A01X+042141Y+032689X0070Y0340     S1      
317m1912            VIA   -    MD0080PA00X+020118Y+121732X0160Y         S0      
327m1912            R1257 -1          A01X+012026Y+122555X0198Y0197R225 S1      
317m1912            VIA   -    M      A01X+013545Y+122940X0200Y         S2      
017m1912            VIA   -    M      A18X+013545Y+122940X0260Y         S2      
017m1912                  -    MD0100PA00X+013545Y+122940                       
327m1912            PEX0  -L16        A01X+020118Y+121732X0180Y         S1      
327m1913            R1113 -2          A01X+052728Y+072542X0198Y0197R270 S1      
327m1913            U114  -A8         A01X+052548Y+071024X0090Y         S1      
317m1914            VIA   -    MD0100PA00X+147761Y+006044X0200Y         S0      
327m1914            R1717 -2          A01X+146282Y+008058X0198Y0197R180 S1      
327m1914            R1723 -2   M      A01X+146602Y+007659X0198Y0197     S1      
327m1914            U138  -3   M      A01X+147731Y+006472X0170Y0460R180 S1      
317m1914            VIA   -    M      A01X+147938Y+009428X0200Y         S2      
017m1914            VIA   -    M      A18X+147938Y+009428X0260Y         S2      
017m1914                  -    MD0100PA00X+147938Y+009428                       
327m1914            R1725 -2          A01X+147938Y+009188X0198Y0197R090 S1      
317m1915            VIA   -    MD0100PA00X+041100Y+145450X0200Y         S0      
317m1915            VIA   -    MD0100PA00X+021761Y+148967X0200Y         S0      
317m1915            J3    -Z10  D0122PA00X+018784Y+145272X0282Y    R180 S3      
317m1915            VIA   -    MD0100PA00X+118024Y+086843X0200Y    R090 S0      
317m1915            VIA   -    M      A01X+078965Y+142752X0200Y         S2      
017m1915            VIA   -    M      A18X+078965Y+142752X0260Y         S2      
017m1915                  -    MD0100PA00X+078965Y+142752                       
317m1915            VIA   -    MD0100PA00X+095522Y+078898X0200Y         S0      
317m1915            VIA   -    MD0100PA00X+091112Y+131413X0200Y         S0      
327m1915            R1865 -2          A18X+117743Y+087124X0198Y0197R090 S2      
327m1916            VIA   -    M      A18X+119265Y+091853X0260Y    R090 S2      
327m1916            R1866 -2          A18X+119115Y+092346X0198Y0197R090 S2      
327m1916            U309  -3          A18X+119043Y+091032X0140Y0520R180 S2      
327JTAG_FPGA_TCK    R875  -1   M      A01X+099199Y+076840X0198Y0197R090 S1      
327JTAG_FPGA_TCK    R4901 -1          A01X+101632Y+075455X0198Y0197     S1      
327JTAG_FPGA_TCK    R4301 -2   M      A01X+099599Y+076840X0198Y0197R270 S1      
317JTAG_FPGA_TCK    VIA   -    M      A01X+098739Y+078749X0200Y         S2      
017JTAG_FPGA_TCK    VIA   -    M      A18X+098739Y+078749X0280Y         S2      
017JTAG_FPGA_TCK          -    MD0100PA00X+098739Y+078749                       
317JTAG_FPGA_TCK    VIA   -    MD0100PA00X+134210Y+088971X0180Y         S0      
327JTAG_FPGA_TCK    U6    -D10        A01X+134368Y+088814X0160Y         S1      
327SSD9_CLK_EN_N    VIA   -    M      A01X+132500Y+081750X0300Y         S1      
327SSD9_CLK_EN_N    U6    -AB5        A01X+132793Y+083144X0160Y         S1      
327SSD9_CLK_EN_N    R4122 -1          A01X+132500Y+080958X0198Y0197R270 S1      
327m1917            R1136 -2          A01X+041568Y+031584X0198Y0197R090 S1      
327m1917            U115  -13         A01X+041984Y+032689X0070Y0340     S1      
327m1918            R1112 -2          A01X+053128Y+072542X0198Y0197R270 S1      
327m1918            U114  -A9         A01X+052744Y+071024X0090Y         S1      
327m1919            R1705 -2          A01X+131085Y+004309X0198Y0197R090 S1      
317m1919            VIA   -    MD0100PA00X+130278Y+003117X0200Y    R270 S0      
327m1919            R1708 -2   M      A01X+131486Y+003990X0198Y0197R270 S1      
327m1919            U137  -2   M      A01X+130699Y+003117X0170Y0460R090 S1      
317m1919            VIA   -    M      A01X+133662Y+003048X0200Y    R270 S2      
017m1919            VIA   -    M      A18X+133662Y+003048X0260Y    R270 S2      
017m1919                  -    MD0100PA00X+133662Y+003048                       
327m1919            R1714 -2          A01X+133422Y+003048X0198Y0197     S1      
317m1920            J3    -Q10  D0122PA00X+018784Y+149878X0282Y    R180 S3      
317m1920            VIA   -    MD0100PA00X+039537Y+150102X0200Y         S0      
327m1920            R1835 -1          A18X+039855Y+149784X0198Y0197     S2      
317m1920            VIA   -    M      A01X+022284Y+149844X0200Y         S2      
017m1920            VIA   -    M      A18X+022284Y+149844X0260Y         S2      
017m1920                  -    MD0100PA00X+022284Y+149844                       
327m1921            VIA   -    M      A18X+119666Y+092290X0260Y         S2      
327m1921            R6175 -2   M      A18X+119512Y+093046X0198Y0197R090 S2      
327m1921            R1866 -1          A18X+119115Y+092661X0198Y0197R090 S2      
327m1921            R1859 -2   M      A18X+119115Y+093046X0198Y0197R090 S2      
317m1921            VIA   -    MD0100PA00X+118165Y+089467X0200Y    R090 S0      
327m1921            U6    -C3         A01X+132163Y+089129X0160Y         S1      
317m1921            VIA   -    MD0100PA00X+132006Y+089286X0180Y         S0      
327JTAG_FPGA_TDO    VIA   -    M      A18X+101116Y+080989X0280Y         S2      
327JTAG_FPGA_TDO    R6284 -2          A18X+126973Y+086440X0198Y0197R090 S2      
317JTAG_FPGA_TDO    VIA   -    MD0100PA00X+127144Y+086185X0200Y         S0      
317JTAG_FPGA_TDO    VIA   -    MD0100PA00X+101382Y+081352X0200Y         S0      
327JTAG_FPGA_TDO    R2620 -1          A01X+101632Y+081897X0198Y0197     S1      
327JTAG_FPGA_TDO    R4902 -1   M      A01X+101628Y+081505X0198Y0197     S1      
327JTAG_FPGA_TDO    R4298 -2          A18X+100558Y+080148X0198Y0197R180 S2      
317PRSNT_SSD8_R_N   VIA   -    MD0100PA00X+094938Y+010656X0200Y         S0      
317PRSNT_SSD8_R_N   VIA   -    M      A01X+094329Y+014376X0200Y         S2      
017PRSNT_SSD8_R_N   VIA   -    M      A18X+094329Y+014376X0260Y         S2      
017PRSNT_SSD8_R_N         -    MD0100PA00X+094329Y+014376                       
327PRSNT_SSD8_R_N   R5565 -2          A01X+094006Y+014376X0198Y0197R270 S1      
317PRSNT_SSD8_R_N   VIA   -    MD0100PA00X+096809Y+079979X0200Y         S0      
317PRSNT_SSD8_R_N   VIA   -    MD0100PA00X+096598Y+076357X0200Y         S0      
317PRSNT_SSD8_R_N   VIA   -    MD0100PA00X+092546Y+087049X0180Y    R270 S0      
327PRSNT_SSD8_R_N   U5    -L2         A01X+092389Y+086891X0160Y    R180 S1      
327PRSNT_SSD8_R_N   R4069 -1   M      A01X+094614Y+010656X0198Y0197R270 S1      
327PRSNT_SSD8_R_N   R4068 -2          A01X+094216Y+010250X0198Y0197     S1      
327PRSNT_SSD8_R_N   C2771 -1   M      A01X+094216Y+010650X0198Y0197R180 S1      
327PRSNT_SSD8_R_N   U6    -AA2        A01X+131848Y+083460X0160Y         S1      
317PRSNT_SSD8_R_N   VIA   -    MD0100PA00X+131691Y+083302X0180Y         S0      
317m1922            VIA   -    M      A01X+168801Y+008601X0200Y    R180 S2      
017m1922            VIA   -    M      A18X+168801Y+008601X0260Y    R180 S2      
017m1922                  -    MD0100PA00X+168801Y+008601                       
327m1922            R1729 -1          A01X+168801Y+008882X0198Y0197R090 S1      
327m1922            U140  -5          A01X+168488Y+008185X0240Y0460R180 S1      
317m1923            J3    -I10  D0122PA00X+018784Y+158067X0282Y    R180 S3      
317m1923            VIA   -    M      A01X+022697Y+151458X0200Y    R090 S2      
017m1923            VIA   -    M      A18X+022697Y+151458X0260Y    R090 S2      
017m1923                  -    MD0100PA00X+022697Y+151458                       
327m1923            R1834 -1          A01X+022947Y+151458X0198Y0197     S1      
327m1924            VIA   -    M      A01X+131700Y+081750X0300Y         S1      
327m1924            R4117 -1          A01X+131700Y+080958X0198Y0197R270 S1      
327m1924            U6    -AB3        A01X+132163Y+083144X0160Y         S1      
327P12V_SSD1_SS     PU32  -7          A01X+019743Y+020923X0110Y0240R270 S1      
327P12V_SSD1_SS     PC374 -1          A01X+020420Y+020086X0180Y0200R180 S1      
317P12V_SSD1_SS     VIA   -    M      A01X+020130Y+020086X0200Y         S2      
017P12V_SSD1_SS     VIA   -    M      A18X+020130Y+020086X0260Y         S2      
017P12V_SSD1_SS           -    MD0100PA00X+020130Y+020086                       
317m1925            VIA   -    MD0100PA00X+145952Y+098943X0200Y         S0      
327m1925            U103  -3          A18X+146471Y+097674X0140Y0440R270 S2      
317m1925            VIA   -    M      A01X+174582Y+098706X0200Y         S2      
017m1925            VIA   -    M      A18X+174582Y+098706X0260Y         S2      
017m1925                  -    MD0100PA00X+174582Y+098706                       
327m1925            R969  -2          A18X+166938Y+113907X0198Y0197R090 S2      
317m1926            VIA   -    M      A01X+147475Y+006051X0200Y         S2      
017m1926            VIA   -    M      A18X+147475Y+006051X0260Y         S2      
017m1926                  -    MD0100PA00X+147475Y+006051                       
327m1926            R1721 -2   M      A01X+146602Y+007259X0198Y0197     S1      
327m1926            R1716 -2          A01X+146282Y+006858X0198Y0197R180 S1      
327m1926            U138  -2   M      A01X+147475Y+006472X0170Y0460R180 S1      
317m1926            VIA   -    MD0100PA00X+147543Y+009435X0200Y         S0      
327m1926            R1727 -2          A01X+147543Y+009195X0198Y0197R090 S1      
327m1927            VIA   -    M      A18X+118465Y+088640X0260Y    R090 S2      
327m1927            U309  -7          A18X+118787Y+089575X0140Y0520R180 S2      
327m1927            R1865 -1          A18X+117743Y+087439X0198Y0197R090 S2      
327m1927            R1861 -2   M      A18X+117743Y+087874X0198Y0197R090 S2      
327JTAG_FPGA_TMS    U6    -C10        A01X+134368Y+089129X0160Y         S1      
317JTAG_FPGA_TMS    VIA   -    MD0100PA00X+134210Y+089286X0180Y         S0      
317JTAG_FPGA_TMS    VIA   -    MD0100PA00X+130579Y+086770X0200Y         S0      
327JTAG_FPGA_TMS    R4903 -1          A18X+128903Y+086694X0198Y0197R090 S2      
317JTAG_FPGA_TMS    VIA   -    M      A01X+100799Y+076590X0200Y    R180 S2      
017JTAG_FPGA_TMS    VIA   -    M      A18X+100799Y+076590X0280Y    R180 S2      
017JTAG_FPGA_TMS          -    MD0100PA00X+100799Y+076590                       
327JTAG_FPGA_TMS    R4300 -2          A01X+100799Y+076840X0198Y0197R270 S1      
327JTAG_FPGA_TMS    R2619 -1   M      A01X+101632Y+077197X0198Y0197     S1      
327JTAG_FPGA_TMS    R4900 -1          A01X+101632Y+077597X0198Y0197     S1      
317PRSNT_SSD9_R_N   VIA   -    M      A01X+104565Y+014376X0200Y         S2      
017PRSNT_SSD9_R_N   VIA   -    M      A18X+104565Y+014376X0260Y         S2      
017PRSNT_SSD9_R_N         -    MD0100PA00X+104565Y+014376                       
317PRSNT_SSD9_R_N   VIA   -    MD0100PA00X+105174Y+010656X0200Y         S0      
317PRSNT_SSD9_R_N   VIA   -    MD0100PA00X+096756Y+080298X0200Y         S0      
317PRSNT_SSD9_R_N   VIA   -    MD0100PA00X+092861Y+087049X0180Y    R270 S0      
327PRSNT_SSD9_R_N   U5    -L1         A01X+092704Y+086891X0160Y    R180 S1      
327PRSNT_SSD9_R_N   R4070 -2          A01X+104452Y+010250X0198Y0197     S1      
327PRSNT_SSD9_R_N   C2772 -1   M      A01X+104452Y+010650X0198Y0197R180 S1      
327PRSNT_SSD9_R_N   R4071 -1   M      A01X+104851Y+010656X0198Y0197R270 S1      
327PRSNT_SSD9_R_N   R5571 -2          A01X+104242Y+014376X0198Y0197R270 S1      
317PRSNT_SSD9_R_N   VIA   -    MD0100PA00X+132636Y+083932X0180Y         S0      
327PRSNT_SSD9_R_N   U6    -W5         A01X+132793Y+084089X0160Y         S1      
327m1928            R965  -2          A18X+121230Y+113907X0198Y0197R090 S2      
317m1928            VIA   -    MD0100PA00X+125215Y+102622X0200Y         S0      
327m1928            U103  -1          A18X+146471Y+097162X0140Y0440R270 S2      
317m1928            VIA   -    M      A01X+145794Y+096671X0200Y         S2      
017m1928            VIA   -    M      A18X+145794Y+096671X0260Y         S2      
017m1928                  -    MD0100PA00X+145794Y+096671                       
317m1929            VIA   -    M      A01X+179071Y+008171X0200Y    R180 S2      
017m1929            VIA   -    M      A18X+179071Y+008171X0260Y    R180 S2      
017m1929                  -    MD0100PA00X+179071Y+008171                       
327m1929            U141  -5          A01X+178725Y+008185X0240Y0460R180 S1      
327m1929            R1732 -1          A01X+179037Y+008882X0198Y0197R090 S1      
317m1930            J3    -R10  D0122PA00X+018784Y+149366X0282Y    R180 S3      
317m1930            VIA   -    MD0100PA00X+039875Y+150096X0200Y         S0      
327m1930            R1836 -1          A18X+039511Y+149091X0198Y0197R270 S2      
317m1930            VIA   -    M      A01X+021802Y+149472X0200Y         S2      
017m1930            VIA   -    M      A18X+021802Y+149472X0260Y         S2      
017m1930                  -    MD0100PA00X+021802Y+149472                       
327m1931            VIA   -    M      A18X+118115Y+091903X0260Y    R090 S2      
327m1931            R1864 -2          A18X+118115Y+092346X0198Y0197R090 S2      
327m1931            U309  -1          A18X+118531Y+091032X0140Y0520R180 S2      
317m1932            VIA   -    MD0100PA00X+097216Y+025888X0200Y         S0      
327m1932            R5994 -2          A01X+095128Y+023797X0198Y0197R270 S1      
317m1932            VIA   -    MD0100PA00X+102174Y+020886X0200Y         S0      
317m1932            VIA   -    M      A01X+134976Y+037191X0200Y         S2      
017m1932            VIA   -    M      A18X+134976Y+037191X0260Y         S2      
017m1932                  -    MD0100PA00X+134976Y+037191                       
317m1932            VIA   -    MD0100PA00X+109256Y+035337X0200Y         S0      
327m1932            R4466 -2          A01X+101916Y+020886X0198Y0197     S1      
327m1932            U6    -AB2        A01X+131848Y+083144X0160Y         S1      
317m1932            VIA   -    MD0100PA00X+131691Y+082987X0180Y         S0      
327P12V_SSD5_OCP    PR214 -1          A01X+066129Y+021286X0198Y0197     S1      
327P12V_SSD5_OCP    PU33  -9          A01X+065452Y+021317X0110Y0240R270 S1      
317P12V_SSD5_OCP    VIA   -    M      A01X+065848Y+021246X0200Y         S2      
017P12V_SSD5_OCP    VIA   -    M      A18X+065848Y+021246X0260Y         S2      
017P12V_SSD5_OCP          -    MD0100PA00X+065848Y+021246                       
327m1933            VIA   -    M      A18X+151747Y+096747X0260Y         S2      
327m1933            U102  -4          A18X+152044Y+096144X0140Y0440     S2      
327m1933            R942  -1          A18X+151742Y+097209X0198Y0197R270 S2      
317m1934            VIA   -    MD0100PA00X+168233Y+006044X0200Y         S0      
327m1934            U140  -3   M      A01X+168203Y+006472X0170Y0460R180 S1      
327m1934            R1731 -2          A01X+166754Y+008058X0198Y0197R180 S1      
327m1934            R1737 -2   M      A01X+167074Y+007659X0198Y0197     S1      
317m1934            VIA   -    M      A01X+168410Y+009428X0200Y         S2      
017m1934            VIA   -    M      A18X+168410Y+009428X0260Y         S2      
017m1934                  -    MD0100PA00X+168410Y+009428                       
327m1934            R1739 -2          A01X+168410Y+009188X0198Y0197R090 S1      
317m1935            VIA   -    M      A01X+022332Y+151858X0200Y    R090 S2      
017m1935            VIA   -    M      A18X+022332Y+151858X0260Y    R090 S2      
017m1935                  -    MD0100PA00X+022332Y+151858                       
317m1935            J3    -H10  D0122PA00X+018784Y+158579X0282Y    R180 S3      
327m1935            C4025 -2   M      A01X+022309Y+151564X0198Y0197     S1      
327m1935            R1833 -2          A01X+022947Y+151858X0198Y0197R180 S1      
317m1936            VIA   -    M      A01X+117446Y+091452X0200Y    R090 S2      
017m1936            VIA   -    M      A18X+117446Y+091452X0260Y    R090 S2      
017m1936                  -    MD0100PA00X+117446Y+091452                       
327m1936            U6    -A3         A01X+132163Y+089759X0160Y         S1      
317m1936            VIA   -    MD0100PA00X+131950Y+090150X0200Y         S0      
327m1936            R6174 -2   M      A18X+117719Y+093046X0198Y0197R090 S2      
327m1936            R1864 -1          A18X+118115Y+092661X0198Y0197R090 S2      
327m1936            R1858 -2   M      A18X+118115Y+093046X0198Y0197R090 S2      
317SSD11_PWRDIS     VIA   -    M      A01X+132900Y+079600X0200Y    R180 S2      
017SSD11_PWRDIS     VIA   -    M      A18X+132900Y+079600X0260Y    R180 S2      
017SSD11_PWRDIS           -    MD0100PA00X+132900Y+079600                       
327SSD11_PWRDIS     R4128 -1          A01X+132900Y+079358X0198Y0197R270 S1      
317SSD11_PWRDIS     VIA   -    MD0100PA00X+133895Y+084562X0180Y         S0      
327SSD11_PWRDIS     U6    -U9         A01X+134053Y+084719X0160Y         S1      
317m1937            VIA   -    M      A01X+157711Y+006051X0200Y         S2      
017m1937            VIA   -    M      A18X+157711Y+006051X0260Y         S2      
017m1937                  -    MD0100PA00X+157711Y+006051                       
327m1937            R1722 -2   M      A01X+156838Y+007259X0198Y0197     S1      
327m1937            R1719 -2          A01X+156518Y+006858X0198Y0197R180 S1      
327m1937            U139  -2   M      A01X+157711Y+006472X0170Y0460R180 S1      
317m1937            VIA   -    MD0100PA00X+157779Y+009435X0200Y         S0      
327m1937            R1728 -2          A01X+157779Y+009195X0198Y0197R090 S1      
317FPGA_JTAGENB     VIA   -    M      A01X+140476Y+091519X0200Y         S2      
017FPGA_JTAGENB     VIA   -    M      A18X+140476Y+091519X0260Y         S2      
017FPGA_JTAGENB           -    MD0100PA00X+140476Y+091519                       
327FPGA_JTAGENB     R2622 -1          A01X+140774Y+091114X0198Y0197     S1      
327FPGA_JTAGENB     R4297 -1   M      A01X+140774Y+091519X0198Y0197     S1      
317FPGA_JTAGENB     VIA   -    MD0100PA00X+135785Y+088656X0180Y         S0      
327FPGA_JTAGENB     U6    -E14        A01X+135628Y+088499X0160Y         S1      
327m1938            VIA   -    M      A18X+134800Y+083200X0260Y         S2      
327m1938            U6    -Y11        A01X+134683Y+083774X0160Y         S1      
317m1938            VIA   -    MD0100PA00X+134525Y+083617X0180Y         S0      
327m1938            R4141 -1          A18X+134650Y+081958X0198Y0197R090 S2      
327m1939            VIA   -    M      A18X+152910Y+096709X0260Y         S2      
327m1939            U102  -6          A18X+152556Y+096144X0140Y0440     S2      
327m1939            R941  -1          A18X+152836Y+097152X0198Y0197R270 S2      
317m1940            VIA   -    M      A01X+112856Y+008601X0200Y    R180 S2      
017m1940            VIA   -    M      A18X+112856Y+008601X0260Y    R180 S2      
017m1940                  -    MD0100PA00X+112856Y+008601                       
327m1940            U135  -5          A01X+112544Y+008185X0240Y0460R180 S1      
327m1940            R1690 -1          A01X+112856Y+008882X0198Y0197R090 S1      
327m1941            U5    -N3         A01X+092074Y+087521X0160Y    R180 S1      
317m1941            VIA   -    MD0100PA00X+092231Y+087679X0180Y    R270 S0      
317m1941            VIA   -    MD0100PA00X+097084Y+072992X0200Y         S0      
317m1941            VIA   -    MD0100PA00X+134210Y+084562X0180Y         S0      
327m1941            U6    -U10        A01X+134368Y+084719X0160Y         S1      
317m1941            VIA   -    MD0100PA00X+138712Y+041731X0200Y         S0      
317m1941            VIA   -    MD0100PA00X+150883Y+010656X0200Y         S0      
317m1941            VIA   -    M      A01X+150274Y+014376X0200Y         S2      
017m1941            VIA   -    M      A18X+150274Y+014376X0260Y         S2      
017m1941                  -    MD0100PA00X+150274Y+014376                       
327m1941            R5574 -2          A01X+149951Y+014376X0198Y0197R270 S1      
327m1941            R4079 -1   M      A01X+150559Y+010656X0198Y0197R270 S1      
327m1941            R4078 -2          A01X+150161Y+010250X0198Y0197     S1      
327m1941            C2776 -1   M      A01X+150161Y+010650X0198Y0197R180 S1      
317m1941            VIA   -    MD0100PA00X+147524Y+041248X0200Y         S0      
327m1942            R934  -2          A18X+075521Y+113907X0198Y0197R090 S2      
327m1942            U101  -3          A18X+146603Y+096294X0140Y0440R270 S2      
317m1942            VIA   -    M      A01X+145820Y+096029X0200Y         S2      
017m1942            VIA   -    M      A18X+145820Y+096029X0260Y         S2      
017m1942                  -    MD0100PA00X+145820Y+096029                       
317m1942            VIA   -    MD0100PA00X+074306Y+100446X0200Y         S0      
317m1943            VIA   -    MD0100PA00X+157997Y+006044X0200Y         S0      
327m1943            U139  -3   M      A01X+157967Y+006472X0170Y0460R180 S1      
327m1943            R1720 -2          A01X+156518Y+008058X0198Y0197R180 S1      
327m1943            R1724 -2   M      A01X+156838Y+007659X0198Y0197     S1      
317m1943            VIA   -    M      A01X+158174Y+009428X0200Y         S2      
017m1943            VIA   -    M      A18X+158174Y+009428X0260Y         S2      
017m1943                  -    MD0100PA00X+158174Y+009428                       
327m1943            R1726 -2          A01X+158174Y+009188X0198Y0197R090 S1      
317PRSNT_GPU_ISO    VIA   -    M      A01X+128955Y+094100X0200Y         S2      
017PRSNT_GPU_ISO    VIA   -    M      A18X+128955Y+094100X0260Y         S2      
017PRSNT_GPU_ISO          -    MD0100PA00X+128955Y+094100                       
327PRSNT_GPU_ISO    Q19   -5          A01X+129250Y+093804X0160Y0240     S1      
327PRSNT_GPU_ISO    Q19   -6          A01X+128955Y+093804X0240Y0240     S1      
327PRSNT_GPU_ISO    R1782 -1   M      A01X+128950Y+094392X0198Y0197R090 S1      
317m1944            VIA   -    MD0100PA00X+147883Y+020886X0200Y         S0      
327m1944            R4467 -2          A01X+147625Y+020886X0198Y0197     S1      
317m1944            VIA   -    MD0100PA00X+142925Y+025888X0200Y         S0      
327m1944            R6014 -2          A01X+138498Y+024208X0198Y0197R180 S1      
317m1944            VIA   -    M      A01X+137511Y+042084X0200Y         S2      
017m1944            VIA   -    M      A18X+137511Y+042084X0260Y         S2      
017m1944                  -    MD0100PA00X+137511Y+042084                       
317m1944            VIA   -    MD0100PA00X+133580Y+082987X0180Y         S0      
327m1944            U6    -AB8        A01X+133738Y+083144X0160Y         S1      
327P12V_SSD5_SS     PU33  -7          A01X+065452Y+020923X0110Y0240R270 S1      
327P12V_SSD5_SS     PC375 -1          A01X+066129Y+020086X0180Y0200R180 S1      
317P12V_SSD5_SS     VIA   -    M      A01X+065839Y+020086X0200Y         S2      
017P12V_SSD5_SS     VIA   -    M      A18X+065839Y+020086X0260Y         S2      
017P12V_SSD5_SS           -    MD0100PA00X+065839Y+020086                       
327m1945            R933  -2          A18X+029812Y+113907X0198Y0197R090 S2      
317m1945            VIA   -    MD0100PA00X+146200Y+095700X0200Y         S0      
317m1945            VIA   -    M      A01X+034108Y+101806X0200Y         S2      
017m1945            VIA   -    M      A18X+034108Y+101806X0260Y         S2      
017m1945                  -    MD0100PA00X+034108Y+101806                       
327m1945            U101  -1          A18X+146603Y+095782X0140Y0440R270 S2      
317m1946            VIA   -    M      A01X+178183Y+006051X0200Y         S2      
017m1946            VIA   -    M      A18X+178183Y+006051X0260Y         S2      
017m1946                  -    MD0100PA00X+178183Y+006051                       
327m1946            U141  -2   M      A01X+178183Y+006472X0170Y0460R180 S1      
327m1946            R1736 -2   M      A01X+177310Y+007259X0198Y0197     S1      
327m1946            R1733 -2          A01X+176991Y+006858X0198Y0197R180 S1      
317m1946            VIA   -    MD0100PA00X+178252Y+009435X0200Y         S0      
327m1946            R1742 -2          A01X+178252Y+009195X0198Y0197R090 S1      
317m1947            VIA   -    MD0100PA00X+125647Y+010656X0200Y         S0      
317m1947            VIA   -    MD0100PA00X+128442Y+035938X0200Y         S0      
317m1947            VIA   -    MD0100PA00X+137702Y+039771X0200Y         S0      
327m1947            U6    -AB7        A01X+133423Y+083144X0160Y         S1      
317m1947            VIA   -    MD0100PA00X+133580Y+082650X0200Y         S0      
317m1947            VIA   -    MD0100PA00X+096859Y+072243X0200Y         S0      
327m1947            R4075 -1   M      A01X+125323Y+010656X0198Y0197R270 S1      
327m1947            R4074 -2          A01X+124925Y+010250X0198Y0197     S1      
327m1947            C2774 -1   M      A01X+124925Y+010650X0198Y0197R180 S1      
317m1947            VIA   -    M      A01X+125038Y+014376X0200Y         S2      
017m1947            VIA   -    M      A18X+125038Y+014376X0260Y         S2      
017m1947                  -    MD0100PA00X+125038Y+014376                       
327m1947            R5583 -2          A01X+124715Y+014376X0198Y0197R270 S1      
327m1947            U5    -M2         A01X+092389Y+087206X0160Y    R180 S1      
317m1947            VIA   -    MD0100PA00X+092546Y+087364X0180Y    R270 S0      
327m1948            VIA   -    M      A18X+150006Y+087034X0260Y         S2      
327m1948            R930  -1          A18X+149514Y+087034X0198Y0197     S2      
327m1948            U100  -4          A18X+150663Y+087378X0140Y0440R090 S2      
317m1949            VIA   -    M      A01X+132412Y+002274X0200Y    R090 S2      
017m1949            VIA   -    M      A18X+132412Y+002274X0260Y    R090 S2      
017m1949                  -    MD0100PA00X+132412Y+002274                       
327m1949            R1704 -1          A01X+133110Y+002263X0198Y0197     S1      
327m1949            U137  -5          A01X+132412Y+002575X0240Y0460R090 S1      
317m1950            VIA   -    MD0100PA00X+088452Y+084844X0180Y    R270 S0      
327m1950            U5    -E14        A01X+088609Y+085002X0160Y    R180 S1      
317m1950            VIA   -    M      A01X+127826Y+072224X0200Y         S2      
017m1950            VIA   -    M      A18X+127826Y+072224X0260Y         S2      
017m1950                  -    MD0100PA00X+127826Y+072224                       
317m1950            VIA   -    MD0100PA00X+091386Y+072129X0200Y         S0      
317m1950            VIA   -    MD0100PA00X+128173Y+094948X0200Y         S0      
327m1950            R1783 -2          A01X+128030Y+093360X0198Y0197R180 S1      
327P12V_SSD4_OCP    PR210 -1          A01X+055893Y+021286X0198Y0197     S1      
327P12V_SSD4_OCP    PU31  -9          A01X+055216Y+021317X0110Y0240R270 S1      
317P12V_SSD4_OCP    VIA   -    M      A01X+055612Y+021246X0200Y         S2      
017P12V_SSD4_OCP    VIA   -    M      A18X+055612Y+021246X0260Y         S2      
017P12V_SSD4_OCP          -    MD0100PA00X+055612Y+021246                       
327m1951            VIA   -    M      A18X+150056Y+088134X0260Y         S2      
327m1951            R929  -1          A18X+149514Y+088084X0198Y0197     S2      
327m1951            U100  -6          A18X+150663Y+087890X0140Y0440R090 S2      
327m1952            R1706 -2          A01X+132285Y+004309X0198Y0197R090 S1      
317m1952            VIA   -    M      A01X+130214Y+002632X0200Y    R270 S2      
017m1952            VIA   -    M      A18X+130214Y+002632X0260Y    R270 S2      
017m1952                  -    MD0100PA00X+130214Y+002632                       
327m1952            U137  -3   M      A01X+130699Y+002861X0170Y0460R090 S1      
327m1952            R1710 -2   M      A01X+131886Y+003990X0198Y0197R270 S1      
317m1952            VIA   -    MD0100PA00X+133655Y+002653X0200Y    R270 S0      
327m1952            R1712 -2          A01X+133415Y+002653X0198Y0197     S1      
317m1953            VIA   -    M      A01X+167947Y+006051X0200Y         S2      
017m1953            VIA   -    M      A18X+167947Y+006051X0260Y         S2      
017m1953                  -    MD0100PA00X+167947Y+006051                       
327m1953            U140  -2   M      A01X+167947Y+006472X0170Y0460R180 S1      
327m1953            R1735 -2   M      A01X+167074Y+007259X0198Y0197     S1      
327m1953            R1730 -2          A01X+166754Y+006858X0198Y0197R180 S1      
317m1953            VIA   -    MD0100PA00X+168016Y+009435X0200Y         S0      
327m1953            R1741 -2          A01X+168016Y+009195X0198Y0197R090 S1      
317m1954            VIA   -    M      A01X+129545Y+092805X0200Y         S2      
017m1954            VIA   -    M      A18X+129545Y+092805X0260Y         S2      
017m1954                  -    MD0100PA00X+129545Y+092805                       
327m1954            R1783 -1          A01X+128345Y+093360X0198Y0197R180 S1      
327m1954            R6147 -1          A01X+130200Y+092308X0198Y0197R270 S1      
327m1954            R1781 -1   M      A01X+129800Y+092308X0198Y0197R270 S1      
327m1954            Q19   -3   M      A01X+129545Y+093096X0240Y0240     S1      
327P12V_SSD6_OCP    PR218 -1          A01X+076365Y+021286X0198Y0197     S1      
327P12V_SSD6_OCP    PU35  -9          A01X+075688Y+021317X0110Y0240R270 S1      
317P12V_SSD6_OCP    VIA   -    M      A01X+076084Y+021246X0200Y         S2      
017P12V_SSD6_OCP    VIA   -    M      A18X+076084Y+021246X0260Y         S2      
017P12V_SSD6_OCP          -    MD0100PA00X+076084Y+021246                       
317m1955            VIA   -    M      A01X+148329Y+008601X0200Y    R180 S2      
017m1955            VIA   -    M      A18X+148329Y+008601X0260Y    R180 S2      
017m1955                  -    MD0100PA00X+148329Y+008601                       
327m1955            U138  -5          A01X+148016Y+008185X0240Y0460R180 S1      
327m1955            R1715 -1          A01X+148329Y+008882X0198Y0197R090 S1      
317m1956            VIA   -    MD0100PA00X+087134Y+008605X0200Y    R180 S0      
327m1956            U133  -6          A01X+087022Y+008185X0170Y0460R180 S1      
327m1956            R1684 -1          A01X+087229Y+008873X0198Y0197R090 S1      
317m1956            VIA   -    M      A01X+087326Y+030003X0200Y         S2      
017m1956            VIA   -    M      A18X+087326Y+030003X0260Y         S2      
017m1956                  -    MD0100PA00X+087326Y+030003                       
327m1956            R1588 -1          A01X+053876Y+037272X0198Y0197R180 S1      
327m1956            R1571 -2   M      A01X+054561Y+037272X0198Y0197R180 S1      
317m1957            VIA   -    MD0100PA00X+178525Y+006066X0200Y         S0      
327m1957            U141  -3   M      A01X+178439Y+006472X0170Y0460R180 S1      
327m1957            R1734 -2          A01X+176991Y+008058X0198Y0197R180 S1      
327m1957            R1738 -2   M      A01X+177310Y+007659X0198Y0197     S1      
317m1957            VIA   -    M      A01X+178647Y+009428X0200Y         S2      
017m1957            VIA   -    M      A18X+178647Y+009428X0260Y         S2      
017m1957                  -    MD0100PA00X+178647Y+009428                       
327m1957            R1740 -2          A01X+178647Y+009188X0198Y0197R090 S1      
327m1958            VIA   -    M      A18X+019725Y+154407X0160Y0041R315 S2      
317m1958            VIA   -    MD0100PA00X+021791Y+142705X0200Y         S0      
327m1958            R6733 -2   M      A01X+022154Y+142896X0180Y0200R270 S1      
327m1958            R5451 -2          A01X+022154Y+142896X0180Y0200R090 S1      
317m1958            J3    -M9   D0122PA00X+017917Y+156098X0282Y    R180 S3      
327m1959            VIA   -    M      A18X+098995Y+036031X0260Y         S2      
317m1959            VIA   -    MD0100PA00X+099602Y+035213X0200Y         S0      
327m1959            R1077 -2          A18X+098008Y+036031X0198Y0197R090 S2      
327m1959            U113  -B4         A01X+101005Y+033585X0110Y0180R090 S1      
317m1960            VIA   -    MD0100PA00X+066662Y+008605X0200Y    R180 S0      
327m1960            R1670 -1          A01X+066757Y+008873X0198Y0197R090 S1      
327m1960            U131  -6          A01X+066550Y+008185X0170Y0460R180 S1      
317m1960            VIA   -    M      A01X+068949Y+033958X0200Y         S2      
017m1960            VIA   -    M      A18X+068949Y+033958X0260Y         S2      
017m1960                  -    MD0100PA00X+068949Y+033958                       
327m1960            R1580 -1          A01X+053876Y+035472X0198Y0197R180 S1      
327m1960            R1564 -2   M      A01X+054561Y+035472X0198Y0197R180 S1      
317m1961            VIA   -    MD0100PA00X+122524Y+006044X0200Y         S0      
327m1961            U136  -3   M      A01X+122494Y+006472X0170Y0460R180 S1      
327m1961            R1703 -2          A01X+121046Y+008058X0198Y0197R180 S1      
327m1961            R1709 -2   M      A01X+121365Y+007659X0198Y0197     S1      
317m1961            VIA   -    M      A01X+122702Y+009428X0200Y         S2      
017m1961            VIA   -    M      A18X+122702Y+009428X0260Y         S2      
017m1961                  -    MD0100PA00X+122702Y+009428                       
327m1961            R1711 -2          A01X+122702Y+009188X0198Y0197R090 S1      
327SSD3_CLK_EN_N    VIA   -    M      A01X+135650Y+091500X0300Y         S1      
327SSD3_CLK_EN_N    R3541 -2          A01X+135450Y+091992X0198Y0197R270 S1      
327SSD3_CLK_EN_N    U6    -B14        A01X+135628Y+089444X0160Y         S1      
327P12V_SSD6_SS     PC387 -1          A01X+076365Y+020086X0198Y0197     S1      
327P12V_SSD6_SS     PU35  -7          A01X+075688Y+020923X0110Y0240R270 S1      
317P12V_SSD6_SS     VIA   -    M      A01X+076075Y+020086X0200Y         S2      
017P12V_SSD6_SS     VIA   -    M      A18X+076075Y+020086X0260Y         S2      
017P12V_SSD6_SS           -    MD0100PA00X+076075Y+020086                       
327m1962            R1669 -1          A01X+056521Y+008873X0198Y0197R090 S1      
327m1962            U130  -6          A01X+056313Y+008185X0170Y0460R180 S1      
317m1962            VIA   -    MD0100PA00X+056426Y+008605X0200Y    R180 S0      
317m1962            VIA   -    M      A01X+058468Y+033628X0200Y         S2      
017m1962            VIA   -    M      A18X+058468Y+033628X0260Y         S2      
017m1962                  -    MD0100PA00X+058468Y+033628                       
327m1962            R1576 -1          A01X+053876Y+034572X0198Y0197R180 S1      
327m1962            R1562 -2   M      A01X+054561Y+034572X0198Y0197R180 S1      
317m1963            VIA   -    M      A01X+123092Y+008601X0200Y    R180 S2      
017m1963            VIA   -    M      A18X+123092Y+008601X0260Y    R180 S2      
017m1963                  -    MD0100PA00X+123092Y+008601                       
327m1963            R1701 -1          A01X+123092Y+008882X0198Y0197R090 S1      
327m1963            U136  -5          A01X+122780Y+008185X0240Y0460R180 S1      
317m1964            J3    -A9   D0122PA00X+017917Y+162240X0282Y    R180 S3      
317m1964            VIA   -    M      A01X+023375Y+153975X0200Y         S2      
017m1964            VIA   -    M      A18X+023375Y+153975X0260Y         S2      
017m1964                  -    MD0100PA00X+023375Y+153975                       
327m1964            R1826 -1          A01X+023375Y+153729X0198Y0197R270 S1      
317SMB_MB_BMC_SDA   J12   -A9   D0122PA00X+052563Y+162240X0282Y    R180 S3      
317SMB_MB_BMC_SDA   VIA   -    M      A01X+055758Y+154341X0200Y         S2      
017SMB_MB_BMC_SDA   VIA   -    M      A18X+055758Y+154341X0260Y         S2      
017SMB_MB_BMC_SDA         -    MD0100PA00X+055758Y+154341                       
327SMB_MB_BMC_SDA   R4106 -1          A01X+055879Y+153768X0198Y0197R270 S1      
317m1965            VIA   -    M      A01X+079028Y+028742X0200Y         S2      
017m1965            VIA   -    M      A18X+079028Y+028742X0260Y         S2      
017m1965                  -    MD0100PA00X+079028Y+028742                       
327m1965            R1584 -1          A01X+053876Y+036372X0198Y0197R180 S1      
327m1965            R1569 -2   M      A01X+054561Y+036372X0198Y0197R180 S1      
317m1965            VIA   -    MD0100PA00X+076898Y+008605X0200Y    R180 S0      
327m1965            U132  -6          A01X+076786Y+008185X0170Y0460R180 S1      
327m1965            R1683 -1          A01X+076993Y+008873X0198Y0197R090 S1      
317m1966            J3    -R9   D0122PA00X+017917Y+149445X0282Y    R180 S3      
317m1966            VIA   -    MD0100PA00X+039538Y+148578X0200Y         S0      
327m1966            R1831 -1          A18X+039156Y+148578X0198Y0197     S2      
317m1966            VIA   -    M      A01X+023076Y+150505X0200Y         S2      
017m1966            VIA   -    M      A18X+023076Y+150505X0260Y         S2      
017m1966                  -    MD0100PA00X+023076Y+150505                       
317m1967            J11   -Z2   D0122PA00X+029177Y+145272X0282Y    R180 S3      
317m1967            VIA   -    M      A01X+023331Y+147670X0200Y         S2      
017m1967            VIA   -    M      A18X+023331Y+147670X0260Y         S2      
017m1967                  -    MD0100PA00X+023331Y+147670                       
327m1967            R1822 -1          A01X+023062Y+147844X0198Y0197R180 S1      
327m1968            R6059 -2          A01X+054539Y+014125X0198Y0197     S1      
327m1968            U386  -1          A01X+056573Y+014265X0240Y0240     S1      
317m1968            VIA   -    MD0100PA00X+054831Y+014125X0200Y         S0      
317m1968            VIA   -    M      A01X+059335Y+024430X0200Y    R090 S2      
017m1968            VIA   -    M      A18X+059335Y+024430X0260Y    R090 S2      
017m1968                  -    MD0100PA00X+059335Y+024430                       
327m1968            U6    -B17        A01X+136572Y+089444X0160Y         S1      
317m1968            VIA   -    MD0100PA00X+136700Y+090050X0200Y         S0      
317m1968            VIA   -    MD0100PA00X+059211Y+089561X0200Y         S0      
327m1968            R4487 -2          A01X+059335Y+024168X0198Y0197     S1      
317m1969            VIA   -    M      A01X+068286Y+033948X0200Y         S2      
017m1969            VIA   -    M      A18X+068286Y+033948X0260Y         S2      
017m1969                  -    MD0100PA00X+068286Y+033948                       
327m1969            R1582 -1          A01X+053876Y+035922X0198Y0197R180 S1      
327m1969            R1565 -2   M      A01X+054561Y+035922X0198Y0197R180 S1      
317m1969            VIA   -    MD0100PA00X+066306Y+008573X0200Y    R180 S0      
327m1969            R1672 -1          A01X+066362Y+008880X0198Y0197R090 S1      
327m1969            U131  -7          A01X+066294Y+008185X0170Y0460R180 S1      
317m1970            J3    -S9   D0122PA00X+017917Y+148933X0282Y    R180 S3      
317m1970            VIA   -    MD0100PA00X+039520Y+148222X0200Y         S0      
327m1970            R1832 -1          A18X+039095Y+148224X0198Y0197     S2      
317m1970            VIA   -    M      A01X+022614Y+150244X0200Y         S2      
017m1970            VIA   -    M      A18X+022614Y+150244X0260Y         S2      
017m1970                  -    MD0100PA00X+022614Y+150244                       
327m1971            U6    -G15        A01X+135942Y+087869X0160Y         S1      
317m1971            VIA   -    MD0100PA00X+136100Y+088026X0180Y         S0      
327m1971            R6071 -2          A01X+075011Y+014125X0198Y0197     S1      
327m1971            U388  -1          A01X+077045Y+014265X0240Y0240     S1      
317m1971            VIA   -    MD0100PA00X+075304Y+014125X0200Y         S0      
317m1971            VIA   -    M      A01X+079808Y+024430X0200Y    R090 S2      
017m1971            VIA   -    M      A18X+079808Y+024430X0260Y    R090 S2      
017m1971                  -    MD0100PA00X+079808Y+024430                       
327m1971            R4494 -2          A01X+079808Y+024168X0198Y0197     S1      
317m1971            VIA   -    MD0100PA00X+096931Y+083933X0200Y         S0      
317m1971            VIA   -    MD0100PA00X+096751Y+086897X0200Y         S0      
317m1971            VIA   -    MD0100PA00X+071290Y+082160X0200Y         S0      
317TP_PEX0_TDO      VIA   -    MD0080PA00X+021427Y+121545X0160Y    R180 S0      
327TP_PEX0_TDO      VIA   -           A18X+021240Y+121732X0260Y         S2      
327TP_PEX0_TDO      PEX0  -L19        A01X+021240Y+121732X0180Y         S1      
327m1972            U130  -7          A01X+056057Y+008185X0170Y0460R180 S1      
327m1972            R1671 -1          A01X+056126Y+008880X0198Y0197R090 S1      
317m1972            VIA   -    MD0100PA00X+056070Y+008573X0200Y    R180 S0      
317m1972            VIA   -    M      A01X+057819Y+033639X0200Y         S2      
017m1972            VIA   -    M      A18X+057819Y+033639X0260Y         S2      
017m1972                  -    MD0100PA00X+057819Y+033639                       
327m1972            R1578 -1          A01X+053876Y+035022X0198Y0197R180 S1      
327m1972            R1563 -2   M      A01X+054561Y+035022X0198Y0197R180 S1      
317m1973            J3    -F9   D0122PA00X+017917Y+159681X0282Y    R180 S3      
317m1973            VIA   -    M      A01X+021998Y+153080X0200Y    R090 S2      
017m1973            VIA   -    M      A18X+021998Y+153080X0260Y    R090 S2      
017m1973                  -    MD0100PA00X+021998Y+153080                       
327m1973            R1829 -1          A01X+022947Y+152658X0198Y0197     S1      
327SSD3_PWRDIS      VIA   -    M      A18X+134850Y+091350X0260Y         S2      
327SSD3_PWRDIS      R3537 -2          A18X+134650Y+091792X0198Y0197R090 S2      
327SSD3_PWRDIS      U6    -D13        A01X+135312Y+088814X0160Y         S1      
317SSD3_PWRDIS      VIA   -    MD0100PA00X+135470Y+088971X0180Y         S0      
327P12V_SSD1_OCP    PR213 -1          A01X+020420Y+021286X0198Y0197     S1      
327P12V_SSD1_OCP    PU32  -9          A01X+019743Y+021317X0110Y0240R270 S1      
317P12V_SSD1_OCP    VIA   -    M      A01X+020139Y+021246X0200Y         S2      
017P12V_SSD1_OCP    VIA   -    M      A18X+020139Y+021246X0260Y         S2      
017P12V_SSD1_OCP          -    MD0100PA00X+020139Y+021246                       
317TP_PEX0_TDI      VIA   -    MD0080PA00X+020305Y+121545X0160Y    R090 S0      
327TP_PEX0_TDI      PEX0  -L17        A01X+020492Y+121732X0180Y         S1      
327TP_PEX0_TDI      VIA   -           A18X+020492Y+121732X0260Y         S2      
317m1974            VIA   -    M      A01X+086779Y+008573X0200Y    R180 S2      
017m1974            VIA   -    M      A18X+086779Y+008573X0260Y    R180 S2      
017m1974                  -    MD0100PA00X+086779Y+008573                       
327m1974            U133  -7          A01X+086766Y+008185X0170Y0460R180 S1      
327m1974            R1686 -1          A01X+086834Y+008880X0198Y0197R090 S1      
317m1974            VIA   -    MD0100PA00X+087205Y+030264X0200Y         S0      
327m1974            R1590 -1          A01X+053876Y+037722X0198Y0197R180 S1      
327m1974            R1572 -2   M      A01X+054561Y+037722X0198Y0197R180 S1      
327m1975            C4017 -2          A01X+022994Y+154631X0198Y0197R270 S1      
317m1975            J3    -C9   D0122PA00X+017917Y+161217X0282Y    R180 S3      
317m1975            VIA   -    M      A01X+022788Y+154082X0200Y         S2      
017m1975            VIA   -    M      A18X+022788Y+154082X0260Y         S2      
017m1975                  -    MD0100PA00X+022788Y+154082                       
327m1975            R1827 -2          A01X+022975Y+153729X0198Y0197R090 S1      
317m1976            VIA   -    M      A01X+134985Y+093676X0200Y         S2      
017m1976            VIA   -    M      A18X+134985Y+093676X0260Y         S2      
017m1976                  -    MD0100PA00X+134985Y+093676                       
327m1976            R3584 -1          A01X+134995Y+094603X0198Y0197R090 S1      
317m1976            VIA   -    MD0100PA00X+134210Y+088656X0180Y         S0      
327m1976            U6    -E10        A01X+134368Y+088499X0160Y         S1      
327m1977            VIA   -    M      A01X+090165Y+090384X0300Y    R090 S1      
327m1977            R4536 -2          A01X+090370Y+090952X0198Y0197R270 S1      
327m1977            U5    -T9         A01X+090184Y+088466X0160Y    R180 S1      
317TP_PEX0_TCK      VIA   -    MD0080PA00X+019557Y+121545X0160Y         S0      
327TP_PEX0_TCK      VIA   -           A18X+019370Y+121732X0260Y         S2      
327TP_PEX0_TCK      PEX0  -M15        A01X+019744Y+121358X0180Y         S1      
317m1978            VIA   -    M      A01X+078646Y+029303X0200Y         S2      
017m1978            VIA   -    M      A18X+078646Y+029303X0260Y         S2      
017m1978                  -    MD0100PA00X+078646Y+029303                       
327m1978            R1586 -1          A01X+053876Y+036822X0198Y0197R180 S1      
327m1978            R1570 -2   M      A01X+054561Y+036822X0198Y0197R180 S1      
327m1978            U132  -7          A01X+076530Y+008185X0170Y0460R180 S1      
327m1978            R1685 -1          A01X+076598Y+008880X0198Y0197R090 S1      
317m1978            VIA   -    MD0100PA00X+076542Y+008573X0200Y    R180 S0      
317GPU_BASE_ID0_R   J3    -G9   D0122PA00X+017917Y+159169X0282Y    R180 S3      
317GPU_BASE_ID0_R   VIA   -    M      A01X+022697Y+152258X0200Y    R090 S2      
017GPU_BASE_ID0_R   VIA   -    M      A18X+022697Y+152258X0260Y    R090 S2      
017GPU_BASE_ID0_R         -    MD0100PA00X+022697Y+152258                       
327GPU_BASE_ID0_R   R1830 -1          A01X+022947Y+152258X0198Y0197     S1      
317m1979            VIA   -    M      A01X+129756Y+097022X0200Y         S2      
017m1979            VIA   -    M      A18X+129756Y+097022X0260Y         S2      
017m1979                  -    MD0100PA00X+129756Y+097022                       
327m1979            J56   -2          A01X+128732Y+099963X0500Y1350R090 S1      
327m1979            R4047 -2   M      A01X+129650Y+096708X0198Y0197R090 S1      
317m1979            VIA   -    MD0100PA00X+132950Y+088971X0180Y         S0      
327m1979            U6    -D6         A01X+133108Y+088814X0160Y         S1      
317m1980            VIA   -    MD0100PA00X+137675Y+084877X0180Y         S0      
327m1980            U6    -T20        A01X+137517Y+085034X0160Y         S1      
317m1980            VIA   -    M      A01X+140550Y+083600X0200Y         S2      
017m1980            VIA   -    M      A18X+140550Y+083600X0260Y         S2      
017m1980                  -    MD0100PA00X+140550Y+083600                       
327m1980            R4095 -2          A01X+140792Y+083600X0198Y0197R180 S1      
317TP_PEX0_TRST_L   VIA   -    MD0080PA00X+020866Y+121358X0160Y         S0      
327TP_PEX0_TRST_L   VIA   -    M      A18X+021614Y+121358X0260Y         S2      
327TP_PEX0_TRST_L   R1256 -1          A18X+022395Y+121388X0198Y0197R270 S2      
327TP_PEX0_TRST_L   PEX0  -M18        A01X+020866Y+121358X0180Y         S1      
317m1981            VIA   -    M      A01X+053164Y+034906X0200Y         S2      
017m1981            VIA   -    M      A18X+053164Y+034906X0260Y         S2      
017m1981                  -    MD0100PA00X+053164Y+034906                       
327m1981            R1578 -2          A01X+053561Y+035022X0198Y0197R180 S1      
327m1981            U124  -14         A01X+052387Y+035921X0120Y0630R270 S1      
317PRSNT_GPU_N      VIA   -    MD0100PA00X+041100Y+145750X0200Y         S0      
317PRSNT_GPU_N      VIA   -    M      A01X+024491Y+153939X0200Y         S2      
017PRSNT_GPU_N      VIA   -    M      A18X+024491Y+153939X0260Y         S2      
017PRSNT_GPU_N            -    MD0100PA00X+024491Y+153939                       
317PRSNT_GPU_N      J3    -A7   D0122PA00X+016185Y+162240X0282Y    R180 S3      
327PRSNT_GPU_N      C4014 -2          A01X+024494Y+154631X0198Y0197R270 S1      
317PRSNT_GPU_N      VIA   -    MD0100PA00X+129250Y+092800X0200Y         S0      
317PRSNT_GPU_N      VIA   -    MD0100PA00X+106968Y+093339X0200Y         S0      
317PRSNT_GPU_N      VIA   -    MD0100PA00X+079346Y+142916X0200Y         S0      
327PRSNT_GPU_N      Q19   -2          A01X+129250Y+093096X0160Y0240     S1      
317m1982            VIA   -    MD0100PA00X+135785Y+088026X0180Y         S0      
327m1982            U6    -G14        A01X+135628Y+087869X0160Y         S1      
327m1982            R6058 -2          A01X+044302Y+014125X0198Y0197     S1      
327m1982            U387  -1          A01X+046337Y+014265X0240Y0240     S1      
317m1982            VIA   -    MD0100PA00X+044595Y+014125X0200Y         S0      
317m1982            VIA   -    M      A01X+049099Y+024430X0200Y    R090 S2      
017m1982            VIA   -    M      A18X+049099Y+024430X0260Y    R090 S2      
017m1982                  -    MD0100PA00X+049099Y+024430                       
317m1982            VIA   -    MD0100PA00X+055862Y+073253X0200Y         S0      
327m1982            R4483 -2          A01X+049099Y+024168X0198Y0197     S1      
327P12V_SSD3_OCP    PR221 -1          A01X+040893Y+021286X0198Y0197     S1      
327P12V_SSD3_OCP    PU36  -9          A01X+040215Y+021317X0110Y0240R270 S1      
317P12V_SSD3_OCP    VIA   -    M      A01X+040612Y+021246X0200Y         S2      
017P12V_SSD3_OCP    VIA   -    M      A18X+040612Y+021246X0260Y         S2      
017P12V_SSD3_OCP          -    MD0100PA00X+040612Y+021246                       
317m1983            VIA   -    MD0080PA00X+165659Y+114439X0160Y         S0      
317m1983            VIA   -    MD0100PA00X+153059Y+097995X0200Y         S0      
327m1983            PEX3  -AK39       A01X+165846Y+114626X0180Y         S1      
327m1983            VIA   -    M      A18X+166782Y+106464X0260Y         S2      
317m1983            VIA   -    MD0100PA00X+165341Y+099059X0200Y         S0      
327m1983            R938  -1          A18X+151342Y+097524X0198Y0197R090 S2      
327m1983            R942  -2   M      A18X+151742Y+097524X0198Y0197R270 S2      
317TP_PEX0_TMS      VIA   -    MD0080PA00X+021427Y+121171X0160Y         S0      
327TP_PEX0_TMS      VIA   -           A18X+021240Y+120984X0260Y         S2      
327TP_PEX0_TMS      PEX0  -M20        A01X+021614Y+121358X0180Y         S1      
317m1984            VIA   -    M      A01X+053014Y+037606X0200Y         S2      
017m1984            VIA   -    M      A18X+053014Y+037606X0260Y         S2      
017m1984                  -    MD0100PA00X+053014Y+037606                       
327m1984            U124  -20         A01X+052387Y+037457X0120Y0630R270 S1      
327m1984            R1590 -2          A01X+053561Y+037722X0198Y0197R180 S1      
327SSD4_PWRDIS      VIA   -    M      A01X+136100Y+091150X0300Y         S1      
327SSD4_PWRDIS      R3552 -2          A01X+135850Y+091992X0198Y0197R270 S1      
327SSD4_PWRDIS      U6    -A15        A01X+135942Y+089759X0160Y         S1      
327m1985            VIA   -    M      A01X+089910Y+089932X0300Y    R090 S1      
327m1985            R4538 -2          A01X+090020Y+090952X0198Y0197R270 S1      
327m1985            U5    -R9         A01X+090184Y+088151X0160Y    R180 S1      
327P12V_SSD9_OCP    PR229 -1          A01X+111838Y+021286X0198Y0197     S1      
327P12V_SSD9_OCP    PU40  -9          A01X+111160Y+021317X0110Y0240R270 S1      
317P12V_SSD9_OCP    VIA   -    M      A01X+111557Y+021246X0200Y         S2      
017P12V_SSD9_OCP    VIA   -    M      A18X+111557Y+021246X0260Y         S2      
017P12V_SSD9_OCP          -    MD0100PA00X+111557Y+021246                       
317m1986            VIA   -    M      A01X+053312Y+037186X0200Y         S2      
017m1986            VIA   -    M      A18X+053312Y+037186X0260Y         S2      
017m1986                  -    MD0100PA00X+053312Y+037186                       
327m1986            R1588 -2          A01X+053561Y+037272X0198Y0197R180 S1      
327m1986            U124  -19         A01X+052387Y+037201X0120Y0630R270 S1      
317PRSNT_GPU_D_N    J3    -Z2   D0122PA00X+011854Y+145272X0282Y    R180 S3      
317PRSNT_GPU_D_N    VIA   -    M      A01X+022576Y+147198X0200Y         S2      
017PRSNT_GPU_D_N    VIA   -    M      A18X+022576Y+147198X0260Y         S2      
017PRSNT_GPU_D_N          -    MD0100PA00X+022576Y+147198                       
327PRSNT_GPU_D_N    R1822 -2          A01X+022747Y+147844X0198Y0197R180 S1      
327PRSNT_GPU_D_N    C4009 -2   M      A01X+022747Y+147452X0198Y0197R180 S1      
327SSD2_CLK_EN_N    U6    -C5         A01X+132793Y+089129X0160Y         S1      
317SSD2_CLK_EN_N    VIA   -    MD0100PA00X+132636Y+089286X0180Y         S0      
327SSD2_CLK_EN_N    R3527 -1          A01X+136995Y+094603X0198Y0197R090 S1      
317SSD2_CLK_EN_N    VIA   -    M      A01X+136995Y+094360X0200Y         S2      
017SSD2_CLK_EN_N    VIA   -    M      A18X+136995Y+094360X0260Y         S2      
017SSD2_CLK_EN_N          -    MD0100PA00X+136995Y+094360                       
317m1987            VIA   -    MD0100PA00X+137360Y+084877X0180Y         S0      
327m1987            U6    -T19        A01X+137202Y+085034X0160Y         S1      
317m1987            VIA   -    MD0100PA00X+147679Y+069145X0200Y         S0      
327m1987            R4714 -2   M      A01X+148508Y+068963X0198Y0197     S1      
327m1987            R4666 -2          A01X+148508Y+068163X0198Y0197     S1      
327m1987            R4679 -1   M      A01X+148508Y+068563X0198Y0197R180 S1      
317m1987            VIA   -    M      A01X+145198Y+069384X0200Y         S2      
017m1987            VIA   -    M      A18X+145198Y+069384X0260Y         S2      
017m1987                  -    MD0100PA00X+145198Y+069384                       
327P12V_SSD11_OCP   PR237 -1          A01X+132310Y+021286X0198Y0197     S1      
327P12V_SSD11_OCP   PU44  -9          A01X+131633Y+021317X0110Y0240R270 S1      
317P12V_SSD11_OCP   VIA   -    M      A01X+132029Y+021246X0200Y         S2      
017P12V_SSD11_OCP   VIA   -    M      A18X+132029Y+021246X0260Y         S2      
017P12V_SSD11_OCP         -    MD0100PA00X+132029Y+021246                       
327m1988            VIA   -    M      A18X+121260Y+111260X0260Y         S2      
327m1988            PEX2  -AK39       A01X+120138Y+114626X0180Y         S1      
317m1988            VIA   -    MD0080PA00X+119951Y+114439X0160Y         S0      
317m1988            VIA   -    MD0100PA00X+124630Y+102780X0200Y         S0      
317m1988            VIA   -    MD0100PA00X+152500Y+097432X0200Y         S0      
327m1988            R937  -1          A18X+153324Y+097465X0198Y0197R090 S2      
327m1988            R941  -2   M      A18X+152836Y+097467X0198Y0197R270 S2      
317m1989            VIA   -    M      A01X+053321Y+036475X0200Y         S2      
017m1989            VIA   -    M      A18X+053321Y+036475X0260Y         S2      
017m1989                  -    MD0100PA00X+053321Y+036475                       
327m1989            U124  -17         A01X+052387Y+036689X0120Y0630R270 S1      
327m1989            R1584 -2          A01X+053561Y+036372X0198Y0197R180 S1      
317m1990            VIA   -    M      A01X+112466Y+009428X0200Y         S2      
017m1990            VIA   -    M      A18X+112466Y+009428X0260Y         S2      
017m1990                  -    MD0100PA00X+112466Y+009428                       
317m1990            VIA   -    MD0100PA00X+112288Y+006044X0200Y         S0      
327m1990            R1692 -2          A01X+110810Y+008058X0198Y0197R180 S1      
327m1990            R1696 -2   M      A01X+111129Y+007659X0198Y0197     S1      
327m1990            U135  -3   M      A01X+112258Y+006472X0170Y0460R180 S1      
327m1990            R1698 -2          A01X+112466Y+009188X0198Y0197R090 S1      
317m1991            J3    -D9   D0122PA00X+017917Y+160705X0282Y    R180 S3      
317m1991            VIA   -    M      A01X+022212Y+153994X0200Y         S2      
017m1991            VIA   -    M      A18X+022212Y+153994X0260Y         S2      
017m1991                  -    MD0100PA00X+022212Y+153994                       
327m1991            R1828 -1          A01X+022575Y+153729X0198Y0197R270 S1      
327m1992            U6    -D8         A01X+133738Y+088814X0160Y         S1      
317m1992            VIA   -    MD0100PA00X+133580Y+088971X0180Y         S0      
327m1992            R3940 -1          A01X+080684Y+113713X0198Y0197R090 S1      
317m1992            VIA   -    MD0100PA00X+080684Y+113473X0200Y         S0      
317m1992            VIA   -    M      A01X+081389Y+083515X0200Y         S2      
017m1992            VIA   -    M      A18X+081389Y+083515X0260Y         S2      
017m1992                  -    MD0100PA00X+081389Y+083515                       
327NIC6_CLK_EN_N    R4087 -1          A01X+140792Y+086000X0198Y0197     S1      
317NIC6_CLK_EN_N    VIA   -    M      A01X+140550Y+086000X0200Y         S2      
017NIC6_CLK_EN_N    VIA   -    M      A18X+140550Y+086000X0260Y         S2      
017NIC6_CLK_EN_N          -    MD0100PA00X+140550Y+086000                       
317NIC6_CLK_EN_N    VIA   -    MD0100PA00X+137045Y+085822X0180Y         S0      
327NIC6_CLK_EN_N    U6    -N18        A01X+136887Y+085979X0160Y         S1      
327P12V_SSD3_SS     PU36  -7          A01X+040215Y+020923X0110Y0240R270 S1      
327P12V_SSD3_SS     PC398 -1          A01X+040893Y+020086X0180Y0200R180 S1      
317P12V_SSD3_SS     VIA   -    M      A01X+040603Y+020086X0200Y         S2      
017P12V_SSD3_SS     VIA   -    M      A18X+040603Y+020086X0260Y         S2      
017P12V_SSD3_SS           -    MD0100PA00X+040603Y+020086                       
327P12V_SSD14_OCP   PR234 -1          A01X+167783Y+021286X0198Y0197     S1      
327P12V_SSD14_OCP   PU43  -9          A01X+167105Y+021317X0110Y0240R270 S1      
317P12V_SSD14_OCP   VIA   -    M      A01X+167502Y+021246X0200Y         S2      
017P12V_SSD14_OCP   VIA   -    M      A18X+167502Y+021246X0260Y         S2      
017P12V_SSD14_OCP         -    MD0100PA00X+167502Y+021246                       
317m1993            VIA   -    M      A01X+053161Y+035427X0200Y         S2      
017m1993            VIA   -    M      A18X+053161Y+035427X0260Y         S2      
017m1993                  -    MD0100PA00X+053161Y+035427                       
327m1993            R1580 -2          A01X+053561Y+035472X0198Y0197R180 S1      
327m1993            U124  -15         A01X+052387Y+036177X0120Y0630R270 S1      
327m1994            VIA   -    M      A18X+020804Y+151652X0160Y0041R270 S2      
317m1994            VIA   -    MD0100PA00X+021791Y+143045X0200Y         S0      
327m1994            R6734 -2   M      A01X+021419Y+142906X0180Y0200R270 S1      
327m1994            R5453 -2          A01X+021419Y+142906X0180Y0200R090 S1      
317m1994            J3    -L9   D0122PA00X+017917Y+156610X0282Y    R180 S3      
327m1995            VIA   -    M      A18X+137450Y+091200X0260Y         S2      
327m1995            R3595 -2          A18X+137050Y+091792X0198Y0197R090 S2      
327m1995            U6    -C19        A01X+137202Y+089129X0160Y         S1      
317m1995            VIA   -    MD0100PA00X+137360Y+089286X0180Y         S0      
317m1996            VIA   -    MD0100PA00X+137045Y+085192X0180Y         S0      
327m1996            U6    -R18        A01X+136887Y+085349X0160Y         S1      
317m1996            VIA   -    MD0100PA00X+145516Y+076371X0200Y         S0      
317m1996            VIA   -    M      A01X+149963Y+078779X0200Y         S2      
017m1996            VIA   -    M      A18X+149963Y+078779X0260Y         S2      
017m1996                  -    MD0100PA00X+149963Y+078779                       
327m1996            R4696 -2          A01X+150258Y+078100X0198Y0197     S1      
327m1996            R4671 -2   M      A01X+150258Y+078500X0198Y0197     S1      
327P12V_SSD7_SS     PU37  -7          A01X+085924Y+020923X0110Y0240R270 S1      
327P12V_SSD7_SS     PC399 -1          A01X+086602Y+020086X0180Y0200R180 S1      
317P12V_SSD7_SS     VIA   -    M      A01X+086312Y+020086X0200Y         S2      
017P12V_SSD7_SS     VIA   -    M      A18X+086312Y+020086X0260Y         S2      
017P12V_SSD7_SS           -    MD0100PA00X+086312Y+020086                       
317m1997            VIA   -    M      A01X+052639Y+035130X0200Y         S2      
017m1997            VIA   -    M      A18X+052639Y+035130X0260Y         S2      
017m1997                  -    MD0100PA00X+052639Y+035130                       
327m1997            R1576 -2          A01X+053561Y+034572X0198Y0197R180 S1      
327m1997            U124  -13         A01X+052387Y+035666X0120Y0630R270 S1      
317m1998            VIA   -    M      A01X+131315Y+093660X0200Y         S2      
017m1998            VIA   -    M      A18X+131315Y+093660X0260Y         S2      
017m1998                  -    MD0100PA00X+131315Y+093660                       
327m1998            U143  -4          A01X+130135Y+094822X0140Y0440R180 S1      
327m1998            R1789 -1          A01X+131315Y+093414X0198Y0197R270 S1      
327m1999            R4004 -1          A01X+172901Y+113713X0198Y0197R090 S1      
317m1999            VIA   -    MD0100PA00X+172901Y+113473X0200Y         S0      
317m1999            VIA   -    MD0100PA00X+176020Y+099248X0200Y         S0      
317m1999            VIA   -    M      A01X+144070Y+098176X0200Y         S2      
017m1999            VIA   -    M      A18X+144070Y+098176X0260Y         S2      
017m1999                  -    MD0100PA00X+144070Y+098176                       
327m1999            U6    -C9         A01X+134053Y+089129X0160Y         S1      
317m1999            VIA   -    MD0100PA00X+133895Y+089286X0180Y         S0      
317m2000            VIA   -    M      A01X+144052Y+038275X0200Y         S2      
017m2000            VIA   -    M      A18X+144052Y+038275X0260Y         S2      
017m2000                  -    MD0100PA00X+144052Y+038275                       
317m2000            VIA   -    MD0100PA00X+137990Y+085192X0180Y         S0      
327m2000            U6    -R21        A01X+137832Y+085349X0160Y         S1      
317m2000            VIA   -    MD0100PA00X+164884Y+039050X0200Y         S0      
327m2000            R359  -2          A18X+165218Y+038800X0198Y0197     S2      
327m2000            R380  -1   M      A18X+164884Y+038800X0198Y0197     S2      
327m2001            PU40  -8          A01X+111160Y+021120X0110Y0240R270 S1      
317m2001            VIA   -    M      A01X+111550Y+020704X0200Y         S2      
017m2001            VIA   -    M      A18X+111550Y+020704X0260Y         S2      
017m2001                  -    MD0100PA00X+111550Y+020704                       
327m2001            R871  -2          A01X+111838Y+020486X0198Y0197R180 S1      
327m2001            R4468 -1   M      A01X+111838Y+020886X0198Y0197     S1      
317m2002            VIA   -    M      A01X+052881Y+036916X0200Y         S2      
017m2002            VIA   -    M      A18X+052881Y+036916X0260Y         S2      
017m2002                  -    MD0100PA00X+052881Y+036916                       
327m2002            R1586 -2          A01X+053561Y+036822X0198Y0197R180 S1      
327m2002            U124  -18         A01X+052387Y+036945X0120Y0630R270 S1      
317m2003            VIA   -    M      A01X+130910Y+091700X0200Y         S2      
017m2003            VIA   -    M      A18X+130910Y+091700X0260Y         S2      
017m2003                  -    MD0100PA00X+130910Y+091700                       
327m2003            R1789 -2          A01X+131315Y+093099X0198Y0197R270 S1      
327m2003            R1787 -2   M      A01X+130910Y+093099X0198Y0197R270 S1      
327m2003            U6    -A2         A01X+131848Y+089759X0160Y         S1      
317m2004            VIA   -    MD0100PA00X+046340Y+084687X0200Y         S0      
317m2004            VIA   -    MD0100PA00X+135150Y+090650X0200Y         S0      
327m2004            U6    -B13        A01X+135312Y+089444X0160Y         S1      
317m2004            VIA   -    M      A01X+034099Y+024430X0200Y    R090 S2      
017m2004            VIA   -    M      A18X+034099Y+024430X0260Y    R090 S2      
017m2004                  -    MD0100PA00X+034099Y+024430                       
327m2004            R4495 -2          A01X+034099Y+024168X0198Y0197     S1      
317m2004            VIA   -    MD0100PA00X+029595Y+014125X0200Y         S0      
327m2004            U384  -1          A01X+031337Y+014265X0240Y0240     S1      
327m2004            R5883 -2          A01X+029302Y+014125X0198Y0197     S1      
317m2005            VIA   -    M      A01X+099355Y+031818X0200Y    R270 S2      
017m2005            VIA   -    M      A18X+099355Y+031818X0260Y    R270 S2      
017m2005                  -    MD0100PA00X+099355Y+031818                       
327m2005            Y6    -3          A01X+097676Y+032027X0480Y0590R180 S1      
327m2005            C2637 -1   M      A01X+099040Y+031818X0198Y0197R090 S1      
327m2005            U113  -B11        A01X+101005Y+032207X0110Y0180R090 S1      
317m2006            VIA   -    M      A01X+053266Y+035956X0200Y         S2      
017m2006            VIA   -    M      A18X+053266Y+035956X0260Y         S2      
017m2006                  -    MD0100PA00X+053266Y+035956                       
327m2006            R1582 -2          A01X+053561Y+035922X0198Y0197R180 S1      
327m2006            U124  -16         A01X+052387Y+036433X0120Y0630R270 S1      
317m2007            VIA   -    MD0100PA00X+081484Y+113473X0200Y         S0      
327m2007            R3939 -1          A01X+081484Y+113713X0198Y0197R090 S1      
317m2007            VIA   -    M      A01X+081430Y+084088X0200Y         S2      
017m2007            VIA   -    M      A18X+081430Y+084088X0260Y         S2      
017m2007                  -    MD0100PA00X+081430Y+084088                       
327m2007            U6    -C8         A01X+133738Y+089129X0160Y         S1      
317m2007            VIA   -    MD0100PA00X+133580Y+089286X0180Y         S0      
327m2008            PU45  -8          A01X+177341Y+021120X0110Y0240R270 S1      
317m2008            VIA   -    M      A01X+177731Y+020704X0200Y         S2      
017m2008            VIA   -    M      A18X+177731Y+020704X0260Y         S2      
017m2008                  -    MD0100PA00X+177731Y+020704                       
327m2008            R877  -2          A01X+178019Y+020486X0198Y0197R180 S1      
327m2008            R4473 -1   M      A01X+178019Y+020886X0198Y0197     S1      
317m2009            VIA   -    M      A01X+049088Y+038257X0200Y         S2      
017m2009            VIA   -    M      A18X+049088Y+038257X0260Y         S2      
017m2009                  -    MD0100PA00X+049088Y+038257                       
327m2009            R1575 -2          A01X+048848Y+038259X0198Y0197     S1      
327m2009            U124  -4          A01X+050182Y+037713X0120Y0630R270 S1      
317m2010            VIA   -    M      A01X+130088Y+093714X0200Y         S2      
017m2010            VIA   -    M      A18X+130088Y+093714X0260Y         S2      
017m2010                  -    MD0100PA00X+130088Y+093714                       
327m2010            R1788 -1          A01X+130088Y+093414X0198Y0197R270 S1      
327m2010            U143  -6          A01X+130647Y+094822X0140Y0440R180 S1      
327m2011            R4758 -2          A01X+139458Y+070300X0198Y0197     S1      
327m2011            R4743 -1          A01X+139942Y+069900X0198Y0197     S1      
327m2011            R4728 -2   M      A01X+139942Y+070300X0198Y0197R180 S1      
317m2011            VIA   -    MD0100PA00X+139700Y+070300X0200Y    R180 S0      
317m2011            VIA   -    M      A01X+143893Y+071636X0200Y         S2      
017m2011            VIA   -    M      A18X+143893Y+071636X0260Y         S2      
017m2011                  -    MD0100PA00X+143893Y+071636                       
317m2011            VIA   -    MD0100PA00X+137990Y+083932X0180Y         S0      
327m2011            U6    -W21        A01X+137832Y+084089X0160Y         S1      
317m2012            VIA   -    M      A01X+100110Y+031801X0200Y    R270 S2      
017m2012            VIA   -    M      A18X+100110Y+031801X0260Y    R270 S2      
017m2012                  -    MD0100PA00X+100110Y+031801                       
327m2012            R1045 -2          A01X+099775Y+031465X0198Y0197     S1      
327m2012            U113  -A13        A01X+100709Y+032109X0070Y0220R090 S1      
317m2013            VIA   -    M      A01X+049184Y+035109X0200Y         S2      
017m2013            VIA   -    M      A18X+049184Y+035109X0260Y         S2      
017m2013                  -    MD0100PA00X+049184Y+035109                       
327m2013            R1589 -2          A01X+048838Y+034800X0198Y0197     S1      
327m2013            U124  -11         A01X+050182Y+035921X0120Y0630R270 S1      
317m2014            VIA   -    M      A01X+130495Y+092855X0200Y         S2      
017m2014            VIA   -    M      A18X+130495Y+092855X0260Y         S2      
017m2014                  -    MD0100PA00X+130495Y+092855                       
327m2014            R1788 -2          A01X+130088Y+093099X0198Y0197R270 S1      
327m2014            R1786 -2   M      A01X+130495Y+093099X0198Y0197R270 S1      
327m2014            U6    -B1         A01X+131533Y+089444X0160Y         S1      
317m2015            VIA   -    M      A01X+109378Y+159957X0200Y    R090 S2      
017m2015            VIA   -    M      A18X+109378Y+159957X0260Y    R090 S2      
017m2015                  -    MD0100PA00X+109378Y+159957                       
327m2015            R1819 -2          A01X+109490Y+159636X0198Y0197R090 S1      
327m2015            U308  -6          A01X+109373Y+160695X0140Y0520R180 S1      
317m2016            VIA   -    MD0100PA00X+034975Y+113473X0200Y         S0      
327m2016            R3892 -1          A01X+034975Y+113713X0198Y0197R090 S1      
317m2016            VIA   -    MD0100PA00X+036807Y+092514X0200Y         S0      
317m2016            VIA   -    M      A01X+037151Y+081530X0200Y         S2      
017m2016            VIA   -    M      A18X+037151Y+081530X0260Y         S2      
017m2016                  -    MD0100PA00X+037151Y+081530                       
327m2016            U6    -D7         A01X+133423Y+088814X0160Y         S1      
317m2016            VIA   -    MD0100PA00X+133265Y+088971X0180Y         S0      
317m2017            VIA   -    M      A01X+145450Y+077758X0200Y         S2      
017m2017            VIA   -    M      A18X+145450Y+077758X0260Y         S2      
017m2017                  -    MD0100PA00X+145450Y+077758                       
317m2017            VIA   -    MD0100PA00X+137990Y+084877X0180Y         S0      
327m2017            U6    -T21        A01X+137832Y+085034X0160Y         S1      
317m2017            VIA   -    MD0100PA00X+149309Y+082044X0200Y         S0      
327m2017            R4602 -2   M      A01X+150258Y+082100X0198Y0197     S1      
327m2017            R4615 -1          A01X+150258Y+081300X0198Y0197R180 S1      
327m2017            R4632 -2   M      A01X+150258Y+081700X0198Y0197     S1      
327P12V_SSD10_SS    PC434 -1          A01X+122074Y+020086X0198Y0197     S1      
327P12V_SSD10_SS    PU42  -7          A01X+121396Y+020923X0110Y0240R270 S1      
317P12V_SSD10_SS    VIA   -    M      A01X+121784Y+020086X0200Y         S2      
017P12V_SSD10_SS    VIA   -    M      A18X+121784Y+020086X0260Y         S2      
017P12V_SSD10_SS          -    MD0100PA00X+121784Y+020086                       
327m2018            VIA   -    M      A18X+144874Y+093559X0260Y         S2      
327m2018            U97   -3          A18X+145481Y+093559X0240Y0440R270 S2      
327m2018            R915  -1          A18X+144358Y+093150X0198Y0197     S2      
327m2018            R914  -1   M      A18X+144358Y+093600X0198Y0197     S2      
327m2019            VIA   -    M      A01X+103042Y+031048X0300Y    R090 S1      
327m2019            R1078 -1          A01X+102964Y+030583X0198Y0197R270 S1      
327m2019            U113  -A26        A01X+103121Y+031666X0070Y0220     S1      
317m2020            VIA   -    M      A01X+049602Y+036291X0200Y         S2      
017m2020            VIA   -    M      A18X+049602Y+036291X0260Y         S2      
017m2020                  -    MD0100PA00X+049602Y+036291                       
327m2020            R1585 -2          A01X+048848Y+036009X0198Y0197     S1      
327m2020            U124  -9          A01X+050182Y+036433X0120Y0630R270 S1      
327m2021            VIA   -    M      A18X+137260Y+090646X0260Y         S2      
327m2021            R3580 -2          A18X+136650Y+091792X0198Y0197R090 S2      
327m2021            U6    -D18        A01X+136887Y+088814X0160Y         S1      
317m2021            VIA   -    MD0100PA00X+137045Y+088971X0180Y         S0      
327m2022            VIA   -    M      A18X+075551Y+111260X0260Y         S2      
327m2022            PEX1  -AK39       A01X+074429Y+114626X0180Y         S1      
317m2022            VIA   -    MD0080PA00X+074242Y+114439X0160Y         S0      
317m2022            VIA   -    MD0100PA00X+148814Y+087284X0200Y         S0      
317m2022            VIA   -    MD0100PA00X+074241Y+098845X0200Y         S0      
327m2022            R930  -2          A18X+149199Y+087034X0198Y0197     S2      
327m2022            R926  -1   M      A18X+148814Y+087034X0198Y0197     S2      
327m2023            VIA   -    M      A18X+147250Y+093532X0260Y         S2      
327m2023            U97   -4          A18X+146583Y+093559X0240Y0440R270 S2      
327m2023            R911  -1          A18X+147712Y+093932X0198Y0197R180 S2      
327m2023            R913  -1   M      A18X+147712Y+093532X0198Y0197R180 S2      
327m2024            VIA   -    M      A01X+101366Y+031136X0300Y    R090 S1      
327m2024            R1081 -1          A01X+101664Y+030583X0198Y0197R270 S1      
327m2024            U113  -B14        A01X+101644Y+031961X0110Y0180     S1      
317m2025            VIA   -    M      A01X+049105Y+036542X0200Y         S2      
017m2025            VIA   -    M      A18X+049105Y+036542X0260Y         S2      
017m2025                  -    MD0100PA00X+049105Y+036542                       
327m2025            R1583 -2          A01X+048848Y+036459X0198Y0197     S1      
327m2025            U124  -8          A01X+050182Y+036689X0120Y0630R270 S1      
317RST_MB_BMC_R_N   VIA   -    M      A01X+109009Y+162830X0200Y    R090 S2      
017RST_MB_BMC_R_N   VIA   -    M      A18X+109009Y+162830X0260Y    R090 S2      
017RST_MB_BMC_R_N         -    MD0100PA00X+109009Y+162830                       
327RST_MB_BMC_R_N   R1817 -2          A01X+108947Y+163185X0198Y0197R270 S1      
327RST_MB_BMC_R_N   U308  -3          A01X+109373Y+162152X0140Y0520R180 S1      
317SMB_MB_BMC_SCL   J12   -D9   D0122PA00X+052563Y+160705X0282Y    R180 S3      
317SMB_MB_BMC_SCL   VIA   -    M      A01X+056397Y+154144X0200Y         S2      
017SMB_MB_BMC_SCL   VIA   -    M      A18X+056397Y+154144X0260Y         S2      
017SMB_MB_BMC_SCL         -    MD0100PA00X+056397Y+154144                       
327SMB_MB_BMC_SCL   R4105 -1          A01X+056279Y+153768X0198Y0197R270 S1      
317m2026            VIA   -    MD0100PA00X+143521Y+085404X0200Y         S0      
327m2026            U6    -P19        A01X+137202Y+085664X0160Y         S1      
317m2026            VIA   -    MD0100PA00X+137360Y+085507X0180Y         S0      
327m2026            R4633 -2          A01X+150258Y+082500X0198Y0197     S1      
327m2026            R4608 -2   M      A01X+150258Y+082900X0198Y0197     S1      
317m2026            VIA   -    M      A01X+148639Y+082530X0200Y    R180 S2      
017m2026            VIA   -    M      A18X+148639Y+082530X0260Y    R180 S2      
017m2026                  -    MD0100PA00X+148639Y+082530                       
327m2027            VIA   -    M      A18X+147200Y+092950X0260Y         S2      
327m2027            R912  -1          A18X+147712Y+092732X0198Y0197R180 S2      
327m2027            U97   -5          A18X+146583Y+093185X0240Y0440R270 S2      
327m2027            R910  -1   M      A18X+147712Y+093132X0198Y0197R180 S2      
327m2028            VIA   -    M      A01X+101882Y+031177X0300Y    R090 S1      
327m2028            U113  -B15        A01X+101841Y+031961X0110Y0180     S1      
327m2028            R1080 -1          A01X+102064Y+030583X0198Y0197R270 S1      
317PEX0_DFT_IDDT    VIA   -    M      A01X+011853Y+120774X0200Y    R315 S2      
017PEX0_DFT_IDDT    VIA   -    M      A18X+011853Y+120774X0260Y    R315 S2      
017PEX0_DFT_IDDT          -    MD0100PA00X+011853Y+120774                       
327PEX0_DFT_IDDT    R1241 -1          A01X+011742Y+120445X0198Y0197R225 S1      
327PEX0_DFT_IDDT    R1252 -2   M      A01X+011459Y+120728X0198Y0197R045 S1      
327PEX0_DFT_IDDT    PEX0  -M16        A01X+020118Y+121358X0180Y         S1      
317PEX0_DFT_IDDT    VIA   -    MD0080PA00X+020118Y+121358X0160Y         S0      
317m2029            VIA   -    M      A01X+049575Y+037753X0200Y         S2      
017m2029            VIA   -    M      A18X+049575Y+037753X0260Y         S2      
017m2029                  -    MD0100PA00X+049575Y+037753                       
327m2029            R1577 -2          A01X+048848Y+037809X0198Y0197     S1      
327m2029            U124  -5          A01X+050182Y+037457X0120Y0630R270 S1      
317MB_BIC_R_MON     VIA   -    M      A01X+110547Y+162945X0200Y    R090 S2      
017MB_BIC_R_MON     VIA   -    M      A18X+110547Y+162945X0260Y    R090 S2      
017MB_BIC_R_MON           -    MD0100PA00X+110547Y+162945                       
327MB_BIC_R_MON     R1815 -2          A01X+110547Y+163185X0198Y0197R270 S1      
327MB_BIC_R_MON     U308  -1          A01X+109885Y+162152X0140Y0520R180 S1      
317m2030            VIA   -    M      A01X+066702Y+020886X0200Y         S2      
017m2030            VIA   -    M      A18X+066702Y+020886X0260Y         S2      
017m2030                  -    MD0100PA00X+066702Y+020886                       
317m2030            VIA   -    MD0100PA00X+136300Y+090050X0200Y         S0      
317m2030            VIA   -    MD0100PA00X+071966Y+090490X0200Y         S0      
327m2030            U6    -A16        A01X+136257Y+089759X0160Y         S1      
327m2030            R4461 -2          A01X+066444Y+020886X0198Y0197     S1      
317m2030            VIA   -    MD0100PA00X+061744Y+025888X0200Y         S0      
327m2030            R5975 -2          A01X+057316Y+024208X0198Y0197R180 S1      
327m2031            R4715 -2          A01X+148508Y+069763X0198Y0197     S1      
327m2031            R4672 -2   M      A01X+148508Y+069363X0198Y0197     S1      
317m2031            VIA   -    M      A01X+142662Y+067411X0200Y         S2      
017m2031            VIA   -    M      A18X+142662Y+067411X0260Y         S2      
017m2031                  -    MD0100PA00X+142662Y+067411                       
317m2031            VIA   -    MD0100PA00X+137045Y+084877X0180Y         S0      
327m2031            U6    -T18        A01X+136887Y+085034X0160Y         S1      
327P12V_SSD4_SS     PU31  -7          A01X+055216Y+020923X0110Y0240R270 S1      
327P12V_SSD4_SS     PC363 -1          A01X+055893Y+020086X0180Y0200R180 S1      
317P12V_SSD4_SS     VIA   -    M      A01X+055603Y+020086X0200Y         S2      
017P12V_SSD4_SS     VIA   -    M      A18X+055603Y+020086X0260Y         S2      
017P12V_SSD4_SS           -    MD0100PA00X+055603Y+020086                       
327m2032            PU44  -8          A01X+131633Y+021120X0110Y0240R270 S1      
317m2032            VIA   -    M      A01X+132022Y+020704X0200Y         S2      
017m2032            VIA   -    M      A18X+132022Y+020704X0260Y         S2      
017m2032                  -    MD0100PA00X+132022Y+020704                       
327m2032            R876  -2          A01X+132310Y+020486X0198Y0197R180 S1      
327m2032            R4472 -1   M      A01X+132310Y+020886X0198Y0197     S1      
317m2033            VIA   -    MD0100PA00X+148814Y+087834X0200Y         S0      
317m2033            VIA   -    M      A01X+033398Y+101794X0200Y         S2      
017m2033            VIA   -    M      A18X+033398Y+101794X0260Y         S2      
017m2033                  -    MD0100PA00X+033398Y+101794                       
327m2033            R929  -2          A18X+149199Y+088084X0198Y0197     S2      
327m2033            R925  -1   M      A18X+148814Y+088084X0198Y0197     S2      
327m2033            PEX0  -AK39       A01X+028720Y+114626X0180Y         S1      
317m2033            VIA   -    MD0080PA00X+028533Y+114439X0160Y         S0      
327m2034            VIA   -    M      A18X+144858Y+092444X0260Y         S2      
327m2034            U97   -1          A18X+145481Y+092811X0240Y0440R270 S2      
327m2034            R915  -2          A18X+144042Y+093150X0198Y0197     S2      
327m2034            R909  -1   M      A18X+144042Y+092700X0198Y0197R180 S2      
327m2035            VIA   -    M      A01X+102542Y+031048X0300Y    R090 S1      
327m2035            U113  -B19        A01X+102629Y+031961X0110Y0180     S1      
327m2035            R1079 -1          A01X+102575Y+030583X0198Y0197R270 S1      
327PEX0_SPARE6      VIA   -    M      A18X+033102Y+123228X0260Y         S2      
327PEX0_SPARE6      R1253 -2          A01X+036240Y+119857X0198Y0197R090 S1      
327PEX0_SPARE6      R1242 -1          A01X+036240Y+120344X0198Y0197R090 S1      
317PEX0_SPARE6      VIA   -    MD0100PA00X+036240Y+120104X0200Y         S0      
327PEX0_SPARE6      PEX0  -L28        A01X+024606Y+121732X0180Y         S1      
317PEX0_SPARE6      VIA   -    MD0080PA00X+024793Y+121545X0160Y    R270 S0      
317m2036            VIA   -    M      A01X+049705Y+036945X0200Y         S2      
017m2036            VIA   -    M      A18X+049705Y+036945X0260Y         S2      
017m2036                  -    MD0100PA00X+049705Y+036945                       
327m2036            R1581 -2          A01X+048848Y+036909X0198Y0197     S1      
327m2036            U124  -7          A01X+050182Y+036945X0120Y0630R270 S1      
327m2037            VIA   -    M      A01X+135138Y+091516X0300Y         S1      
327m2037            R3539 -2          A01X+135050Y+091992X0198Y0197R270 S1      
327m2037            U6    -A14        A01X+135628Y+089759X0160Y         S1      
327m2038            VIA   -    M      A01X+139700Y+085034X0300Y         S1      
327m2038            U6    -T22        A01X+138147Y+085034X0160Y         S1      
327m2038            R4092 -2          A01X+140792Y+085200X0198Y0197R180 S1      
327P12V_SSD7_OCP    PR222 -1          A01X+086602Y+021286X0198Y0197     S1      
327P12V_SSD7_OCP    PU37  -9          A01X+085924Y+021317X0110Y0240R270 S1      
317P12V_SSD7_OCP    VIA   -    M      A01X+086320Y+021246X0200Y         S2      
017P12V_SSD7_OCP    VIA   -    M      A18X+086320Y+021246X0260Y         S2      
017P12V_SSD7_OCP          -    MD0100PA00X+086320Y+021246                       
317m2039            VIA   -    MD0100PA00X+093405Y+036916X0200Y    R090 S0      
327m2039            U112  -14         A01X+093084Y+036916X0100Y0290R090 S1      
327m2039            C2621 -1          A18X+093040Y+036662X0198Y0197     S2      
327m2039            R1006 -2          A18X+092320Y+037174X0198Y0197     S2      
327m2039            C2614 -1          A18X+091882Y+037195X0198Y0197R090 S2      
317m2039            VIA   -    MD0100PA00X+091329Y+037275X0200Y    R090 S0      
327m2039            U112  -21         A01X+091544Y+037275X0100Y0290R180 S1      
327m2039            C2615 -1          A18X+091231Y+036589X0198Y0197R180 S2      
317m2039            VIA   -    MD0100PA00X+093446Y+035862X0200Y    R090 S0      
327m2039            U112  -9          A01X+093084Y+035932X0100Y0290R090 S1      
327m2039            C2617 -1          A18X+093077Y+036013X0198Y0197     S2      
317m2039            VIA   -    M      A01X+092331Y+034996X0200Y    R090 S2      
017m2039            VIA   -    M      A18X+092331Y+034996X0260Y    R090 S2      
017m2039                  -    MD0100PA00X+092331Y+034996                       
327m2039            U112  -5          A01X+092331Y+035376X0100Y0290R180 S1      
327m2039            C2619 -1          A18X+091895Y+035474X0198Y0197R270 S2      
327m2039            C2620 -1          A18X+092414Y+035482X0198Y0197R270 S2      
317m2039            VIA   -    MD0100PA00X+090862Y+035932X0200Y    R090 S0      
327m2039            U112  -27         A01X+091184Y+035932X0100Y0290R090 S1      
317m2039            VIA   -    MD0100PA00X+090852Y+035671X0200Y    R090 S0      
327m2039            U112  -28         A01X+091184Y+035735X0100Y0290R090 S1      
327m2039            C2618 -1          A18X+091266Y+035668X0198Y0197R090 S2      
327m2039            C2616 -1          A18X+091208Y+036058X0198Y0197R180 S2      
327P3V3_SDB_VPLL    VIA   -           A18X+150615Y+091573X0260Y         S2      
327P3V3_SDB_VPLL    VIA   -           A18X+151126Y+091633X0260Y         S2      
327P3V3_SDB_VPLL    L4    -2          A18X+151656Y+093424X0280Y0320R090 S2      
327P3V3_SDB_VPLL    C2580 -1          A18X+151689Y+092374X0198Y0197R180 S2      
327P3V3_SDB_VPLL    C2581 -1          A18X+151656Y+092874X0280Y0320R270 S2      
327P3V3_SDB_VPLL    VIA   -           A18X+151614Y+091840X0260Y         S2      
317P3V3_SDB_VPLL    VIA   -    MD0100PA00X+151518Y+092109X0200Y    R090 S0      
327P3V3_SDB_VPLL    U70   -9          A01X+151518Y+091668X0110Y0540     S1      
327PEX0_SPARE5      PEX0  -L25        A01X+023484Y+121732X0180Y         S1      
317PEX0_SPARE5      VIA   -    MD0080PA00X+023671Y+121545X0160Y    R270 S0      
327PEX0_SPARE5      VIA   -    M      A18X+030859Y+126335X0260Y         S2      
327PEX0_SPARE5      R1246 -2          A01X+036248Y+122630X0198Y0197R135 S1      
327PEX0_SPARE5      R1235 -1          A01X+035518Y+122702X0198Y0197R135 S1      
317PEX0_SPARE5      VIA   -    MD0100PA00X+036027Y+122823X0200Y         S0      
317m2040            VIA   -    M      A01X+049088Y+037359X0200Y         S2      
017m2040            VIA   -    M      A18X+049088Y+037359X0260Y         S2      
017m2040                  -    MD0100PA00X+049088Y+037359                       
327m2040            R1579 -2          A01X+048848Y+037359X0198Y0197     S1      
327m2040            U124  -6          A01X+050182Y+037201X0120Y0630R270 S1      
327SSD7_CLK_EN_N    VIA   -    M      A18X+138000Y+091250X0260Y         S2      
327SSD7_CLK_EN_N    R3597 -2          A18X+137850Y+091792X0198Y0197R090 S2      
327SSD7_CLK_EN_N    U6    -C20        A01X+137517Y+089129X0160Y         S1      
317SSD7_CLK_EN_N    VIA   -    MD0100PA00X+137675Y+089286X0180Y         S0      
317m2041            VIA   -    MD0100PA00X+137360Y+085192X0180Y         S0      
327m2041            U6    -R19        A01X+137202Y+085349X0160Y         S1      
317m2041            VIA   -    MD0100PA00X+145529Y+075966X0200Y         S0      
327m2041            R4665 -2   M      A01X+150258Y+077700X0198Y0197     S1      
327m2041            R4695 -2   M      A01X+150258Y+077300X0198Y0197     S1      
327m2041            R4678 -1          A01X+150258Y+076900X0198Y0197R180 S1      
317m2041            VIA   -    M      A01X+149330Y+077691X0200Y         S2      
017m2041            VIA   -    M      A18X+149330Y+077691X0260Y         S2      
017m2041                  -    MD0100PA00X+149330Y+077691                       
327P12V_SSD15_SS    PC447 -1          A01X+178019Y+020086X0198Y0197     S1      
327P12V_SSD15_SS    PU45  -7          A01X+177341Y+020923X0110Y0240R270 S1      
317P12V_SSD15_SS    VIA   -    M      A01X+177729Y+020086X0200Y         S2      
017P12V_SSD15_SS    VIA   -    M      A18X+177729Y+020086X0260Y         S2      
017P12V_SSD15_SS          -    MD0100PA00X+177729Y+020086                       
327P1V8_SDB_VCORE   VIA   -           A18X+152621Y+091834X0260Y         S2      
327P1V8_SDB_VCORE   VIA   -           A18X+149000Y+092866X0260Y         S2      
317P1V8_SDB_VCORE   VIA   -    MD0100PA00X+151986Y+097764X0200Y         S0      
317P1V8_SDB_VCORE   VIA   -    MD0100PA00X+152108Y+095734X0200Y    R270 S0      
327P1V8_SDB_VCORE   C2577 -1   M      A01X+151986Y+097374X0280Y0320R090 S1      
327P1V8_SDB_VCORE   C2574 -1   M      A01X+152046Y+096874X0198Y0197R180 S1      
327P1V8_SDB_VCORE   U70   -37  M      A01X+152108Y+096176X0110Y0540     S1      
317P1V8_SDB_VCORE   VIA   -    MD0100PA00X+149607Y+095398X0200Y         S0      
327P1V8_SDB_VCORE   U70   -49         A01X+149166Y+095398X0110Y0540R090 S1      
327P1V8_SDB_VCORE   C2573 -1          A18X+149900Y+095308X0198Y0197R090 S2      
317P1V8_SDB_VCORE   VIA   -           A01X+150181Y+093840X0200Y         S2      
017P1V8_SDB_VCORE   VIA   -           A18X+150181Y+093840X0260Y         S2      
017P1V8_SDB_VCORE         -     D0100PA00X+150181Y+093840                       
317P1V8_SDB_VCORE   VIA   -    MD0100PA00X+152108Y+092109X0200Y    R090 S0      
327P1V8_SDB_VCORE   U70   -12         A01X+152108Y+091668X0110Y0540     S1      
327P1V8_SDB_VCORE   C2576 -1   M      A18X+152093Y+091834X0198Y0197R090 S2      
317P1V8_SDB_VCORE   VIA   -    MD0100PA00X+148724Y+092445X0200Y    R180 S0      
327P1V8_SDB_VCORE   U70   -64         A01X+149166Y+092445X0110Y0540R090 S1      
327P1V8_SDB_VCORE   C2575 -1   M      A18X+149000Y+092408X0198Y0197R090 S2      
327PEX0_SPARE4      VIA   -    M      A18X+034466Y+119506X0260Y         S2      
327PEX0_SPARE4      R1247 -2          A01X+035040Y+119857X0198Y0197R090 S1      
327PEX0_SPARE4      R1236 -1          A01X+035040Y+120344X0198Y0197R090 S1      
317PEX0_SPARE4      VIA   -    MD0100PA00X+035040Y+120104X0200Y         S0      
327PEX0_SPARE4      PEX0  -M25        A01X+023484Y+121358X0180Y         S1      
317PEX0_SPARE4      VIA   -    MD0080PA00X+023671Y+121171X0160Y    R270 S0      
317m2042            VIA   -    M      A01X+049282Y+035711X0200Y         S2      
017m2042            VIA   -    M      A18X+049282Y+035711X0260Y         S2      
017m2042                  -    MD0100PA00X+049282Y+035711                       
327m2042            R1587 -2          A01X+048838Y+035250X0198Y0197     S1      
327m2042            U124  -10         A01X+050182Y+036177X0120Y0630R270 S1      
317m2043            VIA   -    MD0100PA00X+133580Y+088026X0180Y         S0      
327m2043            U6    -G8         A01X+133738Y+087869X0160Y         S1      
327m2043            U385  -1          A01X+021100Y+014265X0240Y0240     S1      
327m2043            R5882 -2          A01X+019066Y+014125X0198Y0197     S1      
317m2043            VIA   -    M      A01X+019359Y+014125X0200Y         S2      
017m2043            VIA   -    M      A18X+019359Y+014125X0260Y         S2      
017m2043                  -    MD0100PA00X+019359Y+014125                       
317m2043            VIA   -    MD0100PA00X+023863Y+024430X0200Y    R090 S0      
317m2043            VIA   -    MD0100PA00X+024851Y+081204X0200Y         S0      
327m2043            R4491 -2          A01X+023863Y+024168X0198Y0197     S1      
327m2044            PU41  -8          A01X+156869Y+021120X0110Y0240R270 S1      
317m2044            VIA   -    M      A01X+157259Y+020704X0200Y         S2      
017m2044            VIA   -    M      A18X+157259Y+020704X0260Y         S2      
017m2044                  -    MD0100PA00X+157259Y+020704                       
327m2044            R872  -2          A01X+157546Y+020486X0198Y0197R180 S1      
327m2044            R4469 -1   M      A01X+157546Y+020886X0198Y0197     S1      
327P3V3_SDB_VPHY    VIA   -           A18X+150408Y+094371X0260Y         S2      
327P3V3_SDB_VPHY    VIA   -           A18X+149898Y+094444X0260Y         S2      
327P3V3_SDB_VPHY    L5    -2   M      A18X+150286Y+093074X0280Y0320R270 S2      
327P3V3_SDB_VPHY    C2582 -1          A18X+150208Y+092000X0198Y0197     S2      
327P3V3_SDB_VPHY    C2583 -1          A18X+150286Y+092524X0280Y0320R090 S2      
327P3V3_SDB_VPHY    VIA   -           A18X+150042Y+091519X0260Y         S2      
317P3V3_SDB_VPHY    VIA   -    MD0100PA00X+150534Y+092124X0200Y    R270 S0      
327P3V3_SDB_VPHY    U70   -4          A01X+150534Y+091668X0110Y0540     S1      
327PEX0_SPARE3      VIA   -    M      A18X+033124Y+122106X0260Y         S2      
327PEX0_SPARE3      R1248 -2          A01X+035440Y+119857X0198Y0197R090 S1      
327PEX0_SPARE3      R1237 -1          A01X+035440Y+120344X0198Y0197R090 S1      
317PEX0_SPARE3      VIA   -    MD0100PA00X+035440Y+120104X0200Y         S0      
327PEX0_SPARE3      PEX0  -L32        A01X+026102Y+121732X0180Y         S1      
317PEX0_SPARE3      VIA   -    MD0080PA00X+026289Y+121545X0160Y    R270 S0      
317m2045            VIA   -    MD0100PA00X+031189Y+008605X0200Y    R180 S0      
327m2045            U128  -6          A01X+031077Y+008185X0170Y0460R180 S1      
327m2045            R1655 -1          A01X+031284Y+008873X0198Y0197R090 S1      
327m2045            R1583 -1          A01X+048534Y+036459X0198Y0197     S1      
327m2045            R1555 -2   M      A01X+047848Y+036459X0198Y0197     S1      
317m2045            VIA   -    M      A01X+046953Y+036675X0200Y         S2      
017m2045            VIA   -    M      A18X+046953Y+036675X0260Y         S2      
017m2045                  -    MD0100PA00X+046953Y+036675                       
327SSD1_PWR_EN      VIA   -    M      A01X+134450Y+091150X0300Y         S1      
327SSD1_PWR_EN      U6    -B11        A01X+134683Y+089444X0160Y         S1      
327SSD1_PWR_EN      R3594 -1          A01X+134250Y+091992X0198Y0197R090 S1      
317m2046            VIA   -    MD0100PA00X+165020Y+092591X0200Y         S0      
327m2046            R6617 -1          A01X+165193Y+090928X0198Y0197R180 S1      
317m2046            VIA   -    M      A01X+151650Y+094750X0200Y         S2      
017m2046            VIA   -    M      A18X+151650Y+094750X0260Y         S2      
017m2046                  -    MD0100PA00X+151650Y+094750                       
327m2046            U102  -3          A18X+152044Y+095356X0140Y0440     S2      
327m2046            R940  -2          A18X+151908Y+094300X0198Y0197R180 S2      
317m2046            VIA   -    MD0100PA00X+174180Y+091790X0200Y         S0      
327m2046            R6609 -2          A01X+175009Y+089728X0198Y0197R180 S1      
327m2047            U70   -63         A01X+149166Y+092642X0110Y0540R090 S1      
317m2047            VIA   -    M      A01X+148482Y+092732X0200Y         S2      
017m2047            VIA   -    M      A18X+148482Y+092732X0260Y         S2      
017m2047                  -    MD0100PA00X+148482Y+092732                       
327m2047            R912  -2          A18X+148027Y+092732X0198Y0197R180 S2      
327PEX0_SPARE2      VIA   -    M      A18X+033788Y+123395X0260Y         S2      
327PEX0_SPARE2      R1238 -1          A01X+034952Y+122136X0198Y0197R135 S1      
327PEX0_SPARE2      R1249 -2          A01X+035399Y+121781X0198Y0197R135 S1      
317PEX0_SPARE2      VIA   -    MD0100PA00X+035194Y+121990X0200Y         S0      
327PEX0_SPARE2      PEX0  -L27        A01X+024232Y+121732X0180Y         S1      
317PEX0_SPARE2      VIA   -    MD0080PA00X+024232Y+121732X0160Y         S0      
317m2048            VIA   -    MD0100PA00X+001144Y+013272X0200Y    R180 S0      
327m2048            U126  -7          A01X+001131Y+012884X0170Y0460R180 S1      
327m2048            R1643 -1          A01X+001200Y+013579X0198Y0197R090 S1      
327m2048            R1552 -2          A01X+047848Y+037809X0198Y0197     S1      
327m2048            R1577 -1          A01X+048534Y+037809X0198Y0197     S1      
317m2048            VIA   -    MD0100PA00X+048172Y+037809X0200Y         S0      
317m2048            VIA   -    M      A01X+012613Y+035951X0200Y         S2      
017m2048            VIA   -    M      A18X+012613Y+035951X0260Y         S2      
017m2048                  -    MD0100PA00X+012613Y+035951                       
317m2049            VIA   -    M      A01X+020993Y+020886X0200Y         S2      
017m2049            VIA   -    M      A18X+020993Y+020886X0260Y         S2      
017m2049                  -    MD0100PA00X+020993Y+020886                       
317m2049            VIA   -    MD0100PA00X+024120Y+081484X0200Y         S0      
327m2049            U6    -G11        A01X+134683Y+087869X0160Y         S1      
317m2049            VIA   -    MD0100PA00X+134525Y+088026X0180Y         S0      
327m2049            R4460 -2          A01X+020735Y+020886X0198Y0197     S1      
317m2049            VIA   -    MD0100PA00X+016035Y+025888X0200Y         S0      
327m2049            R5839 -2          A01X+011608Y+024208X0198Y0197R180 S1      
317m2050            VIA   -    M      A01X+144263Y+037150X0200Y         S2      
017m2050            VIA   -    M      A18X+144263Y+037150X0260Y         S2      
017m2050                  -    MD0100PA00X+144263Y+037150                       
317m2050            VIA   -    MD0100PA00X+138305Y+085192X0180Y         S0      
327m2050            U6    -R22        A01X+138147Y+085349X0160Y         S1      
317m2050            VIA   -    MD0100PA00X+164568Y+038150X0200Y         S0      
327m2050            R361  -2          A18X+164568Y+038450X0198Y0197     S2      
327P12V_SSD11_SS    PC446 -1          A01X+132310Y+020086X0198Y0197     S1      
327P12V_SSD11_SS    PU44  -7          A01X+131633Y+020923X0110Y0240R270 S1      
317P12V_SSD11_SS    VIA   -    M      A01X+132020Y+020086X0200Y         S2      
017P12V_SSD11_SS    VIA   -    M      A18X+132020Y+020086X0260Y         S2      
017P12V_SSD11_SS          -    MD0100PA00X+132020Y+020086                       
317m2051            VIA   -    MD0100PA00X+174690Y+087920X0200Y         S0      
327m2051            R6610 -2          A01X+175003Y+087920X0198Y0197R180 S1      
317m2051            VIA   -    MD0100PA00X+164839Y+094555X0200Y         S0      
327m2051            R6619 -1          A01X+165153Y+094214X0198Y0197R180 S1      
317m2051            VIA   -    M      A01X+152850Y+094761X0200Y         S2      
017m2051            VIA   -    M      A18X+152850Y+094761X0260Y         S2      
017m2051                  -    MD0100PA00X+152850Y+094761                       
327m2051            U102  -1          A18X+152556Y+095356X0140Y0440     S2      
327m2051            R939  -2          A18X+152608Y+094300X0198Y0197R180 S2      
317OSC_SDB_IN       VIA   -           A01X+150216Y+089948X0200Y    R270 S2      
017OSC_SDB_IN       VIA   -           A18X+150216Y+089948X0260Y    R270 S2      
017OSC_SDB_IN             -     D0100PA00X+150216Y+089948                       
327OSC_SDB_IN       Y3    -1          A01X+150270Y+088813X0480Y0560R090 S1      
327OSC_SDB_IN       R907  -2   M      A01X+149938Y+090224X0280Y0320R090 S1      
327OSC_SDB_IN       U70   -2          A01X+150140Y+091668X0110Y0540     S1      
327OSC_SDB_IN       C2578 -1   M      A01X+150036Y+090724X0198Y0197R180 S1      
327PEX0_SPARE1      PEX0  -L30        A01X+025354Y+121732X0180Y         S1      
317PEX0_SPARE1      VIA   -    MD0080PA00X+025541Y+121545X0160Y    R270 S0      
327PEX0_SPARE1      VIA   -    M      A18X+033490Y+122451X0260Y         S2      
327PEX0_SPARE1      R1250 -2          A01X+035840Y+119857X0198Y0197R090 S1      
327PEX0_SPARE1      R1239 -1          A01X+035840Y+120344X0198Y0197R090 S1      
317PEX0_SPARE1      VIA   -    MD0100PA00X+035837Y+120104X0200Y         S0      
327m2052            R214  -2          A01X+113260Y+055880X0198Y0197R180 S1      
317m2052            VIA   -    MD0100PA00X+084950Y+081750X0200Y         S0      
327m2052            R6306 -1          A18X+083900Y+081692X0198Y0197R270 S2      
317m2052            VIA   -    M      A01X+085530Y+064682X0200Y         S2      
017m2052            VIA   -    M      A18X+085530Y+064682X0260Y         S2      
017m2052                  -    MD0100PA00X+085530Y+064682                       
327m2052            J24   -A8         A01X+111355Y+055892X0140Y0480R270 S1      
317m2052            VIA   -    MD0100PA00X+111885Y+055892X0200Y    R180 S0      
317m2052            VIA   -    MD0100PA00X+100160Y+062760X0200Y         S0      
327m2053            R1589 -1          A01X+048523Y+034800X0198Y0197     S1      
327m2053            R1561 -2   M      A01X+047838Y+034800X0198Y0197     S1      
317m2053            VIA   -    MD0100PA00X+051477Y+031295X0200Y         S0      
317m2053            VIA   -    M      A01X+041390Y+003257X0200Y    R090 S2      
017m2053            VIA   -    M      A18X+041390Y+003257X0260Y    R090 S2      
017m2053                  -    MD0100PA00X+041390Y+003257                       
327m2053            U129  -7          A01X+040995Y+003117X0170Y0460R090 S1      
327m2053            R1658 -1          A01X+041690Y+003048X0198Y0197     S1      
317m2054            VIA   -    MD0100PA00X+036162Y+113473X0200Y         S0      
317m2054            VIA   -    MD0100PA00X+036863Y+093135X0200Y         S0      
327m2054            R3891 -1          A01X+036175Y+113713X0198Y0197R090 S1      
317m2054            VIA   -    M      A01X+036569Y+081513X0200Y         S2      
017m2054            VIA   -    M      A18X+036569Y+081513X0260Y         S2      
017m2054                  -    MD0100PA00X+036569Y+081513                       
327m2054            U6    -C6         A01X+133108Y+089129X0160Y         S1      
317m2054            VIA   -    MD0100PA00X+132950Y+089286X0180Y         S0      
317m2055            VIA   -    MD0100PA00X+136730Y+085822X0180Y         S0      
327m2055            U6    -N17        A01X+136572Y+085979X0160Y         S1      
317m2055            VIA   -    M      A01X+140200Y+086400X0200Y         S2      
017m2055            VIA   -    M      A18X+140200Y+086400X0260Y         S2      
017m2055                  -    MD0100PA00X+140200Y+086400                       
327m2055            R4086 -2          A01X+140792Y+086400X0198Y0197R180 S1      
327P12V_SSD12_SS    PC411 -1          A01X+147310Y+020086X0198Y0197     S1      
327P12V_SSD12_SS    PU39  -7          A01X+146633Y+020923X0110Y0240R270 S1      
317P12V_SSD12_SS    VIA   -    M      A01X+147020Y+020086X0200Y         S2      
017P12V_SSD12_SS    VIA   -    M      A18X+147020Y+020086X0260Y         S2      
017P12V_SSD12_SS          -    MD0100PA00X+147020Y+020086                       
317OSC_SDB_OUT      VIA   -    M      A01X+150421Y+090974X0200Y    R270 S2      
017OSC_SDB_OUT      VIA   -    M      A18X+150421Y+090974X0260Y    R270 S2      
017OSC_SDB_OUT            -    MD0100PA00X+150421Y+090974                       
327OSC_SDB_OUT      R907  -1   M      A01X+150518Y+090224X0280Y0320R090 S1      
327OSC_SDB_OUT      Y3    -3          A01X+151136Y+089482X0480Y0560R090 S1      
327OSC_SDB_OUT      C2579 -1   M      A01X+150421Y+090724X0198Y0197     S1      
327OSC_SDB_OUT      U70   -3          A01X+150337Y+091668X0110Y0540     S1      
327PEX0_SPARE0      PEX0  -M26        A01X+023858Y+121358X0180Y         S1      
317PEX0_SPARE0      VIA   -    MD0080PA00X+024045Y+121545X0160Y         S0      
327PEX0_SPARE0      VIA   -    M      A18X+034318Y+123754X0260Y         S2      
327PEX0_SPARE0      R1240 -1          A01X+035235Y+122419X0198Y0197R135 S1      
327PEX0_SPARE0      R1251 -2          A01X+035682Y+122064X0198Y0197R135 S1      
317PEX0_SPARE0      VIA   -    MD0100PA00X+035522Y+122317X0200Y         S0      
317m2056            VIA   -    MD0100PA00X+020598Y+008573X0200Y    R180 S0      
327m2056            R1644 -1          A01X+020653Y+008880X0198Y0197R090 S1      
327m2056            U127  -7          A01X+020585Y+008185X0170Y0460R180 S1      
327m2056            R1581 -1          A01X+048534Y+036909X0198Y0197     S1      
327m2056            R1554 -2          A01X+047848Y+036909X0198Y0197     S1      
317m2056            VIA   -    MD0100PA00X+048172Y+036909X0200Y         S0      
317m2056            VIA   -    M      A01X+023626Y+034249X0200Y         S2      
017m2056            VIA   -    M      A18X+023626Y+034249X0260Y         S2      
017m2056                  -    MD0100PA00X+023626Y+034249                       
317m2057            VIA   -    MD0100PA00X+112071Y+009435X0200Y         S0      
317m2057            VIA   -    M      A01X+112002Y+006051X0200Y         S2      
017m2057            VIA   -    M      A18X+112002Y+006051X0260Y         S2      
017m2057                  -    MD0100PA00X+112002Y+006051                       
327m2057            R1694 -2   M      A01X+111129Y+007259X0198Y0197     S1      
327m2057            R1691 -2          A01X+110810Y+006858X0198Y0197R180 S1      
327m2057            U135  -2   M      A01X+112002Y+006472X0170Y0460R180 S1      
327m2057            R1700 -2          A01X+112071Y+009195X0198Y0197R090 S1      
327m2058            R3540 -2          A01X+136195Y+094603X0198Y0197R270 S1      
327m2058            U6    -G12        A01X+134998Y+087869X0160Y         S1      
317m2058            VIA   -    M      A01X+136195Y+094360X0200Y         S2      
017m2058            VIA   -    M      A18X+136195Y+094360X0260Y         S2      
017m2058                  -    MD0100PA00X+136195Y+094360                       
317m2058            VIA   -    MD0100PA00X+135155Y+088026X0180Y         S0      
327m2059            U6    -V19        A01X+137202Y+084404X0160Y         S1      
317m2059            VIA   -    MD0100PA00X+137360Y+084247X0180Y         S0      
327m2059            R4735 -2          A01X+139942Y+066000X0198Y0197R180 S1      
327m2059            R4778 -2          A01X+139458Y+066000X0198Y0197     S1      
317m2059            VIA   -    M      A01X+139700Y+066000X0200Y    R180 S2      
017m2059            VIA   -    M      A18X+139700Y+066000X0260Y    R180 S2      
017m2059                  -    MD0100PA00X+139700Y+066000                       
317m2059            VIA   -    MD0100PA00X+144899Y+069439X0200Y         S0      
327m2060            U70   -62         A01X+149166Y+092839X0110Y0540R090 S1      
317m2060            VIA   -    M      A01X+148550Y+093250X0200Y         S2      
017m2060            VIA   -    M      A18X+148550Y+093250X0260Y         S2      
017m2060                  -    MD0100PA00X+148550Y+093250                       
327m2060            R913  -2          A18X+148027Y+093532X0198Y0197R180 S2      
327m2061            R213  -2          A01X+113260Y+056280X0198Y0197R180 S1      
317m2061            VIA   -    MD0100PA00X+084950Y+081250X0200Y         S0      
327m2061            R6307 -1          A18X+083900Y+081308X0198Y0197R090 S2      
317m2061            VIA   -    M      A01X+086166Y+064665X0200Y         S2      
017m2061            VIA   -    M      A18X+086166Y+064665X0260Y         S2      
017m2061                  -    MD0100PA00X+086166Y+064665                       
327m2061            J24   -A7         A01X+111355Y+056128X0140Y0480R270 S1      
317m2061            VIA   -    MD0100PA00X+111885Y+056142X0200Y    R180 S0      
317m2061            VIA   -    MD0100PA00X+100390Y+062870X0200Y         S0      
317m2062            VIA   -    MD0100PA00X+030834Y+008573X0200Y    R180 S0      
327m2062            R1657 -1          A01X+030890Y+008880X0198Y0197R090 S1      
327m2062            U128  -7          A01X+030821Y+008185X0170Y0460R180 S1      
327m2062            R1585 -1          A01X+048534Y+036009X0198Y0197     S1      
327m2062            R1556 -2   M      A01X+047848Y+036009X0198Y0197     S1      
317m2062            VIA   -    M      A01X+046734Y+035994X0200Y         S2      
017m2062            VIA   -    M      A18X+046734Y+035994X0260Y         S2      
017m2062                  -    MD0100PA00X+046734Y+035994                       
317m2063            VIA   -    MD0100PA00X+071980Y+025888X0200Y         S0      
327m2063            R5984 -2          A01X+067553Y+024208X0198Y0197R180 S1      
317m2063            VIA   -    M      A01X+076938Y+020886X0200Y         S2      
017m2063            VIA   -    M      A18X+076938Y+020886X0260Y         S2      
017m2063                  -    MD0100PA00X+076938Y+020886                       
327m2063            R4463 -2          A01X+076680Y+020886X0198Y0197     S1      
317m2063            VIA   -    MD0100PA00X+136730Y+088971X0180Y         S0      
327m2063            U6    -D17        A01X+136572Y+088814X0160Y         S1      
317m2063            VIA   -    MD0100PA00X+072885Y+094833X0200Y         S0      
317m2064            VIA   -    M      A01X+141090Y+047042X0200Y         S2      
017m2064            VIA   -    M      A18X+141090Y+047042X0260Y         S2      
017m2064                  -    MD0100PA00X+141090Y+047042                       
317m2064            VIA   -    MD0100PA00X+140691Y+049198X0200Y    R180 S0      
327m2064            U6    -M20        A01X+137517Y+086294X0160Y         S1      
317m2064            VIA   -    MD0100PA00X+137675Y+086137X0180Y         S0      
327m2064            R4479 -2          A01X+140949Y+049198X0198Y0197R180 S1      
327m2064            R6046 -2          A01X+141090Y+046749X0198Y0197R090 S1      
317m2065            VIA   -    MD0100PA00X+151845Y+087378X0200Y         S0      
327m2065            VIA   -    M      A18X+152900Y+088401X0260Y         S2      
327m2065            R928  -2          A18X+152900Y+089292X0198Y0197R090 S2      
327m2065            U100  -3          A18X+151450Y+087378X0140Y0440R090 S2      
327m2065            R6611 -2          A01X+179737Y+092752X0198Y0197R090 S1      
317m2065            VIA   -    MD0100PA00X+179736Y+093076X0200Y         S0      
317m2065            VIA   -    MD0100PA00X+155116Y+095289X0200Y         S0      
327m2065            R6613 -1          A01X+155114Y+095660X0198Y0197     S1      
317m2066            VIA   -    M      A01X+143552Y+093600X0200Y         S2      
017m2066            VIA   -    M      A18X+143552Y+093600X0260Y         S2      
017m2066                  -    MD0100PA00X+143552Y+093600                       
327m2066            R914  -2          A18X+144042Y+093600X0198Y0197     S2      
327m2066            U70   -61         A01X+149166Y+093036X0110Y0540R090 S1      
327m2067            R1642 -1          A01X+021048Y+008873X0198Y0197R090 S1      
327m2067            U127  -6          A01X+020841Y+008185X0170Y0460R180 S1      
317m2067            VIA   -    MD0100PA00X+020953Y+008605X0200Y    R180 S0      
327m2067            R1579 -1          A01X+048534Y+037359X0198Y0197     S1      
327m2067            R1553 -2          A01X+047848Y+037359X0198Y0197     S1      
317m2067            VIA   -    MD0100PA00X+048172Y+037359X0200Y         S0      
317m2067            VIA   -    M      A01X+023499Y+033616X0200Y         S2      
017m2067            VIA   -    M      A18X+023499Y+033616X0260Y         S2      
017m2067                  -    MD0100PA00X+023499Y+033616                       
327m2068            VIA   -    M      A01X+136450Y+091530X0300Y         S1      
327m2068            R3554 -2          A01X+136250Y+091992X0198Y0197R270 S1      
327m2068            U6    -B15        A01X+135942Y+089444X0160Y         S1      
327m2069            VIA   -    M      A01X+140250Y+085600X0300Y         S1      
327m2069            U6    -P22        A01X+138147Y+085664X0160Y         S1      
327m2069            R4090 -2          A01X+140792Y+085600X0198Y0197R180 S1      
317m2070            VIA   -    MD0100PA00X+178954Y+093050X0200Y         S0      
327m2070            R6612 -2          A01X+178954Y+092765X0198Y0197R090 S1      
317m2070            VIA   -    M      A01X+164740Y+088146X0200Y         S2      
017m2070            VIA   -    M      A18X+164740Y+088146X0260Y         S2      
017m2070                  -    MD0100PA00X+164740Y+088146                       
327m2070            R6615 -1          A01X+165139Y+087134X0198Y0197R180 S1      
317m2070            VIA   -    MD0100PA00X+151852Y+087890X0200Y         S0      
327m2070            R927  -2          A18X+152500Y+089292X0198Y0197R090 S2      
327m2070            U100  -1          A18X+151450Y+087890X0140Y0440R090 S2      
327PEX0_SPARE7      PEX0  -M27        A01X+024232Y+121358X0180Y         S1      
317PEX0_SPARE7      VIA   -    MD0080PA00X+024419Y+121545X0160Y         S0      
327PEX0_SPARE7      VIA   -    M      A18X+034531Y+122120X0260Y         S2      
327PEX0_SPARE7      R1254 -2          A01X+035116Y+121499X0198Y0197R135 S1      
327PEX0_SPARE7      R1243 -1          A01X+034669Y+121854X0198Y0197R135 S1      
317PEX0_SPARE7      VIA   -    MD0100PA00X+034928Y+121723X0200Y         S0      
327m2071            U126  -6          A01X+001387Y+012884X0170Y0460R180 S1      
327m2071            R1641 -1          A01X+001595Y+013572X0198Y0197R090 S1      
317m2071            VIA   -    MD0100PA00X+001500Y+013303X0200Y    R180 S0      
317m2071            VIA   -    M      A01X+012575Y+036586X0200Y         S2      
017m2071            VIA   -    M      A18X+012575Y+036586X0260Y         S2      
017m2071                  -    MD0100PA00X+012575Y+036586                       
327m2071            R1575 -1          A01X+048534Y+038259X0198Y0197     S1      
327m2071            R1551 -2          A01X+047848Y+038259X0198Y0197     S1      
317m2071            VIA   -    MD0100PA00X+048172Y+038259X0200Y         S0      
327m2072            VIA   -    M      A01X+133050Y+091530X0300Y         S1      
327m2072            U6    -A7         A01X+133423Y+089759X0160Y         S1      
327m2072            R3555 -1          A01X+133050Y+091992X0198Y0197R090 S1      
327m2073            R4759 -2          A01X+139458Y+070700X0198Y0197     S1      
327m2073            R4734 -2          A01X+139942Y+070700X0198Y0197R180 S1      
317m2073            VIA   -    M      A01X+139700Y+070700X0200Y    R180 S2      
017m2073            VIA   -    M      A18X+139700Y+070700X0260Y    R180 S2      
017m2073                  -    MD0100PA00X+139700Y+070700                       
317m2073            VIA   -    MD0100PA00X+144654Y+071955X0200Y         S0      
317m2073            VIA   -    MD0100PA00X+137360Y+084562X0180Y         S0      
327m2073            U6    -U19        A01X+137202Y+084719X0160Y         S1      
327m2074            R1181 -1          A01X+135832Y+034712X0198Y0197R180 S1      
317m2074            VIA   -    MD0100PA00X+136354Y+034702X0200Y         S0      
327m2074            J43   -B14        A01X+153372Y+010468X0150Y0500R090 S1      
317m2074            VIA   -    MD0100PA00X+154048Y+010425X0200Y         S0      
327PEX0_SYS_ERR_N   PEX0  -AV30       A01X+025354Y+111634X0180Y         S1      
317PEX0_SYS_ERR_N   VIA   -    MD0080PA00X+025541Y+111821X0160Y         S0      
317PEX0_SYS_ERR_N   VIA   -    M      A01X+008848Y+102373X0200Y         S2      
017PEX0_SYS_ERR_N   VIA   -    M      A18X+008848Y+102373X0260Y         S2      
017PEX0_SYS_ERR_N         -    MD0100PA00X+008848Y+102373                       
327PEX0_SYS_ERR_N   R1255 -1          A01X+008414Y+102105X0198Y0197     S1      
327m2075            R1560 -2   M      A01X+047838Y+035250X0198Y0197     S1      
327m2075            R1587 -1          A01X+048523Y+035250X0198Y0197     S1      
317m2075            VIA   -    MD0100PA00X+051179Y+031380X0200Y         S0      
317m2075            VIA   -    M      A01X+041414Y+002749X0200Y    R090 S2      
017m2075            VIA   -    M      A18X+041414Y+002749X0260Y    R090 S2      
017m2075                  -    MD0100PA00X+041414Y+002749                       
327m2075            R1656 -1          A01X+041683Y+002653X0198Y0197     S1      
327m2075            U129  -6          A01X+040995Y+002861X0170Y0460R090 S1      
317SSD4_PWR_EN      VIA   -    M      A01X+137395Y+094010X0200Y         S2      
017SSD4_PWR_EN      VIA   -    M      A18X+137395Y+094010X0260Y         S2      
017SSD4_PWR_EN            -    MD0100PA00X+137395Y+094010                       
327SSD4_PWR_EN      R3549 -2          A01X+137395Y+094603X0198Y0197R270 S1      
317SSD4_PWR_EN      VIA   -    MD0100PA00X+135785Y+088341X0180Y         S0      
327SSD4_PWR_EN      U6    -F14        A01X+135628Y+088184X0160Y         S1      
327m2076            VIA   -    M      A01X+089665Y+090381X0300Y    R090 S1      
327m2076            R4539 -2          A01X+089663Y+090951X0198Y0197R270 S1      
327m2076            U5    -T10        A01X+089869Y+088466X0160Y    R180 S1      
327P12V_SSD8_OCP    PR225 -1          A01X+101602Y+021286X0198Y0197     S1      
327P12V_SSD8_OCP    PU38  -9          A01X+100924Y+021317X0110Y0240R270 S1      
317P12V_SSD8_OCP    VIA   -    M      A01X+101320Y+021246X0200Y         S2      
017P12V_SSD8_OCP    VIA   -    M      A18X+101320Y+021246X0260Y         S2      
017P12V_SSD8_OCP          -    MD0100PA00X+101320Y+021246                       
327m2077            R1180 -1          A01X+135832Y+034352X0198Y0197R180 S1      
317m2077            VIA   -    MD0100PA00X+136354Y+034362X0200Y         S0      
327m2077            J43   -B15        A01X+153372Y+010705X0150Y0500R090 S1      
317m2077            VIA   -    MD0100PA00X+154048Y+010765X0200Y         S0      
317m2078            VIA   -           A01X+098963Y+034386X0200Y         S2      
017m2078            VIA   -           A18X+098963Y+034386X0260Y         S2      
017m2078                  -     D0100PA00X+098963Y+034386                       
327m2078            U113  -A9         A01X+100709Y+032896X0070Y0220R090 S1      
317m2079            VIA   -    M      A01X+143706Y+032086X0200Y         S2      
017m2079            VIA   -    M      A18X+143706Y+032086X0260Y         S2      
017m2079                  -    MD0100PA00X+143706Y+032086                       
327m2079            U125  -13         A01X+142641Y+032644X0120Y0630R270 S1      
327m2079            R1616 -2          A01X+144313Y+032086X0198Y0197R180 S1      
317m2080            VIA   -    MD0100PA00X+176249Y+099026X0200Y         S0      
317m2080            VIA   -    MD0100PA00X+172101Y+113473X0200Y         S0      
327m2080            R4005 -1          A01X+172101Y+113713X0198Y0197R090 S1      
317m2080            VIA   -    M      A01X+144109Y+097641X0200Y         S2      
017m2080            VIA   -    M      A18X+144109Y+097641X0260Y         S2      
017m2080                  -    MD0100PA00X+144109Y+097641                       
317m2080            VIA   -    MD0100PA00X+133895Y+088971X0180Y         S0      
327m2080            U6    -D9         A01X+134053Y+088814X0160Y         S1      
317m2081            VIA   -    M      A01X+143353Y+066056X0200Y         S2      
017m2081            VIA   -    M      A18X+143353Y+066056X0260Y         S2      
017m2081                  -    MD0100PA00X+143353Y+066056                       
317m2081            VIA   -    MD0100PA00X+152420Y+064610X0200Y         S0      
327m2081            R310  -2          A01X+152168Y+064197X0198Y0197R180 S1      
317m2081            VIA   -    MD0100PA00X+136415Y+086137X0180Y         S0      
327m2081            U6    -M16        A01X+136257Y+086294X0160Y         S1      
327m2082            R1170 -1          A01X+131826Y+031578X0198Y0197R090 S1      
317m2082            VIA   -    MD0100PA00X+131836Y+031056X0200Y    R270 S0      
327m2082            J38   -B15        A01X+097427Y+010705X0150Y0500R090 S1      
317m2082            VIA   -    MD0100PA00X+098103Y+010765X0200Y         S0      
317m2083            VIA   -           A01X+098863Y+034950X0200Y         S2      
017m2083            VIA   -           A18X+098863Y+034950X0260Y         S2      
017m2083                  -     D0100PA00X+098863Y+034950                       
327m2083            U113  -A8         A01X+100709Y+033093X0070Y0220R090 S1      
317m2084            VIA   -    M      A01X+143404Y+033411X0200Y         S2      
017m2084            VIA   -    M      A18X+143404Y+033411X0260Y         S2      
017m2084                  -    MD0100PA00X+143404Y+033411                       
327m2084            U125  -16         A01X+142641Y+033411X0120Y0630R270 S1      
327m2084            R1622 -2          A01X+144313Y+033436X0198Y0197R180 S1      
327SSD6_CLK_EN_N    VIA   -    M      A01X+137500Y+091150X0300Y         S1      
327SSD6_CLK_EN_N    U6    -A19        A01X+137202Y+089759X0160Y         S1      
327SSD6_CLK_EN_N    R3583 -2          A01X+137450Y+091992X0198Y0197R270 S1      
317m2085            VIA   -    M      A01X+140200Y+084800X0200Y         S2      
017m2085            VIA   -    M      A18X+140200Y+084800X0260Y         S2      
017m2085                  -    MD0100PA00X+140200Y+084800                       
327m2085            R4093 -2          A01X+140792Y+084800X0198Y0197R180 S1      
317m2085            VIA   -    MD0100PA00X+136415Y+085507X0180Y         S0      
327m2085            U6    -P16        A01X+136257Y+085664X0160Y         S1      
327m2086            R1172 -1          A01X+132614Y+031578X0198Y0197R090 S1      
317m2086            VIA   -    MD0100PA00X+132624Y+030756X0200Y    R270 S0      
327m2086            J39   -B15        A01X+107663Y+010705X0150Y0500R090 S1      
317m2086            VIA   -    MD0100PA00X+108339Y+010765X0200Y         S0      
327SMB_NIC4_LS_EN   U119  -5          A01X+085430Y+081216X0140Y0590R270 S1      
317SMB_NIC4_LS_EN   VIA   -    M      A01X+085900Y+081000X0200Y         S2      
017SMB_NIC4_LS_EN   VIA   -    M      A18X+085900Y+081000X0260Y         S2      
017SMB_NIC4_LS_EN         -    MD0100PA00X+085900Y+081000                       
327SMB_NIC4_LS_EN   R1510 -1          A01X+086142Y+081000X0198Y0197     S1      
317m2087            VIA   -    M      A01X+143883Y+032986X0200Y         S2      
017m2087            VIA   -    M      A18X+143883Y+032986X0260Y         S2      
017m2087                  -    MD0100PA00X+143883Y+032986                       
327m2087            U125  -15         A01X+142641Y+033156X0120Y0630R270 S1      
327m2087            R1620 -2          A01X+144313Y+032986X0198Y0197R180 S1      
327m2088            R3986 -1          A01X+126792Y+113713X0198Y0197R090 S1      
317m2088            VIA   -    MD0100PA00X+126792Y+113473X0200Y         S0      
317m2088            VIA   -    MD0100PA00X+133600Y+090050X0200Y         S0      
327m2088            U6    -A8         A01X+133738Y+089759X0160Y         S1      
317m2088            VIA   -    M      A01X+130638Y+103665X0200Y         S2      
017m2088            VIA   -    M      A18X+130638Y+103665X0260Y         S2      
017m2088                  -    MD0100PA00X+130638Y+103665                       
327P12V_SSD15_OCP   PR238 -1          A01X+178019Y+021286X0198Y0197     S1      
327P12V_SSD15_OCP   PU45  -9          A01X+177341Y+021317X0110Y0240R270 S1      
317P12V_SSD15_OCP   VIA   -    M      A01X+177738Y+021246X0200Y         S2      
017P12V_SSD15_OCP   VIA   -    M      A18X+177738Y+021246X0260Y         S2      
017P12V_SSD15_OCP         -    MD0100PA00X+177738Y+021246                       
327FT4232_SDB_REF   U70   -6          A01X+150927Y+091668X0110Y0540     S1      
317FT4232_SDB_REF   VIA   -    M      A01X+150927Y+092123X0200Y         S2      
017FT4232_SDB_REF   VIA   -    M      A18X+150927Y+092123X0260Y         S2      
017FT4232_SDB_REF         -    MD0100PA00X+150927Y+092123                       
327FT4232_SDB_REF   R908  -1          A18X+151050Y+092592X0198Y0197R270 S2      
317m2089            VIA   -    MD0100PA00X+107352Y+101243X0200Y         S0      
327m2089            VIA   -    M      A18X+168090Y+114252X0260Y         S2      
317m2089            VIA   -    MD0100PA00X+174931Y+098790X0200Y         S0      
327m2089            R998  -2          A18X+166938Y+114655X0198Y0197R090 S2      
317m2089            VIA   -    MD0100PA00X+049570Y+084939X0200Y         S0      
317m2089            VIA   -    MD0100PA00X+104241Y+080144X0200Y         S0      
327m2089            U107  -3          A18X+049995Y+084939X0140Y0440R270 S2      
327m2090            J41   -B15        A01X+128136Y+010705X0150Y0500R090 S1      
317m2090            VIA   -    MD0100PA00X+128812Y+010765X0200Y         S0      
327m2090            R1176 -1          A01X+135832Y+032778X0198Y0197R180 S1      
317m2090            VIA   -    MD0100PA00X+136354Y+032788X0200Y         S0      
317m2091            VIA   -    M      A01X+143582Y+035236X0200Y         S2      
017m2091            VIA   -    M      A18X+143582Y+035236X0260Y         S2      
017m2091                  -    MD0100PA00X+143582Y+035236                       
327m2091            U125  -20         A01X+142641Y+034435X0120Y0630R270 S1      
327m2091            R1630 -2          A01X+144313Y+035236X0198Y0197R180 S1      
327SSD1_PWRDIS      VIA   -    M      A01X+133850Y+091530X0300Y         S1      
327SSD1_PWRDIS      R3596 -1          A01X+133850Y+091992X0198Y0197R090 S1      
327SSD1_PWRDIS      U6    -A11        A01X+134683Y+089759X0160Y         S1      
327m2092            VIA   -    M      A01X+140158Y+083249X0300Y         S1      
327m2092            U6    -Y21        A01X+137832Y+083774X0160Y         S1      
327m2092            R4097 -2          A01X+140792Y+082800X0198Y0197R180 S1      
327m2093            PU43  -8          A01X+167105Y+021120X0110Y0240R270 S1      
317m2093            VIA   -    M      A01X+167495Y+020704X0200Y         S2      
017m2093            VIA   -    M      A18X+167495Y+020704X0260Y         S2      
017m2093                  -    MD0100PA00X+167495Y+020704                       
327m2093            R874  -2          A01X+167783Y+020486X0198Y0197R180 S1      
327m2093            R4471 -1   M      A01X+167783Y+020886X0198Y0197     S1      
317m2094            VIA   -    M      A01X+152502Y+090956X0200Y         S2      
017m2094            VIA   -    M      A18X+152502Y+090956X0260Y         S2      
017m2094                  -    MD0100PA00X+152502Y+090956                       
327m2094            R5776 -1          A01X+152502Y+090660X0198Y0197R270 S1      
327m2094            U70   -14         A01X+152502Y+091668X0110Y0540     S1      
317m2095            VIA   -    MD0080PA00X+165659Y+114813X0160Y         S0      
327m2095            VIA   -    M      A18X+165846Y+115000X0260Y         S2      
327m2095            R998  -1          A18X+166938Y+114970X0198Y0197R090 S2      
327m2095            PEX3  -AJ38       A01X+165472Y+115000X0180Y         S1      
327m2096            R1173 -1          A01X+132974Y+031578X0198Y0197R090 S1      
317m2096            VIA   -    MD0100PA00X+132964Y+030756X0200Y    R270 S0      
327m2096            J39   -B14        A01X+107663Y+010468X0150Y0500R090 S1      
317m2096            VIA   -    MD0100PA00X+108339Y+010425X0200Y         S0      
317m2097            VIA   -    M      A01X+008801Y+101368X0200Y         S2      
017m2097            VIA   -    M      A18X+008801Y+101368X0260Y         S2      
017m2097                  -    MD0100PA00X+008801Y+101368                       
327m2097            R6153 -1          A01X+008470Y+100454X0198Y0197R270 S1      
327m2097            R1255 -2          A01X+008729Y+102105X0198Y0197     S1      
327m2097            Q12   -2   M      A01X+008468Y+101221X0160Y0240R270 S1      
317TP_PEX2_TMS      VIA   -    MD0080PA00X+112844Y+121171X0160Y         S0      
327TP_PEX2_TMS      VIA   -           A18X+112657Y+120984X0260Y         S2      
327TP_PEX2_TMS      PEX2  -M20        A01X+113031Y+121358X0180Y         S1      
317m2098            VIA   -    M      A01X+143417Y+032536X0200Y         S2      
017m2098            VIA   -    M      A18X+143417Y+032536X0260Y         S2      
017m2098                  -    MD0100PA00X+143417Y+032536                       
327m2098            U125  -14         A01X+142641Y+032900X0120Y0630R270 S1      
327m2098            R1618 -2          A01X+144313Y+032536X0198Y0197R180 S1      
327m2099            U382  -1          A01X+010864Y+014265X0240Y0240     S1      
327m2099            R5871 -2          A01X+008830Y+014125X0198Y0197     S1      
317m2099            VIA   -    M      A01X+009122Y+014125X0200Y         S2      
017m2099            VIA   -    M      A18X+009122Y+014125X0260Y         S2      
017m2099                  -    MD0100PA00X+009122Y+014125                       
317m2099            VIA   -    MD0100PA00X+013866Y+024170X0200Y         S0      
317m2099            VIA   -    MD0100PA00X+012570Y+085752X0200Y         S0      
327m2099            U6    -F11        A01X+134683Y+088184X0160Y         S1      
317m2099            VIA   -    MD0100PA00X+134525Y+088341X0180Y         S0      
327m2099            R4486 -2          A01X+013626Y+024168X0198Y0197     S1      
327m2100            VIA   -    M      A01X+089415Y+089644X0300Y    R090 S1      
327m2100            U5    -R10        A01X+089869Y+088151X0160Y    R180 S1      
327m2100            R4540 -2          A01X+089263Y+090951X0198Y0197R270 S1      
327m2101            J41   -B14        A01X+128136Y+010468X0150Y0500R090 S1      
317m2101            VIA   -    MD0100PA00X+128812Y+010425X0200Y         S0      
327m2101            R1177 -1          A01X+135832Y+033138X0198Y0197R180 S1      
317m2101            VIA   -    MD0100PA00X+136354Y+033128X0200Y         S0      
327PEX2_SPARE2      VIA   -    M      A18X+125206Y+123395X0260Y         S2      
327PEX2_SPARE2      R1372 -1          A01X+126370Y+122136X0198Y0197R135 S1      
327PEX2_SPARE2      R1385 -2          A01X+126817Y+121781X0198Y0197R135 S1      
317PEX2_SPARE2      VIA   -    MD0100PA00X+126611Y+121990X0200Y         S0      
327PEX2_SPARE2      PEX2  -L27        A01X+115650Y+121732X0180Y         S1      
317PEX2_SPARE2      VIA   -    MD0080PA00X+115650Y+121732X0160Y         S0      
317m2102            VIA   -    M      A01X+144042Y+034683X0200Y         S2      
017m2102            VIA   -    M      A18X+144042Y+034683X0260Y         S2      
017m2102                  -    MD0100PA00X+144042Y+034683                       
327m2102            U125  -19         A01X+142641Y+034179X0120Y0630R270 S1      
327m2102            R1628 -2          A01X+144313Y+034786X0198Y0197R180 S1      
327m2103            R6070 -2          A01X+064775Y+014125X0198Y0197     S1      
327m2103            U389  -1          A01X+066809Y+014265X0240Y0240     S1      
317m2103            VIA   -    MD0100PA00X+065067Y+014125X0200Y         S0      
317m2103            VIA   -    M      A01X+069571Y+024430X0200Y    R090 S2      
017m2103            VIA   -    M      A18X+069571Y+024430X0260Y    R090 S2      
017m2103                  -    MD0100PA00X+069571Y+024430                       
327m2103            U6    -A18        A01X+136887Y+089759X0160Y         S1      
317m2103            VIA   -    MD0100PA00X+136700Y+090450X0200Y         S0      
317m2103            VIA   -    MD0100PA00X+072240Y+094250X0200Y         S0      
327m2103            R4490 -2          A01X+069571Y+024168X0198Y0197     S1      
327P12V_SSD14_SS    PC435 -1          A01X+167783Y+020086X0198Y0197     S1      
327P12V_SSD14_SS    PU43  -7          A01X+167105Y+020923X0110Y0240R270 S1      
317P12V_SSD14_SS    VIA   -    M      A01X+167493Y+020086X0200Y         S2      
017P12V_SSD14_SS    VIA   -    M      A18X+167493Y+020086X0260Y         S2      
017P12V_SSD14_SS          -    MD0100PA00X+167493Y+020086                       
317m2104            VIA   -    MD0100PA00X+133751Y+037340X0200Y    R090 S0      
327m2104            R1184 -1          A01X+133761Y+036818X0198Y0197R270 S1      
327m2104            J45   -B15        A01X+173844Y+010705X0150Y0500R090 S1      
317m2104            VIA   -    MD0100PA00X+174520Y+010765X0200Y         S0      
317PEX2_SPARE0      VIA   -    MD0100PA00X+126939Y+122317X0200Y         S0      
327PEX2_SPARE0      R1387 -2          A01X+127100Y+122064X0198Y0197R135 S1      
327PEX2_SPARE0      R1374 -1          A01X+126652Y+122419X0198Y0197R135 S1      
327PEX2_SPARE0      VIA   -    M      A18X+125735Y+123754X0260Y         S2      
327PEX2_SPARE0      PEX2  -M26        A01X+115276Y+121358X0180Y         S1      
317PEX2_SPARE0      VIA   -    MD0080PA00X+115462Y+121545X0160Y         S0      
317m2105            VIA   -    M      A01X+143971Y+033667X0200Y         S2      
017m2105            VIA   -    M      A18X+143971Y+033667X0260Y         S2      
017m2105                  -    MD0100PA00X+143971Y+033667                       
327m2105            U125  -17         A01X+142641Y+033667X0120Y0630R270 S1      
327m2105            R1624 -2          A01X+144313Y+033886X0198Y0197R180 S1      
327SSD5_PWRDIS      VIA   -    M      A18X+136100Y+090400X0260Y         S2      
327SSD5_PWRDIS      R3566 -2          A18X+135450Y+091792X0198Y0197R090 S2      
327SSD5_PWRDIS      U6    -D16        A01X+136257Y+088814X0160Y         S1      
317SSD5_PWRDIS      VIA   -    MD0100PA00X+136415Y+088971X0180Y         S0      
327m2106            VIA   -    M      A01X+139600Y+083774X0300Y         S1      
327m2106            U6    -Y22        A01X+138147Y+083774X0160Y         S1      
327m2106            R4096 -2          A01X+140792Y+083200X0198Y0197R180 S1      
327P12V_SSD13_SS    PC423 -1          A01X+157546Y+020086X0198Y0197     S1      
327P12V_SSD13_SS    PU41  -7          A01X+156869Y+020923X0110Y0240R270 S1      
317P12V_SSD13_SS    VIA   -    M      A01X+157256Y+020086X0200Y         S2      
017P12V_SSD13_SS    VIA   -    M      A18X+157256Y+020086X0260Y         S2      
017P12V_SSD13_SS          -    MD0100PA00X+157256Y+020086                       
317m2107            VIA   -    MD0100PA00X+136654Y+035150X0200Y         S0      
327m2107            R1182 -1          A01X+135832Y+035140X0198Y0197R180 S1      
317m2107            VIA   -    MD0100PA00X+164284Y+010765X0200Y         S0      
327m2107            J44   -B15        A01X+163608Y+010705X0150Y0500R090 S1      
327PEX2_SPARE7      VIA   -    M      A18X+125948Y+122120X0260Y         S2      
327PEX2_SPARE7      R1390 -2          A01X+126534Y+121499X0198Y0197R135 S1      
327PEX2_SPARE7      R1377 -1          A01X+126087Y+121854X0198Y0197R135 S1      
317PEX2_SPARE7      VIA   -    MD0100PA00X+126345Y+121723X0200Y         S0      
327PEX2_SPARE7      PEX2  -M27        A01X+115650Y+121358X0180Y         S1      
317PEX2_SPARE7      VIA   -    MD0080PA00X+115836Y+121545X0160Y         S0      
317m2108            VIA   -    M      A01X+143416Y+033923X0200Y         S2      
017m2108            VIA   -    M      A18X+143416Y+033923X0260Y         S2      
017m2108                  -    MD0100PA00X+143416Y+033923                       
327m2108            U125  -18         A01X+142641Y+033923X0120Y0630R270 S1      
327m2108            R1626 -2          A01X+144313Y+034336X0198Y0197R180 S1      
317m2109            VIA   -    M      A01X+056466Y+020886X0200Y         S2      
017m2109            VIA   -    M      A18X+056466Y+020886X0260Y         S2      
017m2109                  -    MD0100PA00X+056466Y+020886                       
317m2109            VIA   -    MD0100PA00X+059227Y+087726X0200Y         S0      
327m2109            R4459 -2          A01X+056208Y+020886X0198Y0197     S1      
317m2109            VIA   -    MD0100PA00X+051507Y+025888X0200Y         S0      
327m2109            R5974 -2          A01X+047080Y+024208X0198Y0197R180 S1      
317m2109            VIA   -    MD0100PA00X+135785Y+088971X0180Y         S0      
327m2109            U6    -D14        A01X+135628Y+088814X0160Y         S1      
327m2110            PU39  -8          A01X+146633Y+021120X0110Y0240R270 S1      
317m2110            VIA   -    M      A01X+147023Y+020704X0200Y         S2      
017m2110            VIA   -    M      A18X+147023Y+020704X0260Y         S2      
017m2110                  -    MD0100PA00X+147023Y+020704                       
327m2110            R870  -2          A01X+147310Y+020486X0198Y0197R180 S1      
327m2110            R4467 -1   M      A01X+147310Y+020886X0198Y0197     S1      
327m2111            R996  -2          A18X+121230Y+114655X0198Y0197R090 S2      
327m2111            VIA   -    M      A18X+122382Y+114252X0260Y         S2      
317m2111            VIA   -    MD0100PA00X+106070Y+093162X0200Y         S0      
317m2111            VIA   -    MD0100PA00X+104693Y+079656X0200Y         S0      
317m2111            VIA   -    MD0100PA00X+049547Y+084427X0200Y         S0      
327m2111            U107  -1          A18X+049995Y+084427X0140Y0440R270 S2      
327m2112            R1175 -1          A01X+133761Y+031578X0198Y0197R090 S1      
317m2112            VIA   -    MD0100PA00X+133751Y+031056X0200Y    R270 S0      
327m2112            J40   -B14        A01X+117900Y+010468X0150Y0500R090 S1      
317m2112            VIA   -    MD0100PA00X+118575Y+010425X0200Y         S0      
327PEX2_SPARE5      PEX2  -L25        A01X+114902Y+121732X0180Y         S1      
317PEX2_SPARE5      VIA   -    MD0080PA00X+115088Y+121545X0160Y    R270 S0      
327PEX2_SPARE5      VIA   -    M      A01X+127235Y+123075X0300Y         S1      
327PEX2_SPARE5      R1369 -1          A01X+126935Y+122702X0198Y0197R135 S1      
327PEX2_SPARE5      R1382 -2          A01X+127665Y+122630X0198Y0197R135 S1      
317PEX2_SPARE5      VIA   -    MD0100PA00X+127445Y+122823X0200Y         S0      
317m2113            VIA   -    M      A01X+144850Y+034058X0200Y    R180 S2      
017m2113            VIA   -    M      A18X+144850Y+034058X0260Y    R180 S2      
017m2113                  -    MD0100PA00X+144850Y+034058                       
327m2113            R1606 -2          A01X+145313Y+033886X0198Y0197R180 S1      
327m2113            R1624 -1          A01X+144628Y+033886X0198Y0197R180 S1      
327m2113            R1739 -1          A01X+168410Y+008873X0198Y0197R090 S1      
327m2113            U140  -6          A01X+168203Y+008185X0170Y0460R180 S1      
317m2113            VIA   -    MD0100PA00X+168315Y+008605X0200Y    R180 S0      
317m2113            VIA   -    MD0100PA00X+170361Y+028732X0200Y         S0      
317SSD0_PWRDIS      VIA   -    M      A01X+135795Y+093884X0200Y         S2      
017SSD0_PWRDIS      VIA   -    M      A18X+135795Y+093884X0260Y         S2      
017SSD0_PWRDIS            -    MD0100PA00X+135795Y+093884                       
327SSD0_PWRDIS      R3582 -1          A01X+135795Y+094603X0198Y0197R090 S1      
317SSD0_PWRDIS      VIA   -    MD0100PA00X+134210Y+088341X0180Y         S0      
327SSD0_PWRDIS      U6    -F10        A01X+134368Y+088184X0160Y         S1      
327m2114            R4777 -2          A01X+139458Y+065600X0198Y0197     S1      
327m2114            R4729 -2          A01X+139942Y+065200X0198Y0197R180 S1      
327m2114            R4744 -1   M      A01X+139942Y+065600X0198Y0197     S1      
317m2114            VIA   -    MD0100PA00X+139700Y+065600X0200Y    R180 S0      
317m2114            VIA   -    M      A01X+142591Y+069112X0200Y         S2      
017m2114            VIA   -    M      A18X+142591Y+069112X0260Y         S2      
017m2114                  -    MD0100PA00X+142591Y+069112                       
317m2114            VIA   -    MD0100PA00X+136730Y+084562X0180Y         S0      
327m2114            U6    -U17        A01X+136572Y+084719X0160Y         S1      
327m2115            U70   -52         A01X+149166Y+094808X0110Y0540R090 S1      
317m2115            VIA   -    M      A01X+148950Y+097250X0200Y         S2      
017m2115            VIA   -    M      A18X+148950Y+097250X0260Y         S2      
017m2115                  -    MD0100PA00X+148950Y+097250                       
327m2115            R964  -1          A18X+149357Y+097718X0198Y0197R180 S2      
327m2115            R970  -2   M      A18X+148972Y+097718X0198Y0197R180 S2      
317m2116            VIA   -    MD0080PA00X+119951Y+114813X0160Y         S0      
327m2116            VIA   -    M      A18X+120138Y+115000X0260Y         S2      
327m2116            R996  -1          A18X+121230Y+114970X0198Y0197R090 S2      
327m2116            PEX2  -AJ38       A01X+119764Y+115000X0180Y         S1      
327m2117            J42   -B14        A01X+143136Y+010468X0150Y0500R090 S1      
317m2117            VIA   -    MD0100PA00X+143812Y+010425X0200Y         S0      
327m2117            R1179 -1          A01X+135832Y+033925X0198Y0197R180 S1      
317m2117            VIA   -    MD0100PA00X+136654Y+033915X0200Y         S0      
317PU_PEX2_TR_TCK   VIA   -    MD0080PA00X+113218Y+121545X0160Y    R090 S0      
327PU_PEX2_TR_TCK   R1394 -1          A01X+101977Y+122660X0198Y0197R270 S1      
317PU_PEX2_TR_TCK   VIA   -    M      A01X+104972Y+123492X0200Y         S2      
017PU_PEX2_TR_TCK   VIA   -    M      A18X+104972Y+123492X0260Y         S2      
017PU_PEX2_TR_TCK         -    MD0100PA00X+104972Y+123492                       
327PU_PEX2_TR_TCK   PEX2  -L20        A01X+113031Y+121732X0180Y         S1      
317m2118            VIA   -    MD0100PA00X+180520Y+030095X0200Y         S0      
317m2118            VIA   -    M      A01X+178196Y+008573X0200Y    R180 S2      
017m2118            VIA   -    M      A18X+178196Y+008573X0260Y    R180 S2      
017m2118                  -    MD0100PA00X+178196Y+008573                       
327m2118            R1742 -1          A01X+178252Y+008880X0198Y0197R090 S1      
327m2118            U141  -7          A01X+178183Y+008185X0170Y0460R180 S1      
317m2118            VIA   -    MD0100PA00X+144906Y+035236X0200Y    R180 S0      
327m2118            R1630 -1          A01X+144628Y+035236X0198Y0197R180 S1      
327m2118            R1612 -2          A01X+145313Y+035236X0198Y0197R180 S1      
317m2119            VIA   -    M      A01X+041466Y+020886X0200Y         S2      
017m2119            VIA   -    M      A18X+041466Y+020886X0260Y         S2      
017m2119                  -    MD0100PA00X+041466Y+020886                       
317m2119            VIA   -    MD0100PA00X+135150Y+090300X0200Y         S0      
317m2119            VIA   -    MD0100PA00X+047757Y+086082X0200Y         S0      
327m2119            U6    -A13        A01X+135312Y+089759X0160Y         S1      
327m2119            R4464 -2          A01X+041208Y+020886X0198Y0197     S1      
317m2119            VIA   -    MD0100PA00X+036507Y+025888X0200Y         S0      
327m2119            R5849 -2          A01X+032080Y+024208X0198Y0197R180 S1      
327m2120            U6    -N19        A01X+137202Y+085979X0160Y         S1      
317m2120            VIA   -    MD0100PA00X+137360Y+085822X0180Y         S0      
317m2120            VIA   -    M      A01X+138334Y+050823X0200Y         S2      
017m2120            VIA   -    M      A18X+138334Y+050823X0260Y         S2      
017m2120                  -    MD0100PA00X+138334Y+050823                       
317m2120            VIA   -    MD0100PA00X+164760Y+046737X0200Y         S0      
327m2120            R360  -2          A18X+165034Y+046324X0198Y0197     S2      
327m2120            R381  -1   M      A18X+165036Y+046737X0198Y0197R180 S2      
327m2121            J42   -B15        A01X+143136Y+010705X0150Y0500R090 S1      
317m2121            VIA   -    MD0100PA00X+143812Y+010765X0200Y         S0      
327m2121            R1178 -1          A01X+135832Y+033565X0198Y0197R180 S1      
317m2121            VIA   -    MD0100PA00X+136654Y+033575X0200Y         S0      
327PEX2_SPARE6      PEX2  -L28        A01X+116024Y+121732X0180Y         S1      
317PEX2_SPARE6      VIA   -    MD0080PA00X+116210Y+121545X0160Y    R270 S0      
327PEX2_SPARE6      VIA   -    M      A18X+124519Y+123228X0260Y         S2      
327PEX2_SPARE6      R1389 -2          A01X+127657Y+119857X0198Y0197R090 S1      
327PEX2_SPARE6      R1376 -1          A01X+127658Y+120344X0198Y0197R090 S1      
317PEX2_SPARE6      VIA   -    MD0100PA00X+127658Y+120104X0200Y         S0      
317m2122            VIA   -    MD0100PA00X+150388Y+029555X0200Y         S0      
317m2122            VIA   -    MD0100PA00X+147843Y+008605X0200Y    R180 S0      
327m2122            R1725 -1          A01X+147938Y+008873X0198Y0197R090 S1      
327m2122            U138  -6          A01X+147731Y+008185X0170Y0460R180 S1      
317m2122            VIA   -    M      A01X+144906Y+032086X0200Y    R180 S2      
017m2122            VIA   -    M      A18X+144906Y+032086X0260Y    R180 S2      
017m2122                  -    MD0100PA00X+144906Y+032086                       
327m2122            R1616 -1          A01X+144628Y+032086X0198Y0197R180 S1      
327m2122            R1602 -2          A01X+145313Y+032086X0198Y0197R180 S1      
317m2123            VIA   -    M      A01X+031230Y+020886X0200Y         S2      
017m2123            VIA   -    M      A18X+031230Y+020886X0260Y         S2      
017m2123                  -    MD0100PA00X+031230Y+020886                       
317m2123            VIA   -    MD0100PA00X+027410Y+082072X0200Y         S0      
327m2123            R4462 -2          A01X+030972Y+020886X0198Y0197     S1      
317m2123            VIA   -    MD0100PA00X+026271Y+025888X0200Y         S0      
327m2123            R5848 -2          A01X+021844Y+024208X0198Y0197R180 S1      
317m2123            VIA   -    MD0100PA00X+135418Y+090650X0200Y         S0      
317m2123            VIA   -    MD0100PA00X+133580Y+088341X0180Y         S0      
327m2123            U6    -F8         A01X+133738Y+088184X0160Y         S1      
317m2124            VIA   -    MD0100PA00X+136415Y+085822X0180Y         S0      
327m2124            U6    -N16        A01X+136257Y+085979X0160Y         S1      
317m2124            VIA   -    MD0100PA00X+143048Y+065815X0200Y         S0      
327m2124            R308  -2          A01X+152168Y+062760X0198Y0197R180 S1      
327m2124            R329  -1   M      A01X+152168Y+063142X0198Y0197     S1      
317m2124            VIA   -    M      A01X+152073Y+063419X0200Y         S2      
017m2124            VIA   -    M      A18X+152073Y+063419X0260Y         S2      
017m2124                  -    MD0100PA00X+152073Y+063419                       
327P12V_SSD8_SS     PC410 -1          A01X+101602Y+020086X0198Y0197     S1      
327P12V_SSD8_SS     PU38  -7          A01X+100924Y+020923X0110Y0240R270 S1      
317P12V_SSD8_SS     VIA   -    M      A01X+101312Y+020086X0200Y         S2      
017P12V_SSD8_SS     VIA   -    M      A18X+101312Y+020086X0260Y         S2      
017P12V_SSD8_SS           -    MD0100PA00X+101312Y+020086                       
317m2125            VIA   -    M      A01X+149550Y+097250X0200Y         S2      
017m2125            VIA   -    M      A18X+149550Y+097250X0260Y         S2      
017m2125                  -    MD0100PA00X+149550Y+097250                       
327m2125            U70   -39         A01X+151715Y+096176X0110Y0540     S1      
327m2125            R966  -2          A18X+149008Y+096800X0198Y0197R180 S2      
327m2125            R943  -1   M      A18X+149392Y+096800X0198Y0197R180 S2      
327m2126            R1171 -1          A01X+132186Y+031578X0198Y0197R090 S1      
317m2126            VIA   -    MD0100PA00X+132176Y+031056X0200Y    R270 S0      
327m2126            J38   -B14        A01X+097427Y+010468X0150Y0500R090 S1      
317m2126            VIA   -    MD0100PA00X+098103Y+010425X0200Y         S0      
317m2127            VIA   -    MD0080PA00X+111535Y+121732X0160Y         S0      
327m2127            PEX2  -L16        A01X+111535Y+121732X0180Y         S1      
317m2127            VIA   -    M      A01X+104977Y+122940X0200Y         S2      
017m2127            VIA   -    M      A18X+104977Y+122940X0260Y         S2      
017m2127                  -    MD0100PA00X+104977Y+122940                       
327m2127            R1393 -1          A01X+103443Y+122555X0198Y0197R225 S1      
317m2128            VIA   -    MD0100PA00X+144895Y+032645X0200Y    R180 S0      
327m2128            R1618 -1          A01X+144628Y+032536X0198Y0197R180 S1      
327m2128            R1603 -2          A01X+145313Y+032536X0198Y0197R180 S1      
317m2128            VIA   -    M      A01X+147487Y+008573X0200Y    R180 S2      
017m2128            VIA   -    M      A18X+147487Y+008573X0260Y    R180 S2      
017m2128                  -    MD0100PA00X+147487Y+008573                       
327m2128            R1727 -1          A01X+147543Y+008880X0198Y0197R090 S1      
327m2128            U138  -7          A01X+147475Y+008185X0170Y0460R180 S1      
317m2128            VIA   -    MD0100PA00X+149745Y+029588X0200Y         S0      
327NIC7_CLK_EN_N    R4091 -1          A01X+140792Y+084400X0198Y0197     S1      
317NIC7_CLK_EN_N    VIA   -    MD0100PA00X+137675Y+085507X0180Y         S0      
327NIC7_CLK_EN_N    U6    -P20        A01X+137517Y+085664X0160Y         S1      
317NIC7_CLK_EN_N    VIA   -    M      A01X+140550Y+084400X0200Y         S2      
017NIC7_CLK_EN_N    VIA   -    M      A18X+140550Y+084400X0260Y         S2      
017NIC7_CLK_EN_N          -    MD0100PA00X+140550Y+084400                       
327P12V_SSD10_OCP   PR233 -1          A01X+122074Y+021286X0198Y0197     S1      
327P12V_SSD10_OCP   PU42  -9          A01X+121396Y+021317X0110Y0240R270 S1      
317P12V_SSD10_OCP   VIA   -    M      A01X+121793Y+021246X0200Y         S2      
017P12V_SSD10_OCP   VIA   -    M      A18X+121793Y+021246X0260Y         S2      
017P12V_SSD10_OCP         -    MD0100PA00X+121793Y+021246                       
317m2129            VIA   -    M      A01X+052474Y+084515X0200Y         S2      
017m2129            VIA   -    M      A18X+052474Y+084515X0260Y         S2      
017m2129                  -    MD0100PA00X+052474Y+084515                       
327m2129            U98   -52         A01X+052690Y+082072X0110Y0540R090 S1      
327m2129            R995  -1          A18X+052881Y+084983X0198Y0197R180 S2      
327m2129            R999  -2   M      A18X+052496Y+084983X0198Y0197R180 S2      
317m2130            VIA   -    MD0100PA00X+136654Y+035490X0200Y         S0      
327m2130            R1183 -1          A01X+135832Y+035500X0198Y0197R180 S1      
317m2130            VIA   -    MD0100PA00X+164284Y+010425X0200Y         S0      
327m2130            J44   -B14        A01X+163608Y+010468X0150Y0500R090 S1      
317TP_PEX2_TDO      VIA   -    MD0080PA00X+112844Y+121545X0160Y    R180 S0      
327TP_PEX2_TDO      VIA   -           A18X+112657Y+121732X0260Y         S2      
327TP_PEX2_TDO      PEX2  -L19        A01X+112657Y+121732X0180Y         S1      
317m2131            VIA   -    MD0100PA00X+159620Y+029348X0200Y         S0      
317m2131            VIA   -    M      A01X+157724Y+008573X0200Y    R180 S2      
017m2131            VIA   -    M      A18X+157724Y+008573X0260Y    R180 S2      
017m2131                  -    MD0100PA00X+157724Y+008573                       
327m2131            R1728 -1          A01X+157779Y+008880X0198Y0197R090 S1      
327m2131            U139  -7          A01X+157711Y+008185X0170Y0460R180 S1      
317m2131            VIA   -    MD0100PA00X+144873Y+033291X0200Y    R180 S0      
327m2131            R1622 -1          A01X+144628Y+033436X0198Y0197R180 S1      
327m2131            R1605 -2          A01X+145313Y+033436X0198Y0197R180 S1      
317SSD0_PWR_EN      VIA   -    M      A01X+134595Y+094360X0200Y         S2      
017SSD0_PWR_EN      VIA   -    M      A18X+134595Y+094360X0260Y         S2      
017SSD0_PWR_EN            -    MD0100PA00X+134595Y+094360                       
327SSD0_PWR_EN      R3581 -1          A01X+134595Y+094603X0198Y0197R090 S1      
317SSD0_PWR_EN      VIA   -    MD0100PA00X+133895Y+088026X0180Y         S0      
327SSD0_PWR_EN      U6    -G9         A01X+134053Y+087869X0160Y         S1      
317m2132            VIA   -    MD0100PA00X+144632Y+067318X0200Y         S0      
317m2132            VIA   -    MD0100PA00X+156943Y+067711X0200Y         S0      
327m2132            R330  -1   M      A18X+156907Y+054497X0198Y0197R180 S2      
327m2132            R309  -2          A18X+156522Y+054497X0198Y0197R180 S2      
327m2132            VIA   -    M      A18X+157020Y+055104X0260Y         S2      
317m2132            VIA   -    MD0100PA00X+157176Y+057794X0200Y         S0      
317m2132            VIA   -    MD0100PA00X+137360Y+086137X0180Y         S0      
327m2132            U6    -M19        A01X+137202Y+086294X0160Y         S1      
327P12V_SSD9_SS     PC422 -1          A01X+111838Y+020086X0198Y0197     S1      
327P12V_SSD9_SS     PU40  -7          A01X+111160Y+020923X0110Y0240R270 S1      
317P12V_SSD9_SS     VIA   -    M      A01X+111548Y+020086X0200Y         S2      
017P12V_SSD9_SS     VIA   -    M      A18X+111548Y+020086X0260Y         S2      
017P12V_SSD9_SS           -    MD0100PA00X+111548Y+020086                       
327m2133            U70   -27         A01X+153673Y+094414X0110Y0540R090 S1      
317m2133            VIA   -    M      A01X+150950Y+094414X0200Y         S2      
017m2133            VIA   -    M      A18X+150950Y+094414X0260Y         S2      
017m2133                  -    MD0100PA00X+150950Y+094414                       
327m2133            R936  -2          A18X+149008Y+096350X0198Y0197R180 S2      
327m2133            R932  -1   M      A18X+149392Y+096350X0198Y0197R180 S2      
327m2134            R1174 -1          A01X+133401Y+031578X0198Y0197R090 S1      
317m2134            VIA   -    MD0100PA00X+133411Y+031056X0200Y    R270 S0      
327m2134            J40   -B15        A01X+117900Y+010705X0150Y0500R090 S1      
317m2134            VIA   -    MD0100PA00X+118575Y+010765X0200Y         S0      
327PEX2_SYS_ERR_N   R1391 -1          A01X+100025Y+102449X0198Y0197R270 S1      
317PEX2_SYS_ERR_N   VIA   -    M      A01X+100265Y+102373X0200Y         S2      
017PEX2_SYS_ERR_N   VIA   -    M      A18X+100265Y+102373X0260Y         S2      
017PEX2_SYS_ERR_N         -    MD0100PA00X+100265Y+102373                       
327PEX2_SYS_ERR_N   PEX2  -AV30       A01X+116772Y+111634X0180Y         S1      
317PEX2_SYS_ERR_N   VIA   -    MD0080PA00X+116959Y+111821X0160Y         S0      
327m2135            R1626 -1          A01X+144628Y+034336X0198Y0197R180 S1      
327m2135            R1610 -2          A01X+145313Y+034336X0198Y0197R180 S1      
317m2135            VIA   -    MD0100PA00X+144882Y+034532X0200Y    R180 S0      
327m2135            R1741 -1          A01X+168016Y+008880X0198Y0197R090 S1      
327m2135            U140  -7          A01X+167947Y+008185X0170Y0460R180 S1      
317m2135            VIA   -    M      A01X+167960Y+008573X0200Y    R180 S2      
017m2135            VIA   -    M      A18X+167960Y+008573X0260Y    R180 S2      
017m2135                  -    MD0100PA00X+167960Y+008573                       
317m2135            VIA   -    MD0100PA00X+170022Y+029214X0200Y         S0      
327SSD6_PWR_EN      VIA   -    M      A01X+137850Y+091530X0300Y         S1      
327SSD6_PWR_EN      R3576 -2          A01X+137850Y+091992X0198Y0197R270 S1      
327SSD6_PWR_EN      U6    -B19        A01X+137202Y+089444X0160Y         S1      
327m2136            VIA   -    M      A18X+091129Y+089961X0260Y         S2      
327m2136            R4541 -2          A18X+091129Y+090876X0198Y0197R090 S2      
327m2136            U5    -P10        A01X+089869Y+087836X0160Y    R180 S1      
317m2136            VIA   -    MD0100PA00X+089712Y+087994X0180Y    R270 S0      
327P12V_SSD13_OCP   PR230 -1          A01X+157546Y+021286X0198Y0197     S1      
327P12V_SSD13_OCP   PU41  -9          A01X+156869Y+021317X0110Y0240R270 S1      
317P12V_SSD13_OCP   VIA   -    M      A01X+157265Y+021246X0200Y         S2      
017P12V_SSD13_OCP   VIA   -    M      A18X+157265Y+021246X0260Y         S2      
017P12V_SSD13_OCP         -    MD0100PA00X+157265Y+021246                       
317m2137            VIA   -    MD0100PA00X+133411Y+037340X0200Y    R090 S0      
327m2137            R1185 -1          A01X+133401Y+036818X0198Y0197R270 S1      
327m2137            J45   -B14        A01X+173844Y+010468X0150Y0500R090 S1      
317m2137            VIA   -    MD0100PA00X+174520Y+010425X0200Y         S0      
317m2138            VIA   -    MD0080PA00X+111161Y+121732X0160Y         S0      
327m2138            R1395 -1          A01X+104291Y+121707X0198Y0197R225 S1      
317m2138            VIA   -    MD0100PA00X+105060Y+122447X0200Y         S0      
327m2138            VIA   -    M      A18X+105430Y+122447X0260Y         S2      
327m2138            PEX2  -L15        A01X+111161Y+121732X0180Y         S1      
327m2139            R1726 -1          A01X+158174Y+008873X0198Y0197R090 S1      
327m2139            U139  -6          A01X+157967Y+008185X0170Y0460R180 S1      
317m2139            VIA   -    MD0100PA00X+158079Y+008605X0200Y    R180 S0      
317m2139            VIA   -    MD0100PA00X+159669Y+028740X0200Y         S0      
317m2139            VIA   -    M      A01X+144906Y+032986X0200Y    R180 S2      
017m2139            VIA   -    M      A18X+144906Y+032986X0260Y    R180 S2      
017m2139                  -    MD0100PA00X+144906Y+032986                       
327m2139            R1620 -1          A01X+144628Y+032986X0198Y0197R180 S1      
327m2139            R1604 -2          A01X+145313Y+032986X0198Y0197R180 S1      
327SSD6_PWRDIS      VIA   -    M      A18X+136816Y+091227X0260Y         S2      
327SSD6_PWRDIS      R3578 -2          A18X+136250Y+091792X0198Y0197R090 S2      
327SSD6_PWRDIS      U6    -C18        A01X+136887Y+089129X0160Y         S1      
317SSD6_PWRDIS      VIA   -    MD0100PA00X+137045Y+089286X0180Y         S0      
317m2140            VIA   -    MD0100PA00X+137675Y+085192X0180Y         S0      
327m2140            U6    -R20        A01X+137517Y+085349X0160Y         S1      
317m2140            VIA   -    M      A01X+140200Y+084000X0200Y         S2      
017m2140            VIA   -    M      A18X+140200Y+084000X0260Y         S2      
017m2140                  -    MD0100PA00X+140200Y+084000                       
327m2140            R4094 -2          A01X+140792Y+084000X0198Y0197R180 S1      
327m2141            U70   -17         A01X+153673Y+092445X0110Y0540R090 S1      
317m2141            VIA   -    M      A01X+150950Y+093700X0200Y         S2      
017m2141            VIA   -    M      A18X+150950Y+093700X0260Y         S2      
017m2141                  -    MD0100PA00X+150950Y+093700                       
327m2141            R935  -2          A18X+149004Y+095838X0198Y0197R180 S2      
327m2141            R931  -1   M      A18X+149389Y+095838X0198Y0197R180 S2      
317m2142            VIA   -    M      A01X+053074Y+084515X0200Y         S2      
017m2142            VIA   -    M      A18X+053074Y+084515X0260Y         S2      
017m2142                  -    MD0100PA00X+053074Y+084515                       
327m2142            U98   -39         A01X+055239Y+083440X0110Y0540     S1      
327m2142            R997  -2          A18X+052532Y+084065X0198Y0197R180 S2      
327m2142            R994  -1   M      A18X+052917Y+084065X0198Y0197R180 S2      
327PEX2_SPARE4      PEX2  -M25        A01X+114902Y+121358X0180Y         S1      
317PEX2_SPARE4      VIA   -    MD0080PA00X+115088Y+121171X0160Y    R270 S0      
327PEX2_SPARE4      VIA   -    M      A18X+126242Y+119506X0260Y         S2      
327PEX2_SPARE4      R1383 -2          A01X+126457Y+119857X0198Y0197R090 S1      
327PEX2_SPARE4      R1370 -1          A01X+126458Y+120344X0198Y0197R090 S1      
317PEX2_SPARE4      VIA   -    MD0100PA00X+126458Y+120104X0200Y         S0      
317m2143            VIA   -    M      A01X+144857Y+034944X0200Y    R180 S2      
017m2143            VIA   -    M      A18X+144857Y+034944X0260Y    R180 S2      
017m2143                  -    MD0100PA00X+144857Y+034944                       
327m2143            R1628 -1          A01X+144628Y+034786X0198Y0197R180 S1      
327m2143            R1611 -2          A01X+145313Y+034786X0198Y0197R180 S1      
317m2143            VIA   -    MD0100PA00X+178647Y+008592X0200Y    R180 S0      
327m2143            R1740 -1          A01X+178647Y+008873X0198Y0197R090 S1      
327m2143            U141  -6          A01X+178439Y+008185X0170Y0460R180 S1      
317m2143            VIA   -    MD0100PA00X+180476Y+029443X0200Y         S0      
327SPI_BIC1_CS1_N   VIA   -    M      A01X+090838Y+082531X0300Y    R270 S1      
327SPI_BIC1_CS1_N   R1507 -1          A01X+090942Y+081662X0198Y0197R270 S1      
327SPI_BIC1_CS1_N   U5    -B6         A01X+091129Y+084057X0160Y    R180 S1      
317m2144            VIA   -    MD0100PA00X+144672Y+073554X0200Y         S0      
317m2144            VIA   -    M      A01X+148873Y+073950X0200Y         S2      
017m2144            VIA   -    M      A18X+148873Y+073950X0260Y         S2      
017m2144                  -    MD0100PA00X+148873Y+073950                       
327m2144            R4609 -2          A01X+148558Y+074350X0198Y0197     S1      
327m2144            R4652 -2   M      A01X+148558Y+073950X0198Y0197     S1      
327m2144            U6    -U21        A01X+137832Y+084719X0160Y         S1      
317m2144            VIA   -    MD0100PA00X+137990Y+084562X0180Y         S0      
327m2145            PU42  -8          A01X+121396Y+021120X0110Y0240R270 S1      
317m2145            VIA   -    M      A01X+121786Y+020704X0200Y         S2      
017m2145            VIA   -    M      A18X+121786Y+020704X0260Y         S2      
017m2145                  -    MD0100PA00X+121786Y+020704                       
327m2145            R873  -2          A01X+122074Y+020486X0198Y0197R180 S1      
327m2145            R4470 -1   M      A01X+122074Y+020886X0198Y0197     S1      
327PEX2_SPARE3      PEX2  -L32        A01X+117520Y+121732X0180Y         S1      
317PEX2_SPARE3      VIA   -    MD0080PA00X+117707Y+121545X0160Y    R270 S0      
327PEX2_SPARE3      VIA   -    M      A18X+124541Y+122106X0260Y         S2      
327PEX2_SPARE3      R1384 -2          A01X+126857Y+119857X0198Y0197R090 S1      
327PEX2_SPARE3      R1371 -1          A01X+126858Y+120344X0198Y0197R090 S1      
317PEX2_SPARE3      VIA   -    MD0100PA00X+126857Y+120104X0200Y         S0      
317m2146            VIA   -    M      A01X+139573Y+033053X0200Y         S2      
017m2146            VIA   -    M      A18X+139573Y+033053X0260Y         S2      
017m2146                  -    MD0100PA00X+139573Y+033053                       
327m2146            U125  -9          A01X+140436Y+033411X0120Y0630R270 S1      
327m2146            R1625 -2          A01X+139103Y+032987X0198Y0197     S1      
327m2147            VIA   -    M      A01X+136800Y+091150X0300Y         S1      
327m2147            R3568 -2          A01X+136650Y+091992X0198Y0197R270 S1      
327m2147            U6    -A17        A01X+136572Y+089759X0160Y         S1      
317m2148            VIA   -    M      A01X+150950Y+095050X0200Y         S2      
017m2148            VIA   -    M      A18X+150950Y+095050X0260Y         S2      
017m2148                  -    MD0100PA00X+150950Y+095050                       
327m2148            U70   -48         A01X+149943Y+096176X0110Y0540     S1      
327m2148            R940  -1          A18X+151592Y+094300X0198Y0197R180 S2      
327m2149            VIA   -    M      A18X+055271Y+084012X0260Y         S2      
327m2149            R993  -1          A18X+055266Y+084474X0198Y0197R270 S2      
327m2149            U106  -4          A18X+055568Y+083409X0140Y0440     S2      
317PEX2_DFT_IDDT    VIA   -    MD0080PA00X+111348Y+121171X0160Y         S0      
327PEX2_DFT_IDDT    R1375 -1          A01X+103159Y+120445X0198Y0197R225 S1      
327PEX2_DFT_IDDT    R1388 -2   M      A01X+102877Y+120728X0198Y0197R045 S1      
317PEX2_DFT_IDDT    VIA   -    M      A01X+103283Y+120795X0200Y    R315 S2      
017PEX2_DFT_IDDT    VIA   -    M      A18X+103283Y+120795X0260Y    R315 S2      
017PEX2_DFT_IDDT          -    MD0100PA00X+103283Y+120795                       
327PEX2_DFT_IDDT    PEX2  -M16        A01X+111535Y+121358X0180Y         S1      
317m2150            VIA   -    M      A01X+139573Y+034553X0200Y         S2      
017m2150            VIA   -    M      A18X+139573Y+034553X0260Y         S2      
017m2150                  -    MD0100PA00X+139573Y+034553                       
327m2150            U125  -6          A01X+140436Y+034179X0120Y0630R270 S1      
327m2150            R1619 -2          A01X+139103Y+034337X0198Y0197     S1      
317m2151            VIA   -    M      A01X+136595Y+093948X0200Y         S2      
017m2151            VIA   -    M      A18X+136595Y+093948X0260Y         S2      
017m2151                  -    MD0100PA00X+136595Y+093948                       
327m2151            R3525 -1          A01X+136595Y+094603X0198Y0197R090 S1      
327m2151            U6    -D5         A01X+132793Y+088814X0160Y         S1      
317m2151            VIA   -    MD0100PA00X+132636Y+088971X0180Y         S0      
327m2152            R6047 -2          A01X+177099Y+047156X0198Y0197R180 S1      
317m2152            VIA   -    M      A01X+176491Y+047438X0200Y         S2      
017m2152            VIA   -    M      A18X+176491Y+047438X0260Y         S2      
017m2152                  -    MD0100PA00X+176491Y+047438                       
327m2152            R4481 -2          A01X+176250Y+047438X0198Y0197     S1      
317m2152            VIA   -    MD0100PA00X+139404Y+051099X0200Y         S0      
317m2152            VIA   -    MD0100PA00X+177014Y+049071X0200Y         S0      
317m2152            VIA   -    MD0100PA00X+137675Y+085822X0180Y         S0      
327m2152            U6    -N20        A01X+137517Y+085979X0160Y         S1      
317m2153            VIA   -    MD0080PA00X+165285Y+114439X0160Y         S0      
317m2153            VIA   -    MD0100PA00X+107680Y+101290X0200Y         S0      
327m2153            VIA   -    M      A18X+166220Y+111260X0260Y         S2      
327m2153            PEX3  -AK38       A01X+165472Y+114626X0180Y         S1      
317m2153            VIA   -    MD0100PA00X+165294Y+099380X0200Y         S0      
317m2153            VIA   -    MD0100PA00X+054866Y+085040X0200Y         S0      
327m2153            R993  -2          A18X+055266Y+084789X0198Y0197R270 S2      
327m2153            R989  -1   M      A18X+054866Y+084789X0198Y0197R090 S2      
317m2153            VIA   -    MD0100PA00X+104607Y+079274X0200Y         S0      
327PEX2_SPARE1      VIA   -    M      A18X+124907Y+122451X0260Y         S2      
327PEX2_SPARE1      R1386 -2          A01X+127257Y+119857X0198Y0197R090 S1      
327PEX2_SPARE1      R1373 -1          A01X+127258Y+120344X0198Y0197R090 S1      
317PEX2_SPARE1      VIA   -    MD0100PA00X+127254Y+120104X0200Y         S0      
327PEX2_SPARE1      PEX2  -L30        A01X+116772Y+121732X0180Y         S1      
317PEX2_SPARE1      VIA   -    MD0080PA00X+116959Y+121545X0160Y    R270 S0      
317m2154            VIA   -    M      A01X+139557Y+032553X0200Y         S2      
017m2154            VIA   -    M      A18X+139557Y+032553X0260Y         S2      
017m2154                  -    MD0100PA00X+139557Y+032553                       
327m2154            R1627 -2          A01X+139103Y+032537X0198Y0197     S1      
327m2154            U125  -10         A01X+140436Y+033156X0120Y0630R270 S1      
317m2155            VIA   -    MD0100PA00X+136100Y+088341X0180Y         S0      
327m2155            U6    -F15        A01X+135942Y+088184X0160Y         S1      
317m2155            VIA   -    M      A01X+082216Y+025888X0200Y         S2      
017m2155            VIA   -    M      A18X+082216Y+025888X0260Y         S2      
017m2155                  -    MD0100PA00X+082216Y+025888                       
327m2155            R5985 -2          A01X+077789Y+024208X0198Y0197R180 S1      
327m2155            R4465 -2          A01X+086916Y+020886X0198Y0197     S1      
317m2155            VIA   -    MD0100PA00X+087174Y+020886X0200Y         S0      
317m2155            VIA   -    MD0100PA00X+087286Y+066686X0200Y         S0      
327m2156            VIA   -    M      A01X+090415Y+089644X0300Y    R090 S1      
327m2156            R4537 -2          A01X+090730Y+090952X0198Y0197R270 S1      
327m2156            U5    -P9         A01X+090184Y+087836X0160Y    R180 S1      
317m2157            VIA   -    M      A01X+152150Y+094750X0200Y         S2      
017m2157            VIA   -    M      A18X+152150Y+094750X0260Y         S2      
017m2157                  -    MD0100PA00X+152150Y+094750                       
327m2157            U70   -38         A01X+151912Y+096176X0110Y0540     S1      
327m2157            R939  -1          A18X+152292Y+094300X0198Y0197R180 S2      
317TP_PEX2_TCK      VIA   -    MD0080PA00X+110974Y+121545X0160Y         S0      
327TP_PEX2_TCK      VIA   -           A18X+110787Y+121732X0260Y         S2      
327TP_PEX2_TCK      PEX2  -M15        A01X+111161Y+121358X0180Y         S1      
317m2158            VIA   -    M      A01X+139573Y+035553X0200Y         S2      
017m2158            VIA   -    M      A18X+139573Y+035553X0260Y         S2      
017m2158                  -    MD0100PA00X+139573Y+035553                       
327m2158            U125  -4          A01X+140436Y+034691X0120Y0630R270 S1      
327m2158            R1615 -2          A01X+139103Y+035237X0198Y0197     S1      
327SSD5_CLK_EN_N    VIA   -    M      A01X+137150Y+091530X0300Y         S1      
327SSD5_CLK_EN_N    R3570 -2          A01X+137050Y+091992X0198Y0197R270 S1      
327SSD5_CLK_EN_N    U6    -B18        A01X+136887Y+089444X0160Y         S1      
317m2159            VIA   -    M      A01X+144686Y+073074X0200Y         S2      
017m2159            VIA   -    M      A18X+144686Y+073074X0260Y         S2      
017m2159                  -    MD0100PA00X+144686Y+073074                       
317m2159            VIA   -    MD0100PA00X+138305Y+084562X0180Y         S0      
327m2159            U6    -U22        A01X+138147Y+084719X0160Y         S1      
317m2159            VIA   -    MD0100PA00X+148800Y+073150X0200Y    R180 S0      
327m2159            R4603 -2          A01X+148558Y+073550X0198Y0197     S1      
327m2159            R4616 -1          A01X+148558Y+072750X0198Y0197R180 S1      
327m2159            R4651 -2   M      A01X+148558Y+073150X0198Y0197     S1      
327m2160            VIA   -    M      A18X+056439Y+083990X0260Y         S2      
327m2160            U106  -6          A18X+056080Y+083409X0140Y0440     S2      
327m2160            R991  -1          A18X+056223Y+084472X0198Y0197R270 S2      
317TP_PEX2_TDI      VIA   -    MD0080PA00X+111722Y+121545X0160Y    R090 S0      
327TP_PEX2_TDI      VIA   -           A18X+111909Y+121732X0260Y         S2      
327TP_PEX2_TDI      PEX2  -L17        A01X+111909Y+121732X0180Y         S1      
317m2161            VIA   -    M      A01X+139573Y+034053X0200Y         S2      
017m2161            VIA   -    M      A18X+139573Y+034053X0260Y         S2      
017m2161                  -    MD0100PA00X+139573Y+034053                       
327m2161            R1621 -2          A01X+139103Y+033887X0198Y0197     S1      
327m2161            U125  -7          A01X+140436Y+033923X0120Y0630R270 S1      
327m2162            R1816 -2          A01X+110290Y+159321X0198Y0197R270 S1      
317m2162            VIA   -    M      A01X+110290Y+156667X0200Y    R090 S2      
017m2162            VIA   -    M      A18X+110290Y+156667X0260Y    R090 S2      
017m2162                  -    MD0100PA00X+110290Y+156667                       
317m2162            J12   -G9   D0122PA00X+052563Y+159169X0282Y    R180 S3      
317m2162            VIA   -    MD0100PA00X+056540Y+153510X0200Y         S0      
317m2163            VIA   -    M      A01X+135395Y+094360X0200Y         S2      
017m2163            VIA   -    M      A18X+135395Y+094360X0260Y         S2      
017m2163                  -    MD0100PA00X+135395Y+094360                       
327m2163            U6    -E11        A01X+134683Y+088499X0160Y         S1      
317m2163            VIA   -    MD0100PA00X+134525Y+088656X0180Y         S0      
327m2163            R3598 -1          A01X+135395Y+094603X0198Y0197R090 S1      
327P12V_SSD9_R      PU40  -1          A01X+109979Y+021907X0110Y0240R270 S1      
327P12V_SSD9_R      PU40  -2          A01X+109979Y+021710X0110Y0240R270 S1      
327P12V_SSD9_R      PU40  -3          A01X+109979Y+021513X0110Y0240R270 S1      
327P12V_SSD9_R      PU40  -4          A01X+109979Y+021317X0110Y0240R270 S1      
327P12V_SSD9_R      PU40  -5          A01X+109979Y+021120X0110Y0240R270 S1      
327P12V_SSD9_R      PU112 -6_7        A01X+109606Y+027354X0295Y0354R090 S1      
327P12V_SSD9_R      PC864 -1          A01X+108677Y+027416X0400Y0500R270 S1      
327P12V_SSD9_R      PD110 -C          A01X+107615Y+027104X0670Y0990     S1      
317P12V_SSD9_R      VIA   -    MD0100PA00X+108879Y+027003X0200Y         S0      
317P12V_SSD9_R      VIA   -    MD0100PA00X+108629Y+027003X0200Y         S0      
317P12V_SSD9_R      VIA   -    MD0100PA00X+108349Y+027003X0200Y         S0      
317P12V_SSD9_R      VIA   -    MD0100PA00X+108629Y+026753X0200Y         S0      
317P12V_SSD9_R      VIA   -    MD0100PA00X+108879Y+026753X0200Y         S0      
317P12V_SSD9_R      VIA   -    MD0100PA00X+108349Y+026753X0200Y         S0      
317P12V_SSD9_R      VIA   -    MD0100PA00X+107710Y+026418X0200Y         S0      
317P12V_SSD9_R      VIA   -    MD0100PA00X+107460Y+026418X0200Y         S0      
317P12V_SSD9_R      VIA   -    MD0100PA00X+102350Y+024837X0200Y         S0      
327P12V_SSD9_R      R5999 -1          A01X+102628Y+024837X0198Y0197     S1      
317P12V_SSD9_R      VIA   -    MD0100PA00X+110029Y+016870X0200Y         S0      
327P12V_SSD9_R      R612  -1          A01X+109734Y+016870X0198Y0197R180 S1      
327P12V_SSD9_R      PC416 -1          A01X+109341Y+021661X0198Y0197R090 S1      
327P12V_SSD9_R      PC417 -1          A01X+108719Y+021554X0400Y0500R270 S1      
327P12V_SSD9_R      PD42  -C          A01X+107638Y+021175X0670Y0990     S1      
327P12V_SSD9_R      C325  -1          A01X+109447Y+018426X0198Y0197R090 S1      
327P12V_SSD9_R      R605  -2          A01X+107948Y+018919X1150Y1380R090 S1      
327P12V_SSD9_R      U72   -11         A01X+110097Y+018187X0090Y0240R090 S1      
317P12V_SSD9_R      VIA   -    MD0100PA00X+109706Y+021563X0200Y    R090 S0      
317P12V_SSD9_R      VIA   -    MD0100PA00X+108172Y+021571X0200Y    R090 S0      
317P12V_SSD9_R      VIA   -    MD0100PA00X+109706Y+021313X0200Y    R090 S0      
317P12V_SSD9_R      VIA   -    MD0100PA00X+109335Y+021136X0200Y    R090 S0      
317P12V_SSD9_R      VIA   -    MD0100PA00X+109335Y+021386X0200Y    R090 S0      
317P12V_SSD9_R      VIA   -    MD0100PA00X+108830Y+021170X0200Y         S0      
317P12V_SSD9_R      VIA   -    M      A01X+108860Y+020870X0200Y         S2      
017P12V_SSD9_R      VIA   -    M      A18X+108860Y+020870X0260Y         S2      
017P12V_SSD9_R            -    MD0100PA00X+108860Y+020870                       
317P12V_SSD9_R      VIA   -    MD0100PA00X+108172Y+021321X0200Y    R090 S0      
317P12V_SSD9_R      VIA   -    MD0100PA00X+108172Y+021071X0200Y    R090 S0      
317P12V_SSD9_R      VIA   -    MD0100PA00X+108580Y+021170X0200Y         S0      
317P12V_SSD9_R      VIA   -    MD0100PA00X+108580Y+020870X0200Y         S0      
317P12V_SSD9_R      VIA   -    MD0100PA00X+108172Y+020821X0200Y    R090 S0      
317P12V_SSD9_R      VIA   -    MD0100PA00X+107127Y+021048X0200Y    R090 S0      
317P12V_SSD9_R      VIA   -    MD0100PA00X+107127Y+021548X0200Y    R090 S0      
317P12V_SSD9_R      VIA   -    MD0100PA00X+107127Y+021298X0200Y    R090 S0      
317P12V_SSD9_R      VIA   -    MD0100PA00X+107127Y+020798X0200Y    R090 S0      
317P12V_SSD9_R      VIA   -    MD0100PA00X+108932Y+018422X0200Y         S0      
317P12V_SSD9_R      VIA   -    MD0100PA00X+109194Y+018401X0200Y         S0      
317P12V_SSD9_R      VIA   -    MD0100PA00X+109512Y+018101X0200Y         S0      
317P12V_SSD9_R      VIA   -    MD0100PA00X+108911Y+018143X0200Y         S0      
317P12V_SSD9_R      VIA   -    MD0100PA00X+109232Y+018137X0200Y         S0      
327m2164            U70   -26         A01X+153673Y+094217X0110Y0540R090 S1      
317m2164            VIA   -    M      A01X+154764Y+090306X0200Y         S2      
017m2164            VIA   -    M      A18X+154764Y+090306X0260Y         S2      
017m2164                  -    MD0100PA00X+154764Y+090306                       
327m2164            R928  -1          A18X+152900Y+089608X0198Y0197R090 S2      
327m2165            VIA   -    M      A18X+120512Y+111260X0260Y         S2      
327m2165            PEX2  -AK38       A01X+119764Y+114626X0180Y         S1      
317m2165            VIA   -    MD0080PA00X+119577Y+114439X0160Y         S0      
317m2165            VIA   -    MD0100PA00X+057248Y+084554X0200Y         S0      
327m2165            R991  -2          A18X+056223Y+084787X0198Y0197R270 S2      
327m2165            R988  -1   M      A18X+056623Y+084787X0198Y0197R090 S2      
317m2165            VIA   -    MD0100PA00X+101842Y+091758X0200Y         S0      
317m2165            VIA   -    MD0100PA00X+101406Y+079366X0200Y         S0      
317TP_PEX2_TRST_L   VIA   -    MD0080PA00X+112096Y+121171X0160Y         S0      
327TP_PEX2_TRST_L   VIA   -    M      A18X+113031Y+121358X0260Y         S2      
327TP_PEX2_TRST_L   R1392 -1          A18X+113812Y+121388X0198Y0197R270 S2      
327TP_PEX2_TRST_L   PEX2  -M18        A01X+112283Y+121358X0180Y         S1      
317m2166            VIA   -    M      A01X+139574Y+033553X0200Y         S2      
017m2166            VIA   -    M      A18X+139574Y+033553X0260Y         S2      
017m2166                  -    MD0100PA00X+139574Y+033553                       
327m2166            U125  -8          A01X+140436Y+033667X0120Y0630R270 S1      
327m2166            R1623 -2          A01X+139103Y+033437X0198Y0197     S1      
317SSD2_PWR_EN      VIA   -    M      A01X+131450Y+091150X0200Y         S2      
017SSD2_PWR_EN      VIA   -    M      A18X+131450Y+091150X0260Y         S2      
017SSD2_PWR_EN            -    MD0100PA00X+131450Y+091150                       
327SSD2_PWR_EN      R3521 -1          A01X+131450Y+091992X0198Y0197R090 S1      
327SSD2_PWR_EN      U6    -B4         A01X+132478Y+089444X0160Y         S1      
327P12V_SSD12_OCP   PR226 -1          A01X+147310Y+021286X0198Y0197     S1      
327P12V_SSD12_OCP   PU39  -9          A01X+146633Y+021317X0110Y0240R270 S1      
317P12V_SSD12_OCP   VIA   -    M      A01X+147029Y+021246X0200Y         S2      
017P12V_SSD12_OCP   VIA   -    M      A18X+147029Y+021246X0260Y         S2      
017P12V_SSD12_OCP         -    MD0100PA00X+147029Y+021246                       
327m2167            PU52  -8          A01X+083808Y+046957X0110Y0240R270 S1      
317m2167            VIA   -    M      A01X+084292Y+046701X0200Y         S2      
017m2167            VIA   -    M      A18X+084292Y+046701X0260Y         S2      
017m2167                  -    MD0100PA00X+084292Y+046701                       
327m2167            R4480 -1          A01X+084518Y+046938X0198Y0197     S1      
327m2167            R884  -2   M      A01X+084518Y+046538X0198Y0197R180 S1      
317m2168            VIA   -    M      A01X+139573Y+035053X0200Y         S2      
017m2168            VIA   -    M      A18X+139573Y+035053X0260Y         S2      
017m2168                  -    MD0100PA00X+139573Y+035053                       
327m2168            U125  -5          A01X+140436Y+034435X0120Y0630R270 S1      
327m2168            R1617 -2          A01X+139103Y+034787X0198Y0197     S1      
317m2169            VIA   -    M      A01X+108802Y+160695X0200Y    R090 S2      
017m2169            VIA   -    M      A18X+108802Y+160695X0260Y    R090 S2      
017m2169                  -    MD0100PA00X+108802Y+160695                       
327m2169            R1818 -1          A01X+108374Y+161156X0198Y0197R090 S1      
327m2169            R1813 -2   M      A01X+108374Y+160677X0198Y0197R090 S1      
327m2169            U308  -5          A01X+109117Y+160695X0140Y0520R180 S1      
327m2170            U70   -16         A01X+152896Y+091668X0110Y0540     S1      
317m2170            VIA   -    M      A01X+154808Y+091076X0200Y         S2      
017m2170            VIA   -    M      A18X+154808Y+091076X0260Y         S2      
017m2170                  -    MD0100PA00X+154808Y+091076                       
327m2170            R927  -1          A18X+152500Y+089608X0198Y0197R090 S2      
327m2171            R6644 -2          A01X+052911Y+084070X0198Y0197R180 S1      
317m2171            VIA   -    MD0100PA00X+053730Y+084290X0200Y         S0      
327m2171            U106  -3          A18X+055568Y+082621X0140Y0440     S2      
327m2171            VIA   -    M      A18X+035870Y+077550X0260Y         S2      
317m2171            VIA   -    MD0100PA00X+037042Y+076611X0200Y         S0      
327m2171            R6626 -2          A01X+037431Y+076450X0198Y0197R180 S1      
317m2171            VIA   -    MD0100PA00X+026970Y+085310X0200Y         S0      
327m2171            R6633 -1          A01X+028050Y+085564X0198Y0197R090 S1      
327m2172            R1391 -2          A01X+100025Y+102134X0198Y0197R270 S1      
317m2172            VIA   -    M      A01X+100218Y+101368X0200Y         S2      
017m2172            VIA   -    M      A18X+100218Y+101368X0260Y         S2      
017m2172                  -    MD0100PA00X+100218Y+101368                       
327m2172            R6155 -1          A01X+099887Y+100454X0198Y0197R270 S1      
327m2172            Q15   -2   M      A01X+099885Y+101221X0160Y0240R270 S1      
317m2173            VIA   -    MD0080PA00X+165659Y+117805X0160Y         S0      
327m2173            VIA   -           A18X+166771Y+117847X0260Y         S2      
327m2173            R1448 -1   M      A18X+166270Y+117962X0198Y0197R090 S2      
327m2173            PEX3  -AA39       A01X+165846Y+117992X0180Y         S1      
317m2174            VIA   -    M      A01X+139573Y+032053X0200Y         S2      
017m2174            VIA   -    M      A18X+139573Y+032053X0260Y         S2      
017m2174                  -    MD0100PA00X+139573Y+032053                       
327m2174            U125  -11         A01X+140436Y+032900X0120Y0630R270 S1      
327m2174            R1629 -2          A01X+139103Y+032087X0198Y0197     S1      
327m2175            PU38  -8          A01X+100924Y+021120X0110Y0240R270 S1      
317m2175            VIA   -    M      A01X+101314Y+020704X0200Y         S2      
017m2175            VIA   -    M      A18X+101314Y+020704X0260Y         S2      
017m2175                  -    MD0100PA00X+101314Y+020704                       
327m2175            R869  -2          A01X+101602Y+020486X0198Y0197R180 S1      
327m2175            R4466 -1   M      A01X+101602Y+020886X0198Y0197     S1      
327m2176            R6644 -1          A01X+053226Y+084070X0198Y0197R180 S1      
317m2176            VIA   -           A01X+054474Y+082315X0200Y         S2      
017m2176            VIA   -           A18X+054474Y+082315X0260Y         S2      
017m2176                  -     D0100PA00X+054474Y+082315                       
327m2176            U98   -48  M      A01X+053467Y+083440X0110Y0540     S1      
327m2177            VIA   -           A18X+044835Y+131439X0260Y         S2      
327m2177            R1214 -1          A18X+044100Y+131439X0280Y0320R090 S2      
317m2177            VIA   -    MD0100PA00X+044429Y+131439X0200Y         S0      
327m2177            U118  -29         A18X+041954Y+131467X0100Y0220R180 S2      
317m2177            VIA   -    MD0100PA00X+041954Y+131772X0200Y         S0      
327m2177            VIA   -           A18X+039846Y+133046X0260Y         S2      
317m2177            VIA   -    MD0100PA00X+040922Y+131552X0200Y         S0      
317m2177            VIA   -    MD0100PA00X+040297Y+131982X0200Y         S0      
327m2177            U118  -25         A18X+041167Y+131467X0100Y0220R180 S2      
317m2177            VIA   -    MD0100PA00X+040879Y+132180X0200Y         S0      
317m2177            VIA   -    MD0100PA00X+040492Y+132182X0200Y         S0      
327m2177            L16   -2          A18X+039917Y+132164X0440Y0540     S2      
327m2177            C2696 -1          A18X+040466Y+132709X0198Y0197R270 S2      
327m2177            C2697 -1          A18X+040852Y+132707X0198Y0197R270 S2      
317m2177            VIA   -    MD0100PA00X+040101Y+130726X0200Y         S0      
327m2177            C2700 -1          A18X+039808Y+130724X0198Y0197     S2      
327m2177            U118  -21         A18X+040921Y+130630X0100Y0220R270 S2      
327m2177            VIA   -    M      A18X+040380Y+130586X0260Y         S2      
327m2177            C2698 -1   M      A18X+042243Y+128884X0198Y0197R180 S2      
327m2177            U118  -12         A18X+041954Y+129597X0100Y0220     S2      
317m2177            VIA   -    MD0100PA00X+041998Y+128884X0200Y         S0      
327m2177            C2695 -1          A18X+040407Y+129126X0400Y0500R180 S2      
317m2177            VIA   -    MD0100PA00X+040777Y+129220X0200Y         S0      
317m2177            VIA   -    MD0100PA00X+041353Y+128894X0200Y         S0      
327m2177            U118  -16         A18X+041167Y+129597X0100Y0220     S2      
327m2177            C2699 -1   M      A18X+041087Y+128894X0198Y0197R090 S2      
327PEX2_MODE_SEL5   PEX2  -AW25       A01X+114902Y+111260X0180Y         S1      
317PEX2_MODE_SEL5   VIA   -    MD0080PA00X+115088Y+111447X0160Y         S0      
327PEX2_MODE_SEL5   VIA   -    M      A18X+113834Y+105598X0260Y         S2      
317PEX2_MODE_SEL5   VIA   -    MD0100PA00X+102201Y+098881X0200Y         S0      
327PEX2_MODE_SEL5   R1361 -2          A01X+102201Y+099196X0198Y0197R270 S1      
327PEX2_MODE_SEL5   R1341 -1          A01X+102201Y+098611X0198Y0197R270 S1      
317m2178            VIA   -    MD0080PA00X+166033Y+118179X0160Y         S0      
327m2178            VIA   -           A18X+166727Y+118551X0260Y         S2      
327m2178            R1447 -1   M      A18X+166270Y+118396X0198Y0197R270 S2      
327m2178            PEX3  -Y39        A01X+165846Y+118366X0180Y         S1      
327m2179            R1697 -1          A01X+102229Y+008873X0198Y0197R090 S1      
327m2179            U134  -6          A01X+102022Y+008185X0170Y0460R180 S1      
317m2179            VIA   -    MD0100PA00X+102134Y+008605X0200Y    R180 S0      
317m2179            VIA   -    MD0100PA00X+105180Y+027996X0200Y         S0      
327m2179            R1591 -2          A01X+138103Y+035237X0198Y0197     S1      
327m2179            R1615 -1          A01X+138788Y+035237X0198Y0197     S1      
317m2179            VIA   -    M      A01X+138426Y+035237X0200Y         S2      
017m2179            VIA   -    M      A18X+138426Y+035237X0260Y         S2      
017m2179                  -    MD0100PA00X+138426Y+035237                       
317MB_BIC_MON_BUF   VIA   -    M      A01X+109890Y+160214X0200Y    R090 S2      
017MB_BIC_MON_BUF   VIA   -    M      A18X+109890Y+160214X0260Y    R090 S2      
017MB_BIC_MON_BUF         -    MD0100PA00X+109890Y+160214                       
327MB_BIC_MON_BUF   R1816 -1          A01X+110290Y+159636X0198Y0197R270 S1      
327MB_BIC_MON_BUF   R1812 -2   M      A01X+109890Y+159636X0198Y0197R090 S1      
327MB_BIC_MON_BUF   U308  -7          A01X+109629Y+160695X0140Y0520R180 S1      
327SSD1_CLK_EN_N    VIA   -    M      A18X+133850Y+091300X0260Y         S2      
327SSD1_CLK_EN_N    R3599 -1          A18X+133850Y+091792X0198Y0197R270 S2      
327SSD1_CLK_EN_N    U6    -D11        A01X+134683Y+088814X0160Y         S1      
317SSD1_CLK_EN_N    VIA   -    MD0100PA00X+134525Y+088971X0180Y         S0      
317m2180            VIA   -    MD0100PA00X+042953Y+132505X0200Y         S0      
317m2180            VIA   -    MD0100PA00X+043187Y+131570X0200Y         S0      
327m2180            R1214 -2   M      A18X+043520Y+131439X0280Y0320R090 S2      
327m2180            C2702 -1   M      A18X+043525Y+130986X0198Y0197R180 S2      
327m2180            U118  -2          A18X+042791Y+131024X0100Y0220R090 S2      
327m2180            VIA   -           A18X+042666Y+132532X0200Y         S2      
327m2180            VIA   -           A18X+042266Y+132532X0200Y         S2      
327m2180            VIA   -           A18X+042092Y+132060X0260Y         S2      
327m2180            U118  -31         A18X+042348Y+131467X0100Y0220R180 S2      
327m2180            C2703 -1   M      A18X+042538Y+132068X0198Y0197R180 S2      
327m2180            C2701 -1   M      A18X+042572Y+133136X0400Y0500     S2      
327PEX2_MODE_SEL1   PEX2  -AW38       A01X+119764Y+111260X0180Y         S1      
317PEX2_MODE_SEL1   VIA   -    MD0080PA00X+119951Y+111447X0160Y         S0      
317PEX2_MODE_SEL1   VIA   -    MD0100PA00X+161668Y+074452X0200Y         S0      
327PEX2_MODE_SEL1   R6440 -2          A01X+161668Y+074743X0198Y0197R270 S1      
317PEX2_MODE_SEL1   VIA   -    MD0100PA00X+150035Y+085986X0200Y         S0      
317PEX2_MODE_SEL1   VIA   -    M      A01X+107401Y+098881X0200Y         S2      
017PEX2_MODE_SEL1   VIA   -    M      A18X+107401Y+098881X0260Y         S2      
017PEX2_MODE_SEL1         -    MD0100PA00X+107401Y+098881                       
327PEX2_MODE_SEL1   R1357 -2          A01X+107401Y+099196X0198Y0197R270 S1      
327PEX2_MODE_SEL1   R1337 -1   M      A01X+107401Y+098611X0198Y0197R270 S1      
327m2181            R1711 -1          A01X+122702Y+008873X0198Y0197R090 S1      
327m2181            U136  -6          A01X+122494Y+008185X0170Y0460R180 S1      
317m2181            VIA   -    MD0100PA00X+122606Y+008605X0200Y    R180 S0      
317m2181            VIA   -    MD0100PA00X+126266Y+030273X0200Y         S0      
327m2181            R1595 -2          A01X+138103Y+033437X0198Y0197     S1      
327m2181            R1623 -1          A01X+138788Y+033437X0198Y0197     S1      
317m2181            VIA   -    M      A01X+138426Y+033437X0200Y         S2      
017m2181            VIA   -    M      A18X+138426Y+033437X0260Y         S2      
017m2181                  -    MD0100PA00X+138426Y+033437                       
327m2182            R1820 -2          A01X+109747Y+163500X0198Y0197R090 S1      
317m2182            VIA   -    M      A01X+109747Y+163775X0200Y    R090 S2      
017m2182            VIA   -    M      A18X+109747Y+163775X0260Y    R090 S2      
017m2182                  -    MD0100PA00X+109747Y+163775                       
317m2182            J14   -Z4   D0122PA00X+150429Y+145272X0282Y    R180 S3      
317m2182            VIA   -    MD0100PA00X+143590Y+134080X0200Y         S0      
317m2182            VIA   -    MD0100PA00X+104949Y+135069X0200Y         S0      
327SSD5_PWR_EN      VIA   -    M      A18X+136251Y+091249X0260Y         S2      
327SSD5_PWR_EN      R3564 -2          A18X+135850Y+091792X0198Y0197R090 S2      
327SSD5_PWR_EN      U6    -C17        A01X+136572Y+089129X0160Y         S1      
317SSD5_PWR_EN      VIA   -    MD0100PA00X+136730Y+089286X0180Y         S0      
327P3V3_NIC1_SS     PU48  -7          A01X+038099Y+047261X0110Y0240R270 S1      
317P3V3_NIC1_SS     VIA   -    M      A01X+038529Y+046641X0200Y         S2      
017P3V3_NIC1_SS     VIA   -    M      A18X+038529Y+046641X0260Y         S2      
017P3V3_NIC1_SS           -    MD0100PA00X+038529Y+046641                       
327P3V3_NIC1_SS     PC470 -1          A01X+038809Y+046641X0198Y0197     S1      
317m2183            VIA   -    MD0100PA00X+056240Y+081890X0200Y         S0      
327m2183            U106  -1          A18X+056080Y+082621X0140Y0440     S2      
327m2183            VIA   -    M      A18X+034450Y+074630X0260Y         S2      
317m2183            VIA   -    MD0100PA00X+037240Y+074630X0200Y         S0      
327m2183            R6628 -2          A01X+037601Y+074530X0198Y0197R180 S1      
317m2183            VIA   -    MD0100PA00X+025070Y+081990X0200Y         S0      
327m2183            R6635 -1          A01X+024946Y+081630X0198Y0197R180 S1      
317m2183            VIA   -    MD0100PA00X+057330Y+082960X0200Y         S0      
327m2183            R6643 -2          A01X+054240Y+084789X0198Y0197R090 S1      
327PEX2_MODE_SEL0   R1356 -2          A01X+103401Y+099196X0198Y0197R270 S1      
327PEX2_MODE_SEL0   R1336 -1          A01X+103401Y+098611X0198Y0197R270 S1      
317PEX2_MODE_SEL0   VIA   -    M      A01X+103401Y+098881X0200Y         S2      
017PEX2_MODE_SEL0   VIA   -    M      A18X+103401Y+098881X0260Y         S2      
017PEX2_MODE_SEL0         -    MD0100PA00X+103401Y+098881                       
327PEX2_MODE_SEL0   PEX2  -AW27       A01X+115650Y+111260X0180Y         S1      
317PEX2_MODE_SEL0   VIA   -    MD0080PA00X+115836Y+111447X0160Y         S0      
317m2184            VIA   -    MD0100PA00X+112370Y+008605X0200Y    R180 S0      
327m2184            R1698 -1          A01X+112466Y+008873X0198Y0197R090 S1      
327m2184            U135  -6          A01X+112258Y+008185X0170Y0460R180 S1      
327m2184            R1619 -1          A01X+138788Y+034337X0198Y0197     S1      
327m2184            R1593 -2          A01X+138103Y+034337X0198Y0197     S1      
317m2184            VIA   -    M      A01X+138363Y+034277X0200Y         S2      
017m2184            VIA   -    M      A18X+138363Y+034277X0260Y         S2      
017m2184                  -    MD0100PA00X+138363Y+034277                       
317m2184            VIA   -    MD0100PA00X+117990Y+030637X0200Y         S0      
317m2185            VIA   -    M      A01X+109694Y+162790X0200Y    R090 S2      
017m2185            VIA   -    M      A18X+109694Y+162790X0260Y    R090 S2      
017m2185                  -    MD0100PA00X+109694Y+162790                       
327m2185            U308  -2          A01X+109629Y+162152X0140Y0520R180 S1      
327m2185            R1814 -2          A01X+109347Y+163185X0198Y0197R270 S1      
327m2185            R1820 -1   M      A01X+109747Y+163185X0198Y0197R090 S1      
327m2186            R3985 -1          A01X+127192Y+113713X0198Y0197R090 S1      
317m2186            VIA   -    MD0100PA00X+127192Y+113473X0200Y         S0      
317m2186            VIA   -    M      A01X+133610Y+090504X0200Y         S2      
017m2186            VIA   -    M      A18X+133610Y+090504X0260Y         S2      
017m2186                  -    MD0100PA00X+133610Y+090504                       
327m2186            U6    -B8         A01X+133738Y+089444X0160Y         S1      
317m2186            VIA   -    MD0100PA00X+131287Y+103654X0200Y         S0      
327m2187            PU51  -8          A01X+141941Y+049565X0110Y0240R090 S1      
317m2187            VIA   -    M      A01X+141641Y+049565X0200Y    R180 S2      
017m2187            VIA   -    M      A18X+141641Y+049565X0260Y    R180 S2      
017m2187                  -    MD0100PA00X+141641Y+049565                       
327m2187            R4479 -1          A01X+141264Y+049198X0198Y0197R180 S1      
327m2187            R883  -2   M      A01X+141264Y+049598X0198Y0197     S1      
327m2188            R6643 -1          A01X+054240Y+084474X0198Y0197R090 S1      
317m2188            VIA   -           A01X+055674Y+082015X0200Y         S2      
017m2188            VIA   -           A18X+055674Y+082015X0260Y         S2      
017m2188                  -     D0100PA00X+055674Y+082015                       
327m2188            U98   -38  M      A01X+055436Y+083440X0110Y0540     S1      
317PEX2_DBG_MODE4   VIA   -    M      A01X+106582Y+098877X0200Y         S2      
017PEX2_DBG_MODE4   VIA   -    M      A18X+106582Y+098877X0260Y         S2      
017PEX2_DBG_MODE4         -    MD0100PA00X+106582Y+098877                       
327PEX2_DBG_MODE4   R1355 -2          A01X+106601Y+099196X0198Y0197R270 S1      
327PEX2_DBG_MODE4   R1335 -1          A01X+106601Y+098611X0198Y0197R270 S1      
327PEX2_DBG_MODE4   PEX2  -AW34       A01X+118268Y+111260X0180Y         S1      
317PEX2_DBG_MODE4   VIA   -    MD0080PA00X+118455Y+111447X0160Y         S0      
327m2189            U137  -6          A01X+132412Y+002861X0170Y0460R090 S1      
327m2189            R1712 -1          A01X+133100Y+002653X0198Y0197     S1      
317m2189            VIA   -    M      A01X+132832Y+002733X0200Y    R090 S2      
017m2189            VIA   -    M      A18X+132832Y+002733X0260Y    R090 S2      
017m2189                  -    MD0100PA00X+132832Y+002733                       
327m2189            R1600 -2          A01X+138103Y+032537X0198Y0197     S1      
327m2189            R1627 -1          A01X+138788Y+032537X0198Y0197     S1      
317m2189            VIA   -    MD0100PA00X+138426Y+032537X0200Y         S0      
317SSD7_PWRDIS      VIA   -    M      A01X+138752Y+090531X0200Y         S2      
017SSD7_PWRDIS      VIA   -    M      A18X+138752Y+090531X0260Y         S2      
017SSD7_PWRDIS            -    MD0100PA00X+138752Y+090531                       
327SSD7_PWRDIS      U6    -B21        A01X+137832Y+089444X0160Y         S1      
327SSD7_PWRDIS      R3593 -2          A01X+140100Y+091992X0198Y0197R270 S1      
317PEX2_DBG_MODE0   VIA   -    MD0080PA00X+109852Y+121545X0160Y         S0      
327PEX2_DBG_MODE0   R1331 -1          A01X+103726Y+122272X0198Y0197R225 S1      
327PEX2_DBG_MODE0   R1351 -2          A01X+104008Y+121990X0198Y0197R045 S1      
317PEX2_DBG_MODE0   VIA   -    MD0100PA00X+104359Y+122730X0200Y         S0      
327PEX2_DBG_MODE0   VIA   -    M      A18X+105018Y+121493X0260Y         S2      
327PEX2_DBG_MODE0   PEX2  -L12        A01X+110039Y+121732X0180Y         S1      
327m2190            R1713 -1          A01X+122307Y+008880X0198Y0197R090 S1      
327m2190            U136  -7          A01X+122238Y+008185X0170Y0460R180 S1      
317m2190            VIA   -    M      A01X+122251Y+008573X0200Y    R180 S2      
017m2190            VIA   -    M      A18X+122251Y+008573X0260Y    R180 S2      
017m2190                  -    MD0100PA00X+122251Y+008573                       
317m2190            VIA   -    MD0100PA00X+126696Y+030217X0200Y         S0      
327m2190            R1596 -2          A01X+138103Y+032987X0198Y0197     S1      
327m2190            R1625 -1          A01X+138788Y+032987X0198Y0197     S1      
317m2190            VIA   -    MD0100PA00X+138426Y+032987X0200Y         S0      
317GPU_BASE_ID1_R   J3    -Z8   D0122PA00X+017051Y+145272X0282Y    R180 S3      
317GPU_BASE_ID1_R   VIA   -    M      A01X+022190Y+148880X0200Y         S2      
017GPU_BASE_ID1_R   VIA   -    M      A18X+022190Y+148880X0260Y         S2      
017GPU_BASE_ID1_R         -    MD0100PA00X+022190Y+148880                       
327GPU_BASE_ID1_R   R1825 -1          A01X+022747Y+149044X0198Y0197     S1      
317m2191            VIA   -    M      A01X+110195Y+161471X0200Y    R090 S2      
017m2191            VIA   -    M      A18X+110195Y+161471X0260Y    R090 S2      
017m2191                  -    MD0100PA00X+110195Y+161471                       
327m2191            R1818 -2          A01X+108374Y+161471X0198Y0197R090 S1      
317m2191            J14   -Z8   D0122PA00X+153894Y+145272X0282Y    R180 S3      
317m2191            VIA   -    MD0100PA00X+144120Y+133870X0200Y         S0      
317m2191            VIA   -    MD0100PA00X+104608Y+135065X0200Y         S0      
317m2192            VIA   -    MD0100PA00X+073600Y+086427X0200Y         S0      
317m2192            VIA   -    MD0100PA00X+049507Y+083559X0200Y         S0      
327m2192            U105  -3          A18X+050127Y+083559X0140Y0440R270 S2      
327m2192            R986  -2          A18X+075521Y+114655X0198Y0197R090 S2      
327m2192            VIA   -    M      A18X+076673Y+114252X0260Y         S2      
327m2193            VIA   -    M      A01X+104150Y+031109X0300Y    R090 S1      
327m2193            R1049 -1          A01X+104565Y+030583X0198Y0197R270 S1      
327m2193            U113  -A29        A01X+103761Y+031912X0070Y0220R270 S1      
327m2193            R1059 -2   M      A01X+104150Y+030583X0198Y0197R090 S1      
327PEX2_MODE_SEL8   R1344 -1          A01X+104201Y+098611X0198Y0197R270 S1      
327PEX2_MODE_SEL8   R1364 -2          A01X+104201Y+099196X0198Y0197R270 S1      
317PEX2_MODE_SEL8   VIA   -    M      A01X+104201Y+098881X0200Y         S2      
017PEX2_MODE_SEL8   VIA   -    M      A18X+104201Y+098881X0260Y         S2      
017PEX2_MODE_SEL8         -    MD0100PA00X+104201Y+098881                       
327PEX2_MODE_SEL8   PEX2  -AW29       A01X+116398Y+111260X0180Y         S1      
317PEX2_MODE_SEL8   VIA   -    MD0080PA00X+116585Y+111447X0160Y         S0      
327m2194            R1621 -1          A01X+138788Y+033887X0198Y0197     S1      
327m2194            R1594 -2          A01X+138103Y+033887X0198Y0197     S1      
317m2194            VIA   -    MD0100PA00X+138355Y+033781X0200Y         S0      
317m2194            VIA   -    MD0100PA00X+117356Y+030495X0200Y         S0      
317m2194            VIA   -    M      A01X+112015Y+008573X0200Y    R180 S2      
017m2194            VIA   -    M      A18X+112015Y+008573X0260Y    R180 S2      
017m2194                  -    MD0100PA00X+112015Y+008573                       
327m2194            U135  -7          A01X+112002Y+008185X0170Y0460R180 S1      
327m2194            R1700 -1          A01X+112071Y+008880X0198Y0197R090 S1      
317m2195            VIA   -    MD0080PA00X+074242Y+114813X0160Y         S0      
327m2195            VIA   -    M      A18X+074429Y+115000X0260Y         S2      
327m2195            PEX1  -AJ38       A01X+074055Y+115000X0180Y         S1      
327m2195            R986  -1          A18X+075521Y+114970X0198Y0197R090 S2      
327m2196            VIA   -    M      A01X+105063Y+031454X0300Y    R090 S1      
327m2196            U113  -A30        A01X+103761Y+032109X0070Y0220R270 S1      
327m2196            R1050 -1          A01X+105565Y+031057X0198Y0197     S1      
327m2196            R1060 -2   M      A01X+105565Y+031454X0198Y0197R180 S1      
327PEX2_MODE_SEL6   PEX2  -AV31       A01X+117146Y+111634X0180Y         S1      
317PEX2_MODE_SEL6   VIA   -    MD0080PA00X+117333Y+111821X0160Y         S0      
327PEX2_MODE_SEL6   R1362 -2          A01X+105801Y+099196X0198Y0197R270 S1      
327PEX2_MODE_SEL6   R1342 -1          A01X+105801Y+098611X0198Y0197R270 S1      
317PEX2_MODE_SEL6   VIA   -    M      A01X+105801Y+098881X0200Y         S2      
017PEX2_MODE_SEL6   VIA   -    M      A18X+105801Y+098881X0260Y         S2      
017PEX2_MODE_SEL6         -    MD0100PA00X+105801Y+098881                       
327m2197            R1714 -1          A01X+133107Y+003048X0198Y0197     S1      
327m2197            U137  -7          A01X+132412Y+003117X0170Y0460R090 S1      
317m2197            VIA   -    M      A01X+132800Y+003240X0200Y    R090 S2      
017m2197            VIA   -    M      A18X+132800Y+003240X0260Y    R090 S2      
017m2197                  -    MD0100PA00X+132800Y+003240                       
327m2197            R1601 -2          A01X+138103Y+032087X0198Y0197     S1      
327m2197            R1629 -1          A01X+138788Y+032087X0198Y0197     S1      
317m2197            VIA   -    MD0100PA00X+138426Y+032087X0200Y         S0      
327m2198            R3546 -2          A01X+132650Y+091992X0198Y0197R270 S1      
327m2198            VIA   -    M      A01X+132650Y+091150X0300Y         S1      
327m2198            U6    -B5         A01X+132793Y+089444X0160Y         S1      
317P3V3_NIC3        VIA   -    MD0100PA00X+073195Y+044661X0200Y         S0      
327P3V3_NIC3        R163  -2          A18X+072902Y+044661X0198Y0197R180 S2      
317P3V3_NIC3        VIA   -    MD0100PA00X+071176Y+044587X0200Y         S0      
327P3V3_NIC3        R188  -2          A01X+070936Y+044587X0198Y0197     S1      
317P3V3_NIC3        VIA   -    MD0100PA00X+073204Y+044261X0200Y         S0      
327P3V3_NIC3        R162  -2          A18X+072902Y+044261X0198Y0197R180 S2      
317P3V3_NIC3        VIA   -    MD0100PA00X+076634Y+039791X0200Y         S0      
327P3V3_NIC3        R178  -2          A18X+076394Y+039791X0198Y0197R180 S2      
317P3V3_NIC3        VIA   -    MD0100PA00X+068535Y+039672X0200Y    R180 S0      
327P3V3_NIC3        R180  -2          A01X+068778Y+039672X0198Y0197R180 S1      
317P3V3_NIC3        VIA   -    MD0100PA00X+076634Y+038191X0200Y         S0      
327P3V3_NIC3        R165  -2          A18X+076394Y+038191X0198Y0197R180 S2      
317P3V3_NIC3        VIA   -    MD0100PA00X+076634Y+037791X0200Y         S0      
327P3V3_NIC3        R164  -2          A18X+076394Y+037791X0198Y0197R180 S2      
317P3V3_NIC3        VIA   -    MD0100PA00X+077194Y+031174X0200Y         S0      
327P3V3_NIC3        R202  -1          A01X+076935Y+031174X0198Y0197R090 S1      
327P3V3_NIC3        C904  -1   M      A01X+078412Y+030665X0198Y0197R180 S1      
327P3V3_NIC3        U27   -2          A01X+078451Y+031285X0400Y0500     S1      
317P3V3_NIC3        VIA   -    M      A01X+078412Y+030396X0200Y         S2      
017P3V3_NIC3        VIA   -    M      A18X+078412Y+030396X0260Y         S2      
017P3V3_NIC3              -    MD0100PA00X+078412Y+030396                       
327P3V3_NIC3        PU52  -1          A01X+082626Y+047745X0110Y0240R270 S1      
327P3V3_NIC3        PU52  -2          A01X+082626Y+047548X0110Y0240R270 S1      
327P3V3_NIC3        PU52  -3          A01X+082626Y+047351X0110Y0240R270 S1      
327P3V3_NIC3        PU52  -4          A01X+082626Y+047154X0110Y0240R270 S1      
327P3V3_NIC3        PU52  -5          A01X+082626Y+046957X0110Y0240R270 S1      
327P3V3_NIC3        VIA   -    M      A18X+075772Y+061747X0260Y         S2      
327P3V3_NIC3        VIA   -    M      A18X+076510Y+060054X0260Y         S2      
327P3V3_NIC3        VIA   -    M      A18X+076510Y+057283X0260Y         S2      
327P3V3_NIC3        PC488 -1          A01X+082141Y+047688X0198Y0197R090 S1      
327P3V3_NIC3        PC489 -1          A01X+081602Y+047602X0400Y0500R270 S1      
317P3V3_NIC3        VIA   -    MD0100PA00X+082081Y+047374X0200Y    R090 S0      
317P3V3_NIC3        VIA   -    MD0100PA00X+082354Y+047256X0200Y    R090 S0      
317P3V3_NIC3        VIA   -    MD0100PA00X+082354Y+047506X0200Y    R090 S0      
317P3V3_NIC3        VIA   -    MD0100PA00X+081076Y+047357X0200Y    R090 S0      
317P3V3_NIC3        VIA   -    MD0100PA00X+081076Y+047607X0200Y    R090 S0      
317P3V3_NIC3        VIA   -    MD0100PA00X+086147Y+048730X0200Y    R270 S0      
317P3V3_NIC3        VIA   -    MD0100PA00X+075039Y+045418X0200Y         S0      
317P3V3_NIC3        VIA   -    MD0100PA00X+075039Y+045168X0200Y         S0      
317P3V3_NIC3        VIA   -    MD0100PA00X+075289Y+045418X0200Y         S0      
317P3V3_NIC3        VIA   -    MD0100PA00X+075289Y+045168X0200Y         S0      
317P3V3_NIC3        VIA   -    MD0100PA00X+081483Y+047205X0200Y         S0      
317P3V3_NIC3        VIA   -    MD0100PA00X+081738Y+046881X0200Y         S0      
317P3V3_NIC3        VIA   -    MD0100PA00X+081458Y+046881X0200Y         S0      
317P3V3_NIC3        VIA   -    MD0100PA00X+081076Y+046857X0200Y    R090 S0      
317P3V3_NIC3        VIA   -    MD0100PA00X+081076Y+047107X0200Y    R090 S0      
317P3V3_NIC3        VIA   -    MD0100PA00X+082081Y+047124X0200Y    R090 S0      
317P3V3_NIC3        VIA   -    MD0100PA00X+081733Y+047205X0200Y         S0      
317P3V3_NIC3        VIA   -    MD0100PA00X+085075Y+046538X0200Y         S0      
327P3V3_NIC3        R884  -1          A01X+084833Y+046538X0198Y0197R180 S1      
327P3V3_NIC3        C898  -1          A18X+074713Y+045115X0198Y0197     S2      
327P3V3_NIC3        C899  -1          A18X+074713Y+045515X0198Y0197     S2      
327P3V3_NIC3        C900  -1          A18X+075559Y+045178X0198Y0197R090 S2      
327P3V3_NIC3        C897  -1          A18X+075954Y+045178X0198Y0197R090 S2      
327P3V3_NIC3        R5963 -1          A01X+086388Y+048730X0198Y0197     S1      
327P3V3_NIC3        PD58  -C          A01X+080542Y+047111X0670Y0990     S1      
327P3V3_NIC3        J23   -B11        A01X+074550Y+045368X0140Y0480R090 S1      
327P3V3_NIC3        PU102 -6_7        A01X+081781Y+045152X0295Y0354     S1      
317P3V3_NIC3        VIA   -    MD0100PA00X+081884Y+045606X0200Y    R090 S0      
327P3V3_NIC3        PC793 -1          A01X+081576Y+046033X0400Y0500R180 S1      
317P3V3_NIC3        VIA   -    MD0100PA00X+081584Y+045606X0200Y    R090 S0      
327P3V3_NIC3        R2473 -1          A01X+070436Y+062079X0198Y0197R090 S1      
317P3V3_NIC3        VIA   -    MD0100PA00X+070436Y+061829X0200Y    R180 S0      
327m2199            R1181 -2          A01X+135517Y+034712X0198Y0197R180 S1      
327m2199            U116  -33         A01X+134270Y+034553X0070Y0340R090 S1      
327m2200            VIA   -    M      A18X+117991Y+106461X0260Y         S2      
317m2200            VIA   -    MD0100PA00X+106201Y+098881X0200Y         S0      
327m2200            R1366 -2          A01X+106201Y+099196X0198Y0197R270 S1      
327m2200            R1346 -1          A01X+106201Y+098611X0198Y0197R270 S1      
327m2200            PEX2  -AV32       A01X+117520Y+111634X0180Y         S1      
317m2200            VIA   -    MD0080PA00X+117707Y+111821X0160Y         S0      
317m2201            VIA   -    MD0100PA00X+104536Y+027990X0200Y         S0      
327m2201            R1592 -2          A01X+138103Y+034787X0198Y0197     S1      
327m2201            R1617 -1          A01X+138788Y+034787X0198Y0197     S1      
317m2201            VIA   -    MD0100PA00X+138350Y+034944X0200Y         S0      
317m2201            VIA   -    M      A01X+101779Y+008573X0200Y    R180 S2      
017m2201            VIA   -    M      A18X+101779Y+008573X0260Y    R180 S2      
017m2201                  -    MD0100PA00X+101779Y+008573                       
327m2201            R1699 -1          A01X+101834Y+008880X0198Y0197R090 S1      
327m2201            U134  -7          A01X+101766Y+008185X0170Y0460R180 S1      
327m2202            C4013 -2   M      A01X+022108Y+148306X0198Y0197R090 S1      
317m2202            J3    -Z6   D0122PA00X+015319Y+145272X0282Y    R180 S3      
317m2202            VIA   -    M      A01X+021798Y+148306X0200Y         S2      
017m2202            VIA   -    M      A18X+021798Y+148306X0260Y         S2      
017m2202                  -    MD0100PA00X+021798Y+148306                       
327m2202            R1824 -2          A01X+022747Y+148644X0198Y0197R180 S1      
327SSD4_CLK_EN_N    VIA   -    M      A18X+135614Y+091036X0260Y         S2      
327SSD4_CLK_EN_N    R3556 -2          A18X+135050Y+091792X0198Y0197R090 S2      
327SSD4_CLK_EN_N    U6    -C15        A01X+135942Y+089129X0160Y         S1      
317SSD4_CLK_EN_N    VIA   -    MD0100PA00X+136100Y+089286X0180Y         S0      
317m2203            VIA   -    MD0100PA00X+038028Y+100607X0200Y         S0      
317m2203            VIA   -    MD0100PA00X+049468Y+083047X0200Y         S0      
327m2203            U105  -1          A18X+050127Y+083047X0140Y0440R270 S2      
317m2203            VIA   -    MD0100PA00X+048916Y+097716X0200Y         S0      
327m2203            R984  -2          A18X+029812Y+114655X0198Y0197R090 S2      
327m2203            VIA   -    M      A18X+030964Y+114252X0260Y         S2      
327m2204            R1174 -2          A01X+133401Y+031893X0198Y0197R090 S1      
327m2204            U116  -21         A01X+133502Y+032998X0070Y0340     S1      
317m2205            VIA   -    M      A01X+053195Y+038575X0200Y         S2      
017m2205            VIA   -    M      A18X+053195Y+038575X0260Y         S2      
017m2205                  -    MD0100PA00X+053195Y+038575                       
327m2205            U124  -22         A01X+052387Y+037969X0120Y0630R270 S1      
327m2205            R1574 -2          A01X+053561Y+038622X0198Y0197R180 S1      
327SSD3_PWR_EN      VIA   -    M      A18X+134350Y+091100X0260Y         S2      
327SSD3_PWR_EN      R3535 -2          A18X+134250Y+091792X0198Y0197R090 S2      
327SSD3_PWR_EN      U6    -C13        A01X+135312Y+089129X0160Y         S1      
317SSD3_PWR_EN      VIA   -    MD0100PA00X+135470Y+089286X0180Y         S0      
327P3V3_NIC6        C942  -1          A18X+155128Y+055440X0198Y0197R180 S2      
327P3V3_NIC6        C945  -1          A18X+155128Y+055040X0198Y0197R180 S2      
327P3V3_NIC6        VIA   -           A18X+153298Y+054606X0260Y         S2      
327P3V3_NIC6        VIA   -           A18X+151169Y+054680X0260Y         S2      
327P3V3_NIC6        VIA   -           A18X+148880Y+054792X0260Y         S2      
317P3V3_NIC6        VIA   -    MD0100PA00X+140691Y+049598X0200Y    R180 S0      
327P3V3_NIC6        R883  -1          A01X+140949Y+049598X0198Y0197     S1      
317P3V3_NIC6        VIA   -    MD0100PA00X+141890Y+046990X0200Y    R180 S0      
327P3V3_NIC6        R6050 -1          A01X+141890Y+046749X0198Y0197R270 S1      
327P3V3_NIC6        PU51  -1          A01X+143123Y+048778X0110Y0240R090 S1      
327P3V3_NIC6        PU51  -2          A01X+143123Y+048974X0110Y0240R090 S1      
327P3V3_NIC6        PU51  -3          A01X+143123Y+049171X0110Y0240R090 S1      
327P3V3_NIC6        PU51  -4          A01X+143123Y+049368X0110Y0240R090 S1      
327P3V3_NIC6        PU51  -5          A01X+143123Y+049565X0110Y0240R090 S1      
317P3V3_NIC6        VIA   -    MD0100PA00X+161995Y+067852X0200Y         S0      
327P3V3_NIC6        R355  -1          A01X+161995Y+067589X0198Y0197     S1      
317P3V3_NIC6        VIA   -    MD0100PA00X+161626Y+067846X0200Y         S0      
327P3V3_NIC6        U42   -2          A01X+161384Y+066991X0400Y0500R180 S1      
327P3V3_NIC6        C943  -1   M      A01X+161626Y+067583X0198Y0197R180 S1      
317P3V3_NIC6        VIA   -    MD0100PA00X+161336Y+065632X0200Y         S0      
327P3V3_NIC6        R2469 -1          A01X+161336Y+065382X0198Y0197R270 S1      
317P3V3_NIC6        VIA   -    MD0100PA00X+151918Y+062360X0200Y         S0      
327P3V3_NIC6        R317  -2          A01X+152168Y+062360X0198Y0197R180 S1      
317P3V3_NIC6        VIA   -    MD0100PA00X+088630Y+066665X0200Y         S0      
317P3V3_NIC6        VIA   -    M      A01X+156467Y+065012X0200Y         S2      
017P3V3_NIC6        VIA   -    M      A18X+156467Y+065012X0260Y         S2      
017P3V3_NIC6              -    MD0100PA00X+156467Y+065012                       
317P3V3_NIC6        VIA   -    MD0100PA00X+156238Y+061040X0200Y    R180 S0      
327P3V3_NIC6        R333  -2          A18X+156478Y+061040X0198Y0197     S2      
317P3V3_NIC6        VIA   -    MD0100PA00X+086700Y+077400X0200Y         S0      
327P3V3_NIC6        R1524 -2   M      A01X+086458Y+077400X0198Y0197     S1      
327P3V3_NIC6        R1523 -2   M      A01X+086458Y+077800X0198Y0197     S1      
327P3V3_NIC6        R1522 -2          A01X+086458Y+078200X0198Y0197     S1      
327P3V3_NIC6        U121  -8          A01X+085430Y+078384X0140Y0590R270 S1      
327P3V3_NIC6        C2627 -2   M      A01X+086142Y+078600X0198Y0197R180 S1      
317P3V3_NIC6        VIA   -    MD0100PA00X+086142Y+078850X0200Y         S0      
317P3V3_NIC6        VIA   -    MD0100PA00X+151918Y+061960X0200Y         S0      
327P3V3_NIC6        R318  -2          A01X+152168Y+061960X0198Y0197R180 S1      
317P3V3_NIC6        VIA   -    MD0100PA00X+151918Y+060360X0200Y         S0      
327P3V3_NIC6        R331  -2          A01X+152168Y+060360X0198Y0197R180 S1      
317P3V3_NIC6        VIA   -    MD0100PA00X+159530Y+055880X0200Y         S0      
327P3V3_NIC6        R341  -2          A01X+159828Y+055770X0198Y0197R180 S1      
327P3V3_NIC6        R316  -2          A01X+159284Y+055880X0198Y0197     S1      
317P3V3_NIC6        VIA   -    MD0100PA00X+159536Y+056280X0200Y         S0      
327P3V3_NIC6        R315  -2          A01X+159284Y+056280X0198Y0197     S1      
317P3V3_NIC6        VIA   -    MD0100PA00X+144039Y+046165X0200Y         S0      
317P3V3_NIC6        VIA   -    MD0100PA00X+144039Y+045915X0200Y         S0      
317P3V3_NIC6        VIA   -    MD0100PA00X+144289Y+046165X0200Y         S0      
317P3V3_NIC6        VIA   -    MD0100PA00X+144289Y+045915X0200Y         S0      
317P3V3_NIC6        VIA   -    MD0100PA00X+144289Y+045665X0200Y         S0      
317P3V3_NIC6        VIA   -    MD0100PA00X+144039Y+045665X0200Y         S0      
327P3V3_NIC6        PC911 -1          A01X+144190Y+045292X0400Y0500R090 S1      
327P3V3_NIC6        PU121 -6_7        A01X+143389Y+045249X0295Y0354R270 S1      
327P3V3_NIC6        J26   -B11        A01X+155253Y+055183X0140Y0480R270 S1      
327P3V3_NIC6        C949  -1          A01X+151422Y+054192X0198Y0197R270 S1      
327P3V3_NIC6        C944  -1          A01X+151023Y+054197X0198Y0197R270 S1      
327P3V3_NIC6        PD57  -C          A01X+145463Y+049610X0670Y0990R180 S1      
317P3V3_NIC6        VIA   -    MD0100PA00X+144522Y+049515X0200Y    R180 S0      
317P3V3_NIC6        VIA   -    MD0100PA00X+144929Y+049863X0200Y    R270 S0      
317P3V3_NIC6        VIA   -    MD0100PA00X+144929Y+049613X0200Y    R270 S0      
317P3V3_NIC6        VIA   -    MD0100PA00X+144929Y+049363X0200Y    R270 S0      
317P3V3_NIC6        VIA   -    MD0100PA00X+144522Y+049815X0200Y    R180 S0      
317P3V3_NIC6        VIA   -    MD0100PA00X+143766Y+049549X0200Y    R270 S0      
317P3V3_NIC6        VIA   -    MD0100PA00X+143396Y+049371X0200Y    R270 S0      
317P3V3_NIC6        VIA   -    MD0100PA00X+144242Y+049815X0200Y    R180 S0      
317P3V3_NIC6        VIA   -    MD0100PA00X+143766Y+049299X0200Y    R270 S0      
317P3V3_NIC6        VIA   -    MD0100PA00X+144272Y+049515X0200Y    R180 S0      
327P3V3_NIC6        PC478 -1          A01X+143760Y+049024X0198Y0197R270 S1      
327P3V3_NIC6        PC479 -1          A01X+144382Y+049131X0400Y0500R090 S1      
317P3V3_NIC6        VIA   -    MD0100PA00X+144929Y+049113X0200Y    R270 S0      
317P3V3_NIC6        VIA   -    MD0100PA00X+143396Y+049121X0200Y    R270 S0      
317P3V3_NIC6        VIA   -    MD0100PA00X+154688Y+055091X0200Y         S0      
317P3V3_NIC6        VIA   -    MD0100PA00X+154438Y+055091X0200Y         S0      
317P3V3_NIC6        VIA   -    MD0100PA00X+154688Y+055341X0200Y         S0      
317P3V3_NIC6        VIA   -    MD0100PA00X+154438Y+055341X0200Y         S0      
317m2206            VIA   -    MD0080PA00X+028533Y+114813X0160Y         S0      
327m2206            VIA   -    M      A18X+028720Y+115000X0260Y         S2      
327m2206            R984  -1          A18X+029812Y+114970X0198Y0197R090 S2      
327m2206            PEX0  -AJ38       A01X+028346Y+115000X0180Y         S1      
327m2207            R1177 -2          A01X+135517Y+033138X0198Y0197R180 S1      
327m2207            U116  -26         A01X+134270Y+033450X0070Y0340R090 S1      
327PEX2_MODE_SEL3   PEX2  -AV27       A01X+115650Y+111634X0180Y         S1      
317PEX2_MODE_SEL3   VIA   -    MD0080PA00X+115836Y+111821X0160Y         S0      
327PEX2_MODE_SEL3   VIA   -    M      A18X+114717Y+105876X0260Y         S2      
327PEX2_MODE_SEL3   R1359 -2          A01X+103001Y+099196X0198Y0197R270 S1      
327PEX2_MODE_SEL3   R1339 -1          A01X+103001Y+098611X0198Y0197R270 S1      
317PEX2_MODE_SEL3   VIA   -    MD0100PA00X+103001Y+098881X0200Y         S0      
317m2208            VIA   -    MD0080PA00X+120325Y+118179X0160Y         S0      
327m2208            VIA   -           A18X+121018Y+118551X0260Y         S2      
327m2208            R1380 -1   M      A18X+120562Y+118396X0198Y0197R270 S2      
327m2208            PEX2  -Y39        A01X+120138Y+118366X0180Y         S1      
317m2209            VIA   -    M      A01X+053319Y+039072X0200Y         S2      
017m2209            VIA   -    M      A18X+053319Y+039072X0260Y         S2      
017m2209                  -    MD0100PA00X+053319Y+039072                       
327m2209            U124  -23         A01X+052387Y+038225X0120Y0630R270 S1      
327m2209            R1573 -2          A01X+053561Y+039072X0198Y0197R180 S1      
327SSD0_CLK_EN_N    VIA   -    M      A01X+133450Y+091164X0300Y         S1      
327SSD0_CLK_EN_N    R3586 -1          A01X+133450Y+091992X0198Y0197R090 S1      
327SSD0_CLK_EN_N    U6    -B10        A01X+134368Y+089444X0160Y         S1      
327m2210            R1172 -2          A01X+132614Y+031893X0198Y0197R090 S1      
327m2210            U116  -16         A01X+132715Y+032998X0070Y0340     S1      
327m2211            PEX2  -AW31       A01X+117146Y+111260X0180Y         S1      
317m2211            VIA   -    MD0080PA00X+117333Y+111447X0160Y         S0      
327m2211            R1367 -2          A01X+105001Y+099196X0198Y0197R270 S1      
327m2211            R1347 -1          A01X+105001Y+098611X0198Y0197R270 S1      
317m2211            VIA   -    M      A01X+105001Y+098881X0200Y         S2      
017m2211            VIA   -    M      A18X+105001Y+098881X0260Y         S2      
017m2211                  -    MD0100PA00X+105001Y+098881                       
317m2212            VIA   -    MD0080PA00X+119951Y+117805X0160Y         S0      
327m2212            VIA   -           A18X+121062Y+117847X0260Y         S2      
327m2212            R1381 -1   M      A18X+120562Y+117962X0198Y0197R090 S2      
327m2212            PEX2  -AA39       A01X+120138Y+117992X0180Y         S1      
327m2213            R1614 -2          A01X+054876Y+038622X0198Y0197     S1      
317m2213            VIA   -    M      A01X+055356Y+038499X0200Y         S2      
017m2213            VIA   -    M      A18X+055356Y+038499X0260Y         S2      
017m2213                  -    MD0100PA00X+055356Y+038499                       
327m2213            U125  -22         A01X+142641Y+034947X0120Y0630R270 S1      
317m2213            VIA   -    MD0100PA00X+141647Y+038140X0200Y         S0      
317CLK_25M_FPGA     VIA   -    M      A01X+130214Y+081262X0200Y    R180 S2      
017CLK_25M_FPGA     VIA   -    M      A18X+130214Y+081262X0260Y    R180 S2      
017CLK_25M_FPGA           -    MD0100PA00X+130214Y+081262                       
327CLK_25M_FPGA     R4405 -2          A01X+129891Y+081552X0198Y0197R270 S1      
327CLK_25M_FPGA     OSC1  -3          A01X+130541Y+080788X0400Y0480R090 S1      
327P3V3_NIC2        R112  -1          A01X+067866Y+055880X0198Y0197R180 S1      
327P3V3_NIC2        R111  -1          A01X+067866Y+056280X0198Y0197R180 S1      
327P3V3_NIC2        PU50  -1          A01X+051705Y+048778X0110Y0240R090 S1      
327P3V3_NIC2        PU50  -2          A01X+051705Y+048974X0110Y0240R090 S1      
327P3V3_NIC2        PU50  -3          A01X+051705Y+049171X0110Y0240R090 S1      
327P3V3_NIC2        PU50  -4          A01X+051705Y+049368X0110Y0240R090 S1      
327P3V3_NIC2        PU50  -5          A01X+051705Y+049565X0110Y0240R090 S1      
327P3V3_NIC2        R151  -1          A01X+070578Y+067589X0198Y0197     S1      
317P3V3_NIC2        VIA   -    MD0100PA00X+070578Y+067852X0200Y         S0      
327P3V3_NIC2        C882  -1   M      A01X+070209Y+067583X0198Y0197R180 S1      
327P3V3_NIC2        U22   -2          A01X+069967Y+066991X0400Y0500R180 S1      
317P3V3_NIC2        VIA   -    MD0100PA00X+070209Y+067846X0200Y         S0      
327P3V3_NIC2        R2465 -1          A01X+069919Y+065382X0198Y0197R270 S1      
317P3V3_NIC2        VIA   -    MD0100PA00X+069919Y+065632X0200Y         S0      
327P3V3_NIC2        R113  -2          A01X+060751Y+062360X0198Y0197R180 S1      
317P3V3_NIC2        VIA   -    MD0100PA00X+060501Y+062360X0200Y         S0      
327P3V3_NIC2        R129  -2          A18X+065061Y+061040X0198Y0197     S2      
317P3V3_NIC2        VIA   -    MD0100PA00X+064821Y+061040X0200Y    R180 S0      
327P3V3_NIC2        R114  -2          A01X+060751Y+061960X0198Y0197R180 S1      
317P3V3_NIC2        VIA   -    MD0100PA00X+060501Y+061960X0200Y         S0      
327P3V3_NIC2        R127  -2          A01X+060751Y+060360X0198Y0197R180 S1      
317P3V3_NIC2        VIA   -    MD0100PA00X+060501Y+060360X0200Y         S0      
317P3V3_NIC2        VIA   -    MD0100PA00X+068119Y+056280X0200Y         S0      
327P3V3_NIC2        R137  -2          A01X+068411Y+055770X0198Y0197R180 S1      
317P3V3_NIC2        VIA   -    MD0100PA00X+068113Y+055880X0200Y         S0      
317P3V3_NIC2        VIA   -    M      A01X+050473Y+046990X0200Y    R180 S2      
017P3V3_NIC2        VIA   -    M      A18X+050473Y+046990X0260Y    R180 S2      
017P3V3_NIC2              -    MD0100PA00X+050473Y+046990                       
327P3V3_NIC2        R5962 -1          A01X+050473Y+046749X0198Y0197R270 S1      
317P3V3_NIC2        VIA   -    MD0100PA00X+052872Y+046165X0200Y         S0      
317P3V3_NIC2        VIA   -    MD0100PA00X+052872Y+045915X0200Y         S0      
317P3V3_NIC2        VIA   -    MD0100PA00X+052622Y+046165X0200Y         S0      
317P3V3_NIC2        VIA   -    MD0100PA00X+052622Y+045915X0200Y         S0      
317P3V3_NIC2        VIA   -    MD0100PA00X+052872Y+045665X0200Y         S0      
317P3V3_NIC2        VIA   -    MD0100PA00X+052622Y+045665X0200Y         S0      
327P3V3_NIC2        PC791 -1          A01X+052773Y+045292X0400Y0500R090 S1      
327P3V3_NIC2        PU101 -6_7        A01X+051972Y+045249X0295Y0354R270 S1      
327P3V3_NIC2        J22   -B11        A01X+063836Y+055183X0140Y0480R270 S1      
327P3V3_NIC2        C889  -1          A01X+060005Y+054192X0198Y0197R270 S1      
327P3V3_NIC2        C883  -1          A01X+059606Y+054197X0198Y0197R270 S1      
327P3V3_NIC2        PD56  -C          A01X+054046Y+049610X0670Y0990R180 S1      
327P3V3_NIC2        PC477 -1          A01X+052965Y+049131X0400Y0500R090 S1      
327P3V3_NIC2        PC476 -1          A01X+052343Y+049024X0198Y0197R270 S1      
327P3V3_NIC2        C885  -1          A18X+063711Y+055040X0198Y0197R180 S2      
327P3V3_NIC2        C884  -1          A18X+063711Y+055440X0198Y0197R180 S2      
317P3V3_NIC2        VIA   -    MD0100PA00X+063270Y+055091X0200Y         S0      
317P3V3_NIC2        VIA   -    MD0100PA00X+063020Y+055091X0200Y         S0      
317P3V3_NIC2        VIA   -    MD0100PA00X+063270Y+055341X0200Y         S0      
317P3V3_NIC2        VIA   -    MD0100PA00X+063020Y+055341X0200Y         S0      
327P3V3_NIC2        VIA   -           A18X+061880Y+054606X0260Y         S2      
327P3V3_NIC2        VIA   -           A18X+059752Y+054680X0260Y         S2      
327P3V3_NIC2        VIA   -           A18X+057462Y+054792X0260Y         S2      
317P3V3_NIC2        VIA   -    MD0100PA00X+052825Y+049815X0200Y    R180 S0      
317P3V3_NIC2        VIA   -    MD0100PA00X+052855Y+049515X0200Y    R180 S0      
317P3V3_NIC2        VIA   -    MD0100PA00X+053105Y+049515X0200Y    R180 S0      
317P3V3_NIC2        VIA   -    MD0100PA00X+053512Y+049863X0200Y    R270 S0      
317P3V3_NIC2        VIA   -    MD0100PA00X+053512Y+049613X0200Y    R270 S0      
317P3V3_NIC2        VIA   -    MD0100PA00X+053512Y+049363X0200Y    R270 S0      
317P3V3_NIC2        VIA   -    MD0100PA00X+053105Y+049815X0200Y    R180 S0      
317P3V3_NIC2        VIA   -    MD0100PA00X+052349Y+049549X0200Y    R270 S0      
317P3V3_NIC2        VIA   -    MD0100PA00X+051979Y+049371X0200Y    R270 S0      
317P3V3_NIC2        VIA   -    MD0100PA00X+052349Y+049299X0200Y    R270 S0      
317P3V3_NIC2        VIA   -    MD0100PA00X+049274Y+049598X0200Y    R180 S0      
327P3V3_NIC2        R882  -1          A01X+049532Y+049598X0198Y0197     S1      
317P3V3_NIC2        VIA   -    MD0100PA00X+053512Y+049113X0200Y    R270 S0      
317P3V3_NIC2        VIA   -    MD0100PA00X+051979Y+049121X0200Y    R270 S0      
327m2214            R1170 -2          A01X+131826Y+031893X0198Y0197R090 S1      
327m2214            U116  -13         A01X+132242Y+032998X0070Y0340     S1      
327PEX2_MODE_SEL9   PEX2  -AV28       A01X+116024Y+111634X0180Y         S1      
317PEX2_MODE_SEL9   VIA   -    MD0080PA00X+116211Y+111821X0160Y         S0      
327PEX2_MODE_SEL9   R1365 -2          A01X+101001Y+099196X0198Y0197R270 S1      
327PEX2_MODE_SEL9   R1345 -1          A01X+101001Y+098611X0198Y0197R270 S1      
317PEX2_MODE_SEL9   VIA   -    M      A01X+100956Y+098887X0200Y         S2      
017PEX2_MODE_SEL9   VIA   -    M      A18X+100956Y+098887X0260Y         S2      
017PEX2_MODE_SEL9         -    MD0100PA00X+100956Y+098887                       
327m2215            U125  -3          A01X+140436Y+034947X0120Y0630R270 S1      
317m2215            VIA   -    M      A01X+140885Y+038121X0200Y         S2      
017m2215            VIA   -    M      A18X+140885Y+038121X0260Y         S2      
017m2215                  -    MD0100PA00X+140885Y+038121                       
317m2215            VIA   -    MD0100PA00X+089853Y+033450X0200Y         S0      
327m2215            R5719 -1          A01X+084273Y+083546X0198Y0197     S1      
317m2215            VIA   -    MD0100PA00X+083684Y+083130X0200Y         S0      
327m2216            R1613 -2          A01X+054876Y+039072X0198Y0197     S1      
317m2216            VIA   -    M      A01X+055162Y+039072X0200Y         S2      
017m2216            VIA   -    M      A18X+055162Y+039072X0260Y         S2      
017m2216                  -    MD0100PA00X+055162Y+039072                       
327m2216            U125  -23         A01X+142641Y+035203X0120Y0630R270 S1      
317m2216            VIA   -    MD0100PA00X+141691Y+038690X0200Y         S0      
327SSD2_PWRDIS      R3523 -1          A01X+131850Y+091992X0198Y0197R090 S1      
327SSD2_PWRDIS      U6    -A5         A01X+132793Y+089759X0160Y         S1      
327SSD2_PWRDIS      VIA   -    M      A01X+132250Y+091530X0300Y         S1      
327P3V3_NIC4_SS     PU47  -7          A01X+096233Y+049762X0110Y0240R090 S1      
317P3V3_NIC4_SS     VIA   -    M      A01X+095798Y+050020X0200Y    R180 S2      
017P3V3_NIC4_SS     VIA   -    M      A18X+095798Y+050020X0260Y    R180 S2      
017P3V3_NIC4_SS           -    MD0100PA00X+095798Y+050020                       
327P3V3_NIC4_SS     PC459 -1          A01X+095555Y+049998X0198Y0197R180 S1      
327m2217            U98   -27         A01X+057198Y+081679X0110Y0540R090 S1      
317m2217            VIA   -    M      A01X+054488Y+081631X0200Y         S2      
017m2217            VIA   -    M      A18X+054488Y+081631X0260Y         S2      
017m2217                  -    MD0100PA00X+054488Y+081631                       
327m2217            R987  -2          A18X+052532Y+083615X0198Y0197R180 S2      
327m2217            R983  -1   M      A18X+052917Y+083615X0198Y0197R180 S2      
327m2218            VIA   -    M      A18X+051065Y+070381X0200Y         S2      
317m2218            VIA   -    MD0100PA00X+051550Y+070135X0193Y         S0      
327m2218            U114  -E2         A01X+051367Y+070236X0090Y         S1      
327m2218            R1124 -1          A18X+050646Y+070876X0198Y0197     S2      
327m2218            R1125 -2   M      A18X+050646Y+070476X0198Y0197R180 S2      
327m2219            R1183 -2          A01X+135517Y+035500X0198Y0197R180 S1      
327m2219            U116  -36         A01X+134270Y+035025X0070Y0340R090 S1      
317PEX2_DBG_SEL0    VIA   -    MD0080PA00X+112096Y+121545X0160Y         S0      
317PEX2_DBG_SEL0    VIA   -    M      A01X+102622Y+121437X0200Y    R315 S2      
017PEX2_DBG_SEL0    VIA   -    M      A18X+102622Y+121437X0260Y    R315 S2      
017PEX2_DBG_SEL0          -    MD0100PA00X+102622Y+121437                       
327PEX2_DBG_SEL0    R1349 -2          A01X+102594Y+121011X0198Y0197R045 S1      
327PEX2_DBG_SEL0    R1329 -1   M      A01X+102311Y+121294X0198Y0197R225 S1      
327PEX2_DBG_SEL0    PEX2  -L18        A01X+112283Y+121732X0180Y         S1      
327m2220            VIA   -    M      A01X+086309Y+086766X0300Y         S1      
327m2220            U5    -K16        A01X+087979Y+086576X0160Y    R180 S1      
327m2220            R1493 -1          A01X+085683Y+087146X0198Y0197R180 S1      
317m2221            VIA   -    MD0100PA00X+041100Y+146050X0200Y         S0      
317m2221            VIA   -    M      A01X+025079Y+153976X0200Y         S2      
017m2221            VIA   -    M      A18X+025079Y+153976X0260Y         S2      
017m2221                  -    MD0100PA00X+025079Y+153976                       
317m2221            J3    -A5   D0122PA00X+014453Y+162240X0282Y    R180 S3      
317m2221            VIA   -    MD0100PA00X+078679Y+143380X0200Y         S0      
327m2221            R1867 -2          A18X+119243Y+087124X0198Y0197R090 S2      
317m2221            VIA   -    MD0100PA00X+119243Y+086862X0200Y    R090 S0      
317m2221            VIA   -    MD0100PA00X+107892Y+085670X0200Y         S0      
327SSD7_PWR_EN      VIA   -    M      A01X+138200Y+091150X0300Y         S1      
327SSD7_PWR_EN      U6    -A20        A01X+137517Y+089759X0160Y         S1      
327SSD7_PWR_EN      R3592 -2          A01X+138250Y+091992X0198Y0197R270 S1      
327m2222            R1178 -2          A01X+135517Y+033565X0198Y0197R180 S1      
327m2222            U116  -28         A01X+134270Y+033766X0070Y0340R090 S1      
327PEX2_DBG_MODE2   PEX2  -AW30       A01X+116772Y+111260X0180Y         S1      
317PEX2_DBG_MODE2   VIA   -    MD0080PA00X+116959Y+111447X0160Y         S0      
327PEX2_DBG_MODE2   VIA   -    M      A18X+115477Y+105332X0260Y         S2      
327PEX2_DBG_MODE2   R1353 -2          A01X+104601Y+099196X0198Y0197R270 S1      
327PEX2_DBG_MODE2   R1333 -1          A01X+104601Y+098611X0198Y0197R270 S1      
317PEX2_DBG_MODE2   VIA   -    MD0100PA00X+104601Y+098881X0200Y         S0      
327m2223            VIA   -    M      A01X+086812Y+087030X0300Y         S1      
327m2223            R1491 -1          A01X+085683Y+087546X0198Y0197R180 S1      
327m2223            U5    -L16        A01X+087979Y+086891X0160Y    R180 S1      
327m2224            U6    -B6         A01X+133108Y+089444X0160Y         S1      
317m2224            VIA   -    MD0100PA00X+133106Y+090456X0200Y         S0      
327m2224            D21   -C          A01X+127326Y+089565X0240Y0280R180 S1      
317m2224            VIA   -    M      A01X+127426Y+089859X0200Y         S2      
017m2224            VIA   -    M      A18X+127426Y+089859X0260Y         S2      
017m2224                  -    MD0100PA00X+127426Y+089859                       
327P3V3_NIC7_OCP    PR254 -1          A01X+175935Y+047838X0198Y0197     S1      
327P3V3_NIC7_OCP    PU53  -9          A01X+175225Y+047654X0110Y0240R270 S1      
317P3V3_NIC7_OCP    VIA   -    M      A01X+175695Y+047732X0200Y    R090 S2      
017P3V3_NIC7_OCP    VIA   -    M      A18X+175695Y+047732X0260Y    R090 S2      
017P3V3_NIC7_OCP          -    MD0100PA00X+175695Y+047732                       
327m2225            R1171 -2          A01X+132186Y+031893X0198Y0197R090 S1      
327m2225            U116  -14         A01X+132400Y+032998X0070Y0340     S1      
327m2226            VIA   -           A18X+044115Y+131996X0260Y         S2      
327m2226            U118  -32         A18X+042545Y+131467X0100Y0220R180 S2      
327m2226            R1223 -1   M      A18X+043248Y+131922X0198Y0197R270 S2      
327m2226            R1220 -2   M      A18X+043648Y+131922X0198Y0197R090 S2      
327m2227            PEX2  -AW32       A01X+117520Y+111260X0180Y         S1      
317m2227            VIA   -    MD0080PA00X+117707Y+111447X0160Y         S0      
327m2227            VIA   -    M      A18X+116434Y+105579X0260Y         S2      
327m2227            R1368 -2          A01X+105401Y+099196X0198Y0197R270 S1      
327m2227            R1348 -1          A01X+105401Y+098611X0198Y0197R270 S1      
317m2227            VIA   -    MD0100PA00X+105401Y+098881X0200Y         S0      
327m2228            R4885 -1          A01X+083631Y+087401X0198Y0197R090 S1      
317m2228            VIA   -    M      A01X+054171Y+038622X0200Y         S2      
017m2228            VIA   -    M      A18X+054171Y+038622X0260Y         S2      
017m2228                  -    MD0100PA00X+054171Y+038622                       
327m2228            R1574 -1          A01X+053876Y+038622X0198Y0197R180 S1      
327m2228            R1614 -1          A01X+054561Y+038622X0198Y0197     S1      
317m2228            VIA   -    MD0100PA00X+085607Y+035643X0200Y         S0      
327m2228            R1491 -2          A01X+085368Y+087546X0198Y0197R180 S1      
317m2228            VIA   -    MD0100PA00X+085118Y+087546X0200Y         S0      
317m2229            J3    -Z4   D0122PA00X+013587Y+145272X0282Y    R180 S3      
317m2229            VIA   -    M      A01X+022478Y+147815X0200Y         S2      
017m2229            VIA   -    M      A18X+022478Y+147815X0260Y         S2      
017m2229                  -    MD0100PA00X+022478Y+147815                       
327m2229            R1870 -1          A01X+022747Y+148244X0198Y0197     S1      
317m2230            VIA   -    M      A01X+054474Y+080965X0200Y         S2      
017m2230            VIA   -    M      A18X+054474Y+080965X0260Y         S2      
017m2230                  -    MD0100PA00X+054474Y+080965                       
327m2230            R985  -2          A18X+052528Y+083103X0198Y0197R180 S2      
327m2230            R982  -1   M      A18X+052913Y+083103X0198Y0197R180 S2      
327m2230            U98   -17         A01X+057198Y+079710X0110Y0540R090 S1      
327m2231            R1173 -2          A01X+132974Y+031893X0198Y0197R090 S1      
327m2231            U116  -17         A01X+132872Y+032998X0070Y0340     S1      
317m2232            VIA   -    MD0100PA00X+085257Y+035671X0200Y         S0      
317m2232            VIA   -    MD0100PA00X+085118Y+087146X0200Y         S0      
327m2232            R4886 -1          A01X+084334Y+087146X0198Y0197R180 S1      
327m2232            R1493 -2          A01X+085368Y+087146X0198Y0197R180 S1      
317m2232            VIA   -    M      A01X+054203Y+039221X0200Y         S2      
017m2232            VIA   -    M      A18X+054203Y+039221X0260Y         S2      
017m2232                  -    MD0100PA00X+054203Y+039221                       
327m2232            R1573 -1          A01X+053876Y+039072X0198Y0197R180 S1      
327m2232            R1613 -1          A01X+054561Y+039072X0198Y0197     S1      
327m2233            J31   -A7         A01X+014435Y+008815X0150Y0500R090 S1      
317m2233            VIA   -    M      A01X+015391Y+009062X0200Y         S2      
017m2233            VIA   -    M      A18X+015391Y+009062X0260Y         S2      
017m2233                  -    MD0100PA00X+015391Y+009062                       
327m2233            R1638 -1          A01X+019397Y+007259X0198Y0197     S1      
317m2233            VIA   -    MD0100PA00X+019157Y+007262X0200Y         S0      
327m2234            U114  -B4         A01X+051760Y+070827X0090Y         S1      
327m2234            VIA   -    M      A18X+051168Y+071280X0260Y         S2      
327m2234            R1120 -1          A18X+050579Y+071734X0198Y0197R270 S2      
327m2234            R1122 -2   M      A18X+050979Y+071734X0198Y0197R090 S2      
317m2234            VIA   -    MD0100PA00X+051839Y+070639X0193Y         S0      
327m2235            R1176 -2          A01X+135517Y+032778X0198Y0197R180 S1      
327m2235            U116  -25         A01X+134270Y+033293X0070Y0340R090 S1      
317PEX2_DBG_MODE3   VIA   -    M      A01X+102601Y+098881X0200Y         S2      
017PEX2_DBG_MODE3   VIA   -    M      A18X+102601Y+098881X0260Y         S2      
017PEX2_DBG_MODE3         -    MD0100PA00X+102601Y+098881                       
327PEX2_DBG_MODE3   R1354 -2          A01X+102601Y+099196X0198Y0197R270 S1      
327PEX2_DBG_MODE3   R1334 -1          A01X+102601Y+098611X0198Y0197R270 S1      
327PEX2_DBG_MODE3   PEX2  -AW26       A01X+115276Y+111260X0180Y         S1      
317PEX2_DBG_MODE3   VIA   -    MD0080PA00X+115462Y+111447X0160Y         S0      
317m2236            VIA   -    M      A01X+144118Y+035491X0200Y         S2      
017m2236            VIA   -    M      A18X+144118Y+035491X0260Y         S2      
017m2236                  -    MD0100PA00X+144118Y+035491                       
327m2236            U125  -21         A01X+142641Y+034691X0120Y0630R270 S1      
327m2236            R1599 -2   M      A01X+144313Y+035686X0198Y0197R180 S1      
327m2236            R1609 -1          A01X+145313Y+035686X0198Y0197     S1      
327m2237            J37   -A7         A01X+080616Y+008815X0150Y0500R090 S1      
317m2237            VIA   -    M      A01X+081572Y+009062X0200Y         S2      
017m2237            VIA   -    M      A18X+081572Y+009062X0260Y         S2      
017m2237                  -    MD0100PA00X+081572Y+009062                       
317m2237            VIA   -    MD0100PA00X+085338Y+007262X0200Y         S0      
327m2237            R1680 -1          A01X+085578Y+007259X0198Y0197     S1      
327m2238            VIA   -    M      A18X+057750Y+081155X0260Y    R270 S2      
327m2238            R981  -1          A18X+057750Y+081647X0198Y0197R270 S2      
327m2238            U104  -4          A18X+058094Y+080498X0140Y0440     S2      
327m2239            R1179 -2          A01X+135517Y+033925X0198Y0197R180 S1      
327m2239            U116  -29         A01X+134270Y+033923X0070Y0340R090 S1      
327m2240            VIA   -    M      A01X+104594Y+033253X0300Y    R090 S1      
327m2240            U113  -B27        A01X+103465Y+032995X0110Y0180R270 S1      
327m2240            R1057 -1          A01X+105554Y+034351X0198Y0197     S1      
327m2240            R1069 -2   M      A01X+105554Y+033951X0198Y0197R180 S1      
327PEX2_MODE_SEL4   VIA   -    M      A18X+114449Y+105004X0260Y         S2      
327PEX2_MODE_SEL4   R1360 -2          A01X+103801Y+099196X0198Y0197R270 S1      
327PEX2_MODE_SEL4   R1340 -1          A01X+103801Y+098611X0198Y0197R270 S1      
317PEX2_MODE_SEL4   VIA   -    MD0100PA00X+103801Y+098881X0200Y         S0      
327PEX2_MODE_SEL4   PEX2  -AW28       A01X+116024Y+111260X0180Y         S1      
317PEX2_MODE_SEL4   VIA   -    MD0080PA00X+116211Y+111447X0160Y         S0      
317m2241            VIA   -    M      A01X+139573Y+036053X0200Y         S2      
017m2241            VIA   -    M      A18X+139573Y+036053X0260Y         S2      
017m2241                  -    MD0100PA00X+139573Y+036053                       
327m2241            R1598 -2          A01X+138103Y+035687X0198Y0197     S1      
327m2241            U125  -2          A01X+140436Y+035203X0120Y0630R270 S1      
327m2241            R1608 -1   M      A01X+139103Y+035687X0198Y0197R180 S1      
317m2242            VIA   -    M      A01X+102620Y+008601X0200Y    R180 S2      
017m2242            VIA   -    M      A18X+102620Y+008601X0260Y    R180 S2      
017m2242                  -    MD0100PA00X+102620Y+008601                       
327m2242            R1687 -1          A01X+102620Y+008882X0198Y0197R090 S1      
327m2242            U134  -5          A01X+102307Y+008185X0240Y0460R180 S1      
327m2243            J36   -A7         A01X+070380Y+008815X0150Y0500R090 S1      
317m2243            VIA   -    M      A01X+071336Y+009062X0200Y         S2      
017m2243            VIA   -    M      A18X+071336Y+009062X0260Y         S2      
017m2243                  -    MD0100PA00X+071336Y+009062                       
327m2243            R1679 -1          A01X+075342Y+007256X0198Y0197     S1      
317m2243            VIA   -    MD0100PA00X+075102Y+007262X0200Y         S0      
327m2244            PU50  -8          A01X+050524Y+049565X0110Y0240R090 S1      
317m2244            VIA   -    M      A01X+050249Y+049592X0200Y    R180 S2      
017m2244            VIA   -    M      A18X+050249Y+049592X0260Y    R180 S2      
017m2244                  -    MD0100PA00X+050249Y+049592                       
327m2244            R4478 -1          A01X+049847Y+049198X0198Y0197R180 S1      
327m2244            R882  -2   M      A01X+049847Y+049598X0198Y0197     S1      
327m2245            PEX1  -AK38       A01X+074055Y+114626X0180Y         S1      
317m2245            VIA   -    MD0080PA00X+073868Y+114439X0160Y         S0      
317m2245            VIA   -    M      A01X+059756Y+096583X0200Y         S2      
017m2245            VIA   -    M      A18X+059756Y+096583X0260Y         S2      
017m2245                  -    MD0100PA00X+059756Y+096583                       
317m2245            VIA   -    MD0100PA00X+058116Y+082347X0200Y    R270 S0      
327m2245            R981  -2          A18X+057750Y+081962X0198Y0197R270 S2      
327m2245            R972  -1   M      A18X+057750Y+082347X0198Y0197R270 S2      
327m2246            U114  -B8         A01X+052548Y+070827X0090Y         S1      
327m2246            VIA   -    M      A18X+052865Y+070895X0260Y         S2      
327m2246            R1121 -1          A18X+053702Y+071517X0198Y0197R270 S2      
327m2246            R1123 -2   M      A18X+053302Y+071517X0198Y0197R090 S2      
317m2246            VIA   -    MD0100PA00X+052393Y+070639X0193Y         S0      
327m2247            R1184 -2          A01X+133761Y+036504X0198Y0197R270 S1      
327m2247            U116  -39         A01X+133660Y+035321X0070Y0340R180 S1      
327m2248            R1219 -1          A18X+044533Y+130154X0198Y0197R180 S2      
327m2248            U118  -4          A18X+042791Y+130630X0100Y0220R090 S2      
317PEX2_DBG_MODE1   VIA   -    MD0080PA00X+110600Y+121545X0160Y    R180 S0      
317PEX2_DBG_MODE1   VIA   -    M      A01X+104993Y+122141X0200Y         S2      
017PEX2_DBG_MODE1   VIA   -    M      A18X+104993Y+122141X0260Y         S2      
017PEX2_DBG_MODE1         -    MD0100PA00X+104993Y+122141                       
327PEX2_DBG_MODE1   R1352 -2          A01X+104857Y+121141X0198Y0197R045 S1      
327PEX2_DBG_MODE1   R1332 -1   M      A01X+104574Y+121424X0198Y0197R225 S1      
327PEX2_DBG_MODE1   PEX2  -L13        A01X+110413Y+121732X0180Y         S1      
317m2249            VIA   -    M      A01X+139190Y+036553X0200Y         S2      
017m2249            VIA   -    M      A18X+139190Y+036553X0260Y         S2      
017m2249                  -    MD0100PA00X+139190Y+036553                       
327m2249            R1597 -2          A01X+138103Y+036137X0198Y0197     S1      
327m2249            U125  -1          A01X+140436Y+035459X0120Y0630R270 S1      
327m2249            R1607 -1   M      A01X+139103Y+036137X0198Y0197R180 S1      
317m2250            VIA   -    M      A01X+101766Y+006051X0200Y         S2      
017m2250            VIA   -    M      A18X+101766Y+006051X0260Y         S2      
017m2250                  -    MD0100PA00X+101766Y+006051                       
327m2250            U134  -2   M      A01X+101766Y+006472X0170Y0460R180 S1      
327m2250            R1693 -2   M      A01X+100893Y+007259X0198Y0197     S1      
327m2250            R1688 -2          A01X+100573Y+006858X0198Y0197R180 S1      
317m2250            VIA   -    MD0100PA00X+101834Y+009435X0200Y         S0      
327m2250            R1699 -2          A01X+101834Y+009195X0198Y0197R090 S1      
327m2251            J32   -A7         A01X+024671Y+008815X0150Y0500R090 S1      
317m2251            VIA   -    M      A01X+025627Y+009062X0200Y         S2      
017m2251            VIA   -    M      A18X+025627Y+009062X0260Y         S2      
017m2251                  -    MD0100PA00X+025627Y+009062                       
327m2251            R1651 -1          A01X+029633Y+007259X0198Y0197     S1      
317m2251            VIA   -    MD0100PA00X+029393Y+007262X0200Y         S0      
327m2252            R1175 -2          A01X+133761Y+031893X0198Y0197R090 S1      
327m2252            U116  -22         A01X+133660Y+032998X0070Y0340     S1      
327m2253            VIA   -    M      A01X+098804Y+035581X0300Y    R090 S1      
327m2253            U113  -A1         A01X+100709Y+034471X0070Y0220R090 S1      
327m2253            R1070 -2   M      A01X+098804Y+036101X0198Y0197R270 S1      
327m2253            R1058 -1          A01X+098004Y+036101X0198Y0197R090 S1      
327m2253            C2652 -1   M      A01X+098404Y+036101X0198Y0197R090 S1      
317PEX2_MODE_SEL2   VIA   -    MD0100PA00X+161187Y+079513X0200Y         S0      
327PEX2_MODE_SEL2   R6441 -2          A01X+160838Y+079513X0198Y0197R270 S1      
317PEX2_MODE_SEL2   VIA   -    MD0100PA00X+150494Y+085971X0200Y         S0      
317PEX2_MODE_SEL2   VIA   -    MD0100PA00X+102192Y+098046X0200Y         S0      
317PEX2_MODE_SEL2   VIA   -    M      A01X+101801Y+098881X0200Y         S2      
017PEX2_MODE_SEL2   VIA   -    M      A18X+101801Y+098881X0260Y         S2      
017PEX2_MODE_SEL2         -    MD0100PA00X+101801Y+098881                       
327PEX2_MODE_SEL2   R1358 -2          A01X+101801Y+099196X0198Y0197R270 S1      
327PEX2_MODE_SEL2   R1338 -1          A01X+101801Y+098611X0198Y0197R270 S1      
327PEX2_MODE_SEL2   PEX2  -AV25       A01X+114902Y+111634X0180Y         S1      
317PEX2_MODE_SEL2   VIA   -    MD0080PA00X+115088Y+111821X0160Y         S0      
317m2254            VIA   -    MD0080PA00X+074242Y+117805X0160Y         S0      
327m2254            VIA   -           A18X+075354Y+117847X0260Y         S2      
327m2254            R1312 -1   M      A18X+074853Y+117962X0198Y0197R090 S2      
327m2254            PEX1  -AA39       A01X+074429Y+117992X0180Y         S1      
317m2255            VIA   -    MD0100PA00X+102052Y+006044X0200Y         S0      
327m2255            U134  -3   M      A01X+102022Y+006472X0170Y0460R180 S1      
327m2255            R1689 -2          A01X+100573Y+008058X0198Y0197R180 S1      
327m2255            R1695 -2   M      A01X+100893Y+007659X0198Y0197     S1      
317m2255            VIA   -    M      A01X+102229Y+009428X0200Y         S2      
017m2255            VIA   -    M      A18X+102229Y+009428X0260Y         S2      
017m2255                  -    MD0100PA00X+102229Y+009428                       
327m2255            R1697 -2          A01X+102229Y+009188X0198Y0197R090 S1      
327m2256            J37   -A8         A01X+080616Y+009051X0150Y0500R090 S1      
317m2256            VIA   -    M      A01X+081041Y+009065X0200Y         S2      
017m2256            VIA   -    M      A18X+081041Y+009065X0260Y         S2      
017m2256                  -    MD0100PA00X+081041Y+009065                       
317m2256            VIA   -    MD0100PA00X+085338Y+007659X0200Y         S0      
327m2256            R1682 -1          A01X+085578Y+007659X0198Y0197     S1      
327m2257            VIA   -    M      A18X+058850Y+081105X0260Y    R270 S2      
327m2257            U104  -6          A18X+058606Y+080498X0140Y0440     S2      
327m2257            R980  -1          A18X+058800Y+081647X0198Y0197R270 S2      
327m2258            U63   -2          A01X+117128Y+080834X0140Y0630R180 S1      
317m2258            VIA   -    M      A01X+116473Y+080227X0200Y         S2      
017m2258            VIA   -    M      A18X+116473Y+080227X0260Y         S2      
017m2258                  -    MD0100PA00X+116473Y+080227                       
327m2258            R1042 -2          A18X+116020Y+079748X0198Y0197R270 S2      
327m2258            R1038 -1   M      A18X+116420Y+079748X0198Y0197R090 S2      
327m2259            R1182 -2          A01X+135517Y+035140X0198Y0197R180 S1      
327m2259            U116  -35         A01X+134270Y+034868X0070Y0340R090 S1      
327m2260            R1072 -2          A01X+105565Y+032816X0198Y0197R180 S1      
327m2260            U113  -A33        A01X+103761Y+032699X0070Y0220R270 S1      
327m2261            VIA   -    M      A01X+099483Y+032679X0300Y    R090 S1      
327m2261            R1051 -1          A01X+098270Y+033897X0198Y0197R180 S1      
327m2261            R1061 -2   M      A01X+098270Y+033547X0198Y0197     S1      
327m2261            U113  -B9         A01X+101005Y+032601X0110Y0180R090 S1      
327m2262            R1218 -1          A18X+044533Y+130554X0198Y0197R180 S2      
327m2262            U118  -3          A18X+042791Y+130827X0100Y0220R090 S2      
317PEX2_DBG_SEL1    VIA   -    MD0080PA00X+112470Y+121545X0160Y         S0      
317PEX2_DBG_SEL1    VIA   -    M      A01X+104061Y+123041X0200Y         S2      
017PEX2_DBG_SEL1    VIA   -    M      A18X+104061Y+123041X0260Y         S2      
017PEX2_DBG_SEL1          -    MD0100PA00X+104061Y+123041                       
327PEX2_DBG_SEL1    PEX2  -M19        A01X+112657Y+121358X0180Y         S1      
327PEX2_DBG_SEL1    R1330 -1          A01X+102377Y+122660X0198Y0197R270 S1      
327PEX2_DBG_SEL1    R1350 -2   M      A01X+103160Y+122838X0198Y0197R045 S1      
317m2263            VIA   -    MD0080PA00X+074616Y+118179X0160Y         S0      
327m2263            VIA   -           A18X+075310Y+118551X0260Y         S2      
327m2263            R1311 -1   M      A18X+074853Y+118396X0198Y0197R270 S2      
327m2263            PEX1  -Y39        A01X+074429Y+118366X0180Y         S1      
317m2264            VIA   -    MD0100PA00X+040469Y+004545X0200Y    R270 S0      
327m2264            R1654 -1          A01X+040469Y+004305X0198Y0197R270 S1      
327m2264            J33   -A8         A01X+034907Y+009051X0150Y0500R090 S1      
317m2264            VIA   -    M      A01X+035332Y+009065X0200Y         S2      
017m2264            VIA   -    M      A18X+035332Y+009065X0260Y         S2      
017m2264                  -    MD0100PA00X+035332Y+009065                       
317m2265            VIA   -    M      A01X+058274Y+081983X0200Y    R270 S2      
017m2265            VIA   -    M      A18X+058274Y+081983X0260Y    R270 S2      
017m2265                  -    MD0100PA00X+058274Y+081983                       
327m2265            R980  -2          A18X+058800Y+081962X0198Y0197R270 S2      
327m2265            R971  -1   M      A18X+058800Y+082347X0198Y0197R270 S2      
317m2265            VIA   -    MD0100PA00X+057390Y+096532X0200Y         S0      
317m2265            VIA   -    MD0100PA00X+037879Y+100108X0200Y         S0      
327m2265            PEX0  -AK38       A01X+028346Y+114626X0180Y         S1      
317m2265            VIA   -    MD0080PA00X+028159Y+114439X0160Y         S0      
327m2266            R923  -1          A18X+049107Y+079102X0198Y0197     S2      
327m2266            R924  -1   M      A18X+049703Y+079028X0198Y0197R180 S2      
327m2266            VIA   -    M      A18X+049554Y+079500X0260Y         S2      
327m2266            U99   -3          A18X+049005Y+080824X0240Y0440R270 S2      
317m2267            VIA   -    M      A01X+117312Y+080276X0200Y         S2      
017m2267            VIA   -    M      A18X+117312Y+080276X0260Y         S2      
017m2267                  -    MD0100PA00X+117312Y+080276                       
327m2267            U63   -1          A01X+117384Y+080834X0140Y0630R180 S1      
327m2267            R1037 -1          A18X+116970Y+079748X0198Y0197R090 S2      
327m2267            R1041 -2   M      A18X+117370Y+079748X0198Y0197R270 S2      
327m2268            R1180 -2          A01X+135517Y+034352X0198Y0197R180 S1      
327m2268            U116  -32         A01X+134270Y+034395X0070Y0340R090 S1      
327PEX2_MODE_SEL7   PEX2  -AV26       A01X+115276Y+111634X0180Y         S1      
317PEX2_MODE_SEL7   VIA   -    MD0080PA00X+115462Y+111821X0160Y         S0      
327PEX2_MODE_SEL7   VIA   -    M      A18X+113917Y+106285X0260Y         S2      
327PEX2_MODE_SEL7   R1363 -2          A01X+101401Y+099196X0198Y0197R270 S1      
327PEX2_MODE_SEL7   R1343 -1          A01X+101401Y+098611X0198Y0197R270 S1      
317PEX2_MODE_SEL7   VIA   -    MD0100PA00X+101401Y+098881X0200Y         S0      
327m2269            J33   -A7         A01X+034907Y+008815X0150Y0500R090 S1      
317m2269            VIA   -    M      A01X+035864Y+009062X0200Y         S2      
017m2269            VIA   -    M      A18X+035864Y+009062X0260Y         S2      
017m2269                  -    MD0100PA00X+035864Y+009062                       
317m2269            VIA   -    MD0100PA00X+040071Y+004545X0200Y    R270 S0      
327m2269            R1652 -1          A01X+040069Y+004305X0198Y0197R270 S1      
317FT4232_CLI_REF   VIA   -    M      A01X+054452Y+079388X0200Y         S2      
017FT4232_CLI_REF   VIA   -    M      A18X+054452Y+079388X0260Y         S2      
017FT4232_CLI_REF         -    MD0100PA00X+054452Y+079388                       
327FT4232_CLI_REF   U98   -6          A01X+054452Y+078933X0110Y0540     S1      
327FT4232_CLI_REF   R917  -1          A18X+054574Y+079857X0198Y0197R270 S2      
327m2270            U63   -7          A01X+115849Y+080834X0140Y0630R180 S1      
317m2270            VIA   -    M      A01X+115498Y+080290X0200Y         S2      
017m2270            VIA   -    M      A18X+115498Y+080290X0260Y         S2      
017m2270                  -    MD0100PA00X+115498Y+080290                       
327m2270            R1043 -2          A18X+114906Y+079714X0198Y0197R180 S2      
327m2270            R1039 -1   M      A18X+114906Y+080064X0198Y0197     S2      
327m2271            R1185 -2          A01X+133401Y+036504X0198Y0197R270 S1      
327m2271            U116  -40         A01X+133502Y+035321X0070Y0340R180 S1      
327m2272            R1071 -2          A01X+105565Y+033176X0198Y0197R180 S1      
327m2272            U113  -A34        A01X+103761Y+032896X0070Y0220R270 S1      
327m2273            VIA   -    M      A01X+098819Y+032756X0300Y    R090 S1      
327m2273            R1052 -1          A01X+098270Y+033197X0198Y0197R180 S1      
327m2273            U113  -A11        A01X+100709Y+032502X0070Y0220R090 S1      
327m2273            R1062 -2   M      A01X+098270Y+032847X0198Y0197     S1      
327m2274            J30   -A7         A01X+004199Y+008815X0150Y0500R090 S1      
317m2274            VIA   -    M      A01X+001029Y+009424X0200Y         S2      
017m2274            VIA   -    M      A18X+001029Y+009424X0260Y         S2      
017m2274                  -    MD0100PA00X+001029Y+009424                       
327m2274            R1637 -1          A01X+001029Y+009664X0198Y0197R090 S1      
317m2274            VIA   -    MD0100PA00X+005155Y+009062X0200Y         S0      
327P3V3_NIC3_SS     PU52  -7          A01X+083808Y+046761X0110Y0240R270 S1      
317P3V3_NIC3_SS     VIA   -    M      A01X+084252Y+046138X0200Y         S2      
017P3V3_NIC3_SS     VIA   -    M      A18X+084252Y+046138X0260Y         S2      
017P3V3_NIC3_SS           -    MD0100PA00X+084252Y+046138                       
327P3V3_NIC3_SS     PC494 -1          A01X+084518Y+046138X0198Y0197     S1      
327m2275            VIA   -    M      A01X+057944Y+078496X0300Y         S1      
327m2275            R6642 -2          A01X+057519Y+078070X0198Y0197     S1      
317m2275            VIA   -    MD0100PA00X+027840Y+089084X0200Y         S0      
327m2275            R6637 -1          A01X+028630Y+089084X0198Y0197R090 S1      
327m2275            R6630 -2          A01X+042040Y+079869X0198Y0197R090 S1      
317m2275            VIA   -    MD0100PA00X+042370Y+079550X0200Y         S0      
317m2275            VIA   -    MD0100PA00X+058210Y+078760X0200Y         S0      
327m2275            U104  -3          A18X+058094Y+079711X0140Y0440     S2      
327m2276            VIA   -    M      A18X+050724Y+080215X0260Y         S2      
327m2276            U99   -5          A18X+050107Y+080450X0240Y0440R270 S2      
327m2276            R921  -1          A18X+051236Y+079997X0198Y0197R180 S2      
327m2276            R919  -1   M      A18X+051236Y+080397X0198Y0197R180 S2      
327m2277            U63   -8          A01X+115593Y+080834X0140Y0630R180 S1      
317m2277            VIA   -    M      A01X+115348Y+081314X0200Y         S2      
017m2277            VIA   -    M      A18X+115348Y+081314X0260Y         S2      
017m2277                  -    MD0100PA00X+115348Y+081314                       
327m2277            R1040 -1          A18X+114906Y+080664X0198Y0197     S2      
327m2277            R1044 -2   M      A18X+114906Y+081014X0198Y0197R180 S2      
327m2278            VIA   -    M      A18X+043570Y+130238X0260Y         S2      
327m2278            R1224 -2          A18X+044533Y+129304X0198Y0197     S2      
327m2278            R1221 -1   M      A18X+044533Y+129704X0198Y0197R180 S2      
327m2278            U118  -5          A18X+042791Y+130433X0100Y0220R090 S2      
327m2279            J34   -A7         A01X+049908Y+008815X0150Y0500R090 S1      
317m2279            VIA   -    M      A01X+050864Y+009062X0200Y         S2      
017m2279            VIA   -    M      A18X+050864Y+009062X0260Y         S2      
017m2279                  -    MD0100PA00X+050864Y+009062                       
317m2279            VIA   -    MD0100PA00X+054629Y+007262X0200Y         S0      
327m2279            R1665 -1          A01X+054869Y+007259X0198Y0197     S1      
317m2280            VIA   -    MD0100PA00X+109277Y+093698X0200Y         S0      
327m2280            R1869 -2          A18X+118715Y+093361X0198Y0197R270 S2      
317m2280            VIA   -    MD0100PA00X+075504Y+144352X0200Y         S0      
317m2280            VIA   -    MD0100PA00X+041100Y+146350X0200Y         S0      
317m2280            VIA   -    M      A01X+025591Y+154204X0200Y         S2      
017m2280            VIA   -    M      A18X+025591Y+154204X0260Y         S2      
017m2280                  -    MD0100PA00X+025591Y+154204                       
317m2280            J3    -A1   D0122PA00X+010988Y+162240X0282Y0282R180 S3      
327m2281            PU49  -8          A01X+129516Y+047457X0110Y0240R270 S1      
317m2281            VIA   -    M      A01X+129981Y+047202X0200Y         S2      
017m2281            VIA   -    M      A18X+129981Y+047202X0260Y         S2      
017m2281                  -    MD0100PA00X+129981Y+047202                       
327m2281            R4477 -1          A01X+130227Y+047438X0198Y0197     S1      
327m2281            R881  -2   M      A01X+130227Y+047038X0198Y0197R180 S1      
327m2282            R6642 -1          A01X+057204Y+078070X0198Y0197     S1      
327m2282            U98   -26         A01X+057198Y+081482X0110Y0540R090 S1      
317m2282            VIA   -    M      A01X+057198Y+078451X0200Y         S2      
017m2282            VIA   -    M      A18X+057198Y+078451X0260Y         S2      
017m2282                  -    MD0100PA00X+057198Y+078451                       
327m2283            VIA   -    M      A18X+050774Y+080797X0260Y         S2      
327m2283            U99   -4          A18X+050107Y+080824X0240Y0440R270 S2      
327m2283            R920  -1          A18X+051236Y+081197X0198Y0197R180 S2      
327m2283            R922  -1   M      A18X+051236Y+080797X0198Y0197R180 S2      
317m2284            VIA   -    MD0100PA00X+130290Y+034040X0200Y         S0      
327m2284            U116  -5          A01X+131947Y+034395X0070Y0340R270 S1      
327m2284            R1076 -1          A01X+103379Y+030268X0198Y0197R090 S1      
317m2284            VIA   -    MD0100PA00X+103389Y+029629X0200Y         S0      
327m2285            J30   -A8         A01X+004199Y+009051X0150Y0500R090 S1      
317m2285            VIA   -    MD0100PA00X+001426Y+009424X0200Y         S0      
317m2285            VIA   -    M      A01X+004599Y+009051X0200Y         S2      
017m2285            VIA   -    M      A18X+004599Y+009051X0260Y         S2      
017m2285                  -    MD0100PA00X+004599Y+009051                       
327m2285            R1639 -1          A01X+001429Y+009664X0198Y0197R090 S1      
327P3V3_NIC5        PU49  -1          A01X+128335Y+048245X0110Y0240R270 S1      
327P3V3_NIC5        PU49  -2          A01X+128335Y+048048X0110Y0240R270 S1      
327P3V3_NIC5        PU49  -3          A01X+128335Y+047851X0110Y0240R270 S1      
327P3V3_NIC5        PU49  -4          A01X+128335Y+047654X0110Y0240R270 S1      
327P3V3_NIC5        PU49  -5          A01X+128335Y+047457X0110Y0240R270 S1      
327P3V3_NIC5        VIA   -           A18X+125233Y+045600X0260Y         S2      
327P3V3_NIC5        VIA   -           A18X+123277Y+045656X0260Y         S2      
327P3V3_NIC5        PC466 -1          A01X+127850Y+048188X0198Y0197R090 S1      
327P3V3_NIC5        PC903 -1          A01X+127285Y+046633X0400Y0500R180 S1      
327P3V3_NIC5        PU120 -6_7        A01X+127490Y+045752X0295Y0354     S1      
327P3V3_NIC5        C928  -1          A18X+121663Y+045178X0198Y0197R090 S2      
327P3V3_NIC5        C927  -1          A18X+121268Y+045178X0198Y0197R090 S2      
327P3V3_NIC5        C934  -1          A18X+120422Y+045515X0198Y0197     S2      
327P3V3_NIC5        C929  -1          A18X+120422Y+045115X0198Y0197     S2      
317P3V3_NIC5        VIA   -    MD0100PA00X+131149Y+047556X0200Y    R270 S0      
327P3V3_NIC5        R6039 -1          A01X+131390Y+047556X0198Y0197     S1      
317P3V3_NIC5        VIA   -    MD0100PA00X+127192Y+047705X0200Y         S0      
317P3V3_NIC5        VIA   -    MD0100PA00X+127442Y+047705X0200Y         S0      
317P3V3_NIC5        VIA   -    MD0100PA00X+127790Y+047638X0200Y    R090 S0      
317P3V3_NIC5        VIA   -    MD0100PA00X+127790Y+047888X0200Y    R090 S0      
317P3V3_NIC5        VIA   -    MD0100PA00X+128063Y+047769X0200Y    R090 S0      
317P3V3_NIC5        VIA   -    MD0100PA00X+128063Y+048019X0200Y    R090 S0      
317P3V3_NIC5        VIA   -    MD0100PA00X+126784Y+047357X0200Y    R090 S0      
317P3V3_NIC5        VIA   -    MD0100PA00X+126784Y+047607X0200Y    R090 S0      
317P3V3_NIC5        VIA   -    MD0100PA00X+126784Y+047857X0200Y    R090 S0      
317P3V3_NIC5        VIA   -    MD0100PA00X+126784Y+048107X0200Y    R090 S0      
317P3V3_NIC5        VIA   -    MD0100PA00X+120748Y+045168X0200Y         S0      
317P3V3_NIC5        VIA   -    MD0100PA00X+120998Y+045418X0200Y         S0      
317P3V3_NIC5        VIA   -    MD0100PA00X+120748Y+045418X0200Y         S0      
317P3V3_NIC5        VIA   -    MD0100PA00X+120998Y+045168X0200Y         S0      
317P3V3_NIC5        VIA   -    MD0100PA00X+127593Y+046206X0200Y    R090 S0      
317P3V3_NIC5        VIA   -    MD0100PA00X+127293Y+046206X0200Y    R090 S0      
317P3V3_NIC5        VIA   -    MD0100PA00X+130784Y+047038X0200Y    R090 S0      
327P3V3_NIC5        R881  -1          A01X+130542Y+047038X0198Y0197R180 S1      
327P3V3_NIC5        PC467 -1          A01X+127311Y+048102X0400Y0500R270 S1      
327P3V3_NIC5        PD55  -C          A01X+126250Y+047611X0670Y0990     S1      
327P3V3_NIC5        J25   -B11        A01X+120259Y+045368X0140Y0480R090 S1      
317P3V3_NIC5        VIA   -    MD0100PA00X+118874Y+044661X0200Y         S0      
327P3V3_NIC5        R265  -2          A18X+118611Y+044661X0198Y0197R180 S2      
327P3V3_NIC5        R1517 -2   M      A01X+086458Y+079200X0198Y0197     S1      
317P3V3_NIC5        VIA   -    MD0100PA00X+086700Y+079200X0200Y         S0      
327P3V3_NIC5        R1516 -2   M      A01X+086458Y+079600X0198Y0197     S1      
327P3V3_NIC5        R1515 -2          A01X+086458Y+080000X0198Y0197     S1      
327P3V3_NIC5        U120  -8          A01X+085430Y+080184X0140Y0590R270 S1      
327P3V3_NIC5        C2625 -2   M      A01X+086142Y+080400X0198Y0197R180 S1      
317P3V3_NIC5        VIA   -    MD0100PA00X+086142Y+080650X0200Y         S0      
317P3V3_NIC5        VIA   -    MD0100PA00X+116885Y+044587X0200Y         S0      
317P3V3_NIC5        VIA   -    MD0100PA00X+089246Y+066667X0200Y         S0      
317P3V3_NIC5        VIA   -    MD0100PA00X+116145Y+061829X0200Y    R180 S0      
317P3V3_NIC5        VIA   -    MD0100PA00X+117046Y+067784X0200Y         S0      
327P3V3_NIC5        R2475 -1          A01X+116145Y+062079X0198Y0197R090 S1      
327P3V3_NIC5        R290  -2          A01X+116645Y+044587X0198Y0197     S1      
317P3V3_NIC5        VIA   -    MD0100PA00X+118912Y+044261X0200Y         S0      
327P3V3_NIC5        R264  -2          A18X+118611Y+044261X0198Y0197R180 S2      
317P3V3_NIC5        VIA   -    MD0100PA00X+122343Y+039791X0200Y         S0      
327P3V3_NIC5        R280  -2          A18X+122103Y+039791X0198Y0197R180 S2      
317P3V3_NIC5        VIA   -    MD0100PA00X+114244Y+039672X0200Y    R180 S0      
327P3V3_NIC5        R282  -2          A01X+114486Y+039672X0198Y0197R180 S1      
317P3V3_NIC5        VIA   -    MD0100PA00X+122343Y+037791X0200Y         S0      
317P3V3_NIC5        VIA   -    MD0100PA00X+122903Y+031174X0200Y         S0      
327P3V3_NIC5        U37   -2          A01X+124160Y+031285X0400Y0500     S1      
327P3V3_NIC5        C930  -1   M      A01X+124120Y+030665X0198Y0197R180 S1      
317P3V3_NIC5        VIA   -    M      A01X+124120Y+030396X0200Y         S2      
017P3V3_NIC5        VIA   -    M      A18X+124120Y+030396X0260Y         S2      
017P3V3_NIC5              -    MD0100PA00X+124120Y+030396                       
327P3V3_NIC5        R304  -1          A01X+122644Y+031174X0198Y0197R090 S1      
327P3V3_NIC5        R266  -2          A18X+122103Y+037791X0198Y0197R180 S2      
317P3V3_NIC5        VIA   -    MD0100PA00X+122343Y+038191X0200Y         S0      
327P3V3_NIC5        R267  -2          A18X+122103Y+038191X0198Y0197R180 S2      
317m2286            VIA   -    MD0100PA00X+090870Y+070939X0200Y         S0      
317m2286            VIA   -    MD0100PA00X+117303Y+076506X0200Y         S0      
327m2286            Q124  -D          A18X+126975Y+093770X0240Y0320R090 S2      
327m2286            R1004 -2          A01X+092758Y+030526X0198Y0197R180 S1      
317m2286            VIA   -    M      A01X+092373Y+030458X0200Y         S2      
017m2286            VIA   -    M      A18X+092373Y+030458X0260Y         S2      
017m2286                  -    MD0100PA00X+092373Y+030458                       
327m2286            R1005 -1          A01X+091992Y+030458X0198Y0197R180 S1      
327m2287            R923  -2          A18X+048792Y+079102X0198Y0197     S2      
327m2287            R918  -1   M      A18X+048792Y+079502X0198Y0197R180 S2      
327m2287            VIA   -    M      A18X+048248Y+079816X0260Y         S2      
327m2287            U99   -1          A18X+049005Y+080076X0240Y0440R270 S2      
327m2288            J32   -A8         A01X+024671Y+009051X0150Y0500R090 S1      
317m2288            VIA   -    M      A01X+025096Y+009065X0200Y         S2      
017m2288            VIA   -    M      A18X+025096Y+009065X0260Y         S2      
017m2288                  -    MD0100PA00X+025096Y+009065                       
327m2288            R1653 -1          A01X+029633Y+007659X0198Y0197     S1      
317m2288            VIA   -    MD0100PA00X+029393Y+007659X0200Y         S0      
327P3V3_NIC4_OCP    PR242 -1          A01X+095555Y+048798X0198Y0197R180 S1      
327P3V3_NIC4_OCP    PU47  -9          A01X+096233Y+049368X0110Y0240R090 S1      
317P3V3_NIC4_OCP    VIA   -    M      A01X+095812Y+049235X0200Y    R180 S2      
017P3V3_NIC4_OCP    VIA   -    M      A18X+095812Y+049235X0260Y    R180 S2      
017P3V3_NIC4_OCP          -    MD0100PA00X+095812Y+049235                       
327m2289            R6641 -1          A01X+057204Y+077670X0198Y0197     S1      
317m2289            VIA   -    M      A01X+056713Y+077907X0200Y         S2      
017m2289            VIA   -    M      A18X+056713Y+077907X0260Y         S2      
017m2289                  -    MD0100PA00X+056713Y+077907                       
327m2289            U98   -16         A01X+056420Y+078933X0110Y0540     S1      
317m2290            VIA   -    M      A01X+056026Y+078221X0200Y         S2      
017m2290            VIA   -    M      A18X+056026Y+078221X0260Y         S2      
017m2290                  -    MD0100PA00X+056026Y+078221                       
327m2290            U98   -14         A01X+056026Y+078933X0110Y0540     S1      
327m2290            R5775 -1          A01X+056026Y+077925X0198Y0197R270 S1      
317m2291            VIA   -    MD0100PA00X+051453Y+071640X0200Y         S0      
317m2291            VIA   -    MD0100PA00X+051253Y+071830X0200Y         S0      
327m2291            R1082 -2          A18X+051438Y+072358X0280Y0320R090 S2      
327m2291            R1083 -2          A18X+050141Y+068798X0280Y0320R090 S2      
327m2291            L11   -2          A18X+050141Y+068148X0280Y0320R090 S2      
317m2291            VIA   -    MD0100PA00X+049828Y+067895X0200Y         S0      
327m2291            VIA   -           A18X+049618Y+068497X0260Y         S2      
317m2291            VIA   -    MD0100PA00X+049828Y+068145X0200Y         S0      
317m2292            VIA   -    MD0100PA00X+130290Y+034380X0200Y         S0      
327m2292            U116  -4          A01X+131947Y+034553X0070Y0340R270 S1      
327m2292            R1075 -1          A01X+103739Y+030268X0198Y0197R090 S1      
317m2292            VIA   -    MD0100PA00X+103729Y+029629X0200Y         S0      
327m2293            VIA   -    M      A01X+104706Y+036118X0300Y         S1      
327m2293            U113  -B42        A01X+101644Y+034422X0110Y0180     S1      
327m2293            R1054 -1          A01X+105513Y+036828X0198Y0197     S1      
327m2293            R1064 -2   M      A01X+105513Y+036428X0198Y0197R180 S1      
317m2294            VIA   -    M      A01X+100258Y+030962X0200Y         S2      
017m2294            VIA   -    M      A18X+100258Y+030962X0260Y         S2      
017m2294                  -    MD0100PA00X+100258Y+030962                       
327m2294            U113  -A16        A01X+101152Y+031666X0070Y0220     S1      
327m2294            R1056 -1          A01X+100070Y+030583X0198Y0197R270 S1      
327m2294            R1068 -2   M      A01X+100464Y+030583X0198Y0197R090 S1      
327m2295            J35   -A7         A01X+060144Y+008815X0150Y0500R090 S1      
317m2295            VIA   -    M      A01X+061100Y+009062X0200Y         S2      
017m2295            VIA   -    M      A18X+061100Y+009062X0260Y         S2      
017m2295                  -    MD0100PA00X+061100Y+009062                       
317m2295            VIA   -    MD0100PA00X+064866Y+007262X0200Y         S0      
327m2295            R1666 -1          A01X+065106Y+007259X0198Y0197     S1      
327P3V3_NIC1_OCP    PR245 -1          A01X+038809Y+047838X0198Y0197     S1      
327P3V3_NIC1_OCP    PU48  -9          A01X+038099Y+047654X0110Y0240R270 S1      
317P3V3_NIC1_OCP    VIA   -    M      A01X+038569Y+047732X0200Y    R090 S2      
017P3V3_NIC1_OCP    VIA   -    M      A18X+038569Y+047732X0260Y    R090 S2      
017P3V3_NIC1_OCP          -    MD0100PA00X+038569Y+047732                       
317OSC_CLI_IN       VIA   -    M      A01X+053758Y+077243X0200Y    R270 S2      
017OSC_CLI_IN       VIA   -    M      A18X+053758Y+077243X0260Y    R270 S2      
017OSC_CLI_IN             -    MD0100PA00X+053758Y+077243                       
327OSC_CLI_IN       U98   -2          A01X+053664Y+078933X0110Y0540     S1      
327OSC_CLI_IN       Y4    -1          A01X+053794Y+076078X0480Y0560R090 S1      
327OSC_CLI_IN       R916  -2   M      A01X+053462Y+077489X0280Y0320R090 S1      
327OSC_CLI_IN       C2597 -1   M      A01X+053560Y+077989X0198Y0197R180 S1      
327m2296            VIA   -           A18X+051136Y+069849X0200Y         S2      
327m2296            VIA   -           A18X+051536Y+069825X0200Y         S2      
327m2296            VIA   -           A18X+051332Y+069389X0200Y         S2      
327m2296            C2655 -1          A18X+050846Y+069324X0280Y0320R090 S2      
317m2296            VIA   -    MD0100PA00X+051548Y+069576X0193Y         S0      
327m2296            U114  -H2         A01X+051367Y+069646X0090Y         S1      
327m2296            R1083 -1          A18X+050721Y+068798X0280Y0320R090 S2      
327m2296            C2656 -1          A18X+050722Y+069740X0198Y0197     S2      
327I3C_MB_SDA       VIA   -    M      A01X+086373Y+087272X0300Y         S1      
327I3C_MB_SDA       R1485 -1          A01X+085683Y+087946X0198Y0197R180 S1      
327I3C_MB_SDA       U5    -M16        A01X+087979Y+087206X0160Y    R180 S1      
327m2297            J34   -A8         A01X+049908Y+009051X0150Y0500R090 S1      
317m2297            VIA   -    M      A01X+050332Y+009065X0200Y         S2      
017m2297            VIA   -    M      A18X+050332Y+009065X0260Y         S2      
017m2297                  -    MD0100PA00X+050332Y+009065                       
317m2297            VIA   -    MD0100PA00X+054629Y+007659X0200Y         S0      
327m2297            R1667 -1          A01X+054869Y+007659X0198Y0197     S1      
327GPU_PEX_STRAP0   C4040 -2          A01X+022194Y+153431X0198Y0197R270 S1      
317GPU_PEX_STRAP0   J11   -D9   D0122PA00X+035240Y+160705X0282Y    R180 S3      
317GPU_PEX_STRAP0   VIA   -    M      A01X+023758Y+152860X0200Y         S2      
017GPU_PEX_STRAP0   VIA   -    M      A18X+023758Y+152860X0260Y         S2      
017GPU_PEX_STRAP0         -    MD0100PA00X+023758Y+152860                       
327GPU_PEX_STRAP0   R1828 -2   M      A01X+022575Y+153414X0198Y0197R270 S1      
327P3V3_NIC5_SS     PU49  -7          A01X+129516Y+047261X0110Y0240R270 S1      
317P3V3_NIC5_SS     VIA   -    M      A01X+129947Y+046641X0200Y         S2      
017P3V3_NIC5_SS     VIA   -    M      A18X+129947Y+046641X0260Y         S2      
017P3V3_NIC5_SS           -    MD0100PA00X+129947Y+046641                       
327P3V3_NIC5_SS     PC471 -1          A01X+130227Y+046641X0198Y0197     S1      
327m2298            R1000 -2          A01X+176408Y+082088X0198Y0197     S1      
327m2298            J54   -2          A01X+179644Y+082134X0170Y0590R090 S1      
327m2298            U108  -2   M      A01X+178347Y+081870X0240Y0280     S1      
327m2299            R924  -2          A18X+050018Y+079028X0198Y0197R180 S2      
317m2299            VIA   -    M      A01X+050710Y+081478X0200Y         S2      
017m2299            VIA   -    M      A18X+050710Y+081478X0260Y         S2      
017m2299                  -    MD0100PA00X+050710Y+081478                       
327m2299            U98   -61         A01X+052690Y+080301X0110Y0540R090 S1      
327m2300            VIA   -           A18X+054786Y+069258X0260Y         S2      
327m2300            VIA   -           A18X+053681Y+069120X0260Y         S2      
327m2300            U114  -B11        A01X+053138Y+070827X0090Y         S1      
327m2300            C2659 -1          A18X+053320Y+070871X0198Y0197R180 S2      
317m2300            VIA   -    MD0100PA00X+052947Y+070623X0193Y         S0      
327m2300            VIA   -    M      A18X+051224Y+070843X0260Y         S2      
317m2300            VIA   -    MD0100PA00X+051565Y+070639X0193Y         S0      
327m2300            U114  -B2         A01X+051367Y+070827X0090Y         S1      
327m2300            C2660 -1          A18X+050646Y+071276X0198Y0197     S2      
327m2300            C2661 -1          A18X+051538Y+068896X0198Y0197R090 S2      
327m2300            U114  -L2         A01X+051367Y+069055X0090Y         S1      
317m2300            VIA   -    MD0100PA00X+051557Y+069252X0180Y         S0      
327m2300            L12   -2          A18X+054704Y+068734X0280Y0320     S2      
327m2300            C2657 -1          A18X+054208Y+068726X0280Y0320R180 S2      
327m2300            C2658 -1          A18X+053225Y+068737X0198Y0197R090 S2      
317m2300            VIA   -    MD0100PA00X+052949Y+069244X0180Y         S0      
327m2300            U114  -L11        A01X+053138Y+069055X0090Y         S1      
317m2300            VIA   -    MD0100PA00X+053574Y+068749X0200Y         S0      
317m2300            VIA   -    MD0100PA00X+053832Y+068736X0200Y         S0      
317m2301            VIA   -           A01X+098637Y+037047X0200Y         S2      
017m2301            VIA   -           A18X+098637Y+037047X0260Y         S2      
017m2301                  -     D0100PA00X+098637Y+037047                       
327m2301            U113  -A53        A01X+101546Y+034717X0070Y0220     S1      
317SMB_MB_R_SCL     VIA   -    MD0100PA00X+119717Y+094064X0200Y    R270 S0      
317SMB_MB_R_SCL     VIA   -    M      A01X+095857Y+092765X0200Y    R270 S2      
017SMB_MB_R_SCL     VIA   -    M      A18X+095857Y+092765X0260Y    R270 S2      
017SMB_MB_R_SCL           -    MD0100PA00X+095857Y+092765                       
327SMB_MB_R_SCL     R6241 -2          A01X+095857Y+093024X0198Y0197R270 S1      
327SMB_MB_R_SCL     R4107 -2          A18X+120122Y+094321X0198Y0197R090 S2      
327SMB_MB_R_SCL     R5646 -1          A01X+126872Y+091896X0198Y0197     S1      
327m2302            J36   -A8         A01X+070380Y+009051X0150Y0500R090 S1      
317m2302            VIA   -    M      A01X+070805Y+009065X0200Y         S2      
017m2302            VIA   -    M      A18X+070805Y+009065X0260Y         S2      
017m2302                  -    MD0100PA00X+070805Y+009065                       
327m2302            R1681 -1          A01X+075342Y+007659X0198Y0197     S1      
317m2302            VIA   -    MD0100PA00X+075102Y+007659X0200Y         S0      
327P3V3_NIC6_OCP    PR250 -1          A01X+141264Y+048798X0198Y0197R180 S1      
327P3V3_NIC6_OCP    PU51  -9          A01X+141941Y+049368X0110Y0240R090 S1      
317P3V3_NIC6_OCP    VIA   -    M      A01X+141562Y+049227X0200Y    R180 S2      
017P3V3_NIC6_OCP    VIA   -    M      A18X+141562Y+049227X0260Y    R180 S2      
017P3V3_NIC6_OCP          -    MD0100PA00X+141562Y+049227                       
317USB_VBUS_CONN    VIA   -    MD0100PA00X+179104Y+081880X0200Y    R090 S0      
317USB_VBUS_CONN    VIA   -    M      A01X+177940Y+082657X0200Y    R090 S2      
017USB_VBUS_CONN    VIA   -    M      A18X+177940Y+082657X0260Y    R090 S2      
017USB_VBUS_CONN          -    MD0100PA00X+177940Y+082657                       
327USB_VBUS_CONN    C2613 -1          A01X+177607Y+083332X0198Y0197R090 S1      
327USB_VBUS_CONN    U108  -4   M      A01X+177599Y+082657X0240Y0280     S1      
327USB_VBUS_CONN    J54   -1          A01X+179644Y+081878X0170Y0590R090 S1      
327m2303            U98   -62         A01X+052690Y+080104X0110Y0540R090 S1      
317m2303            VIA   -    M      A01X+052074Y+080515X0200Y         S2      
017m2303            VIA   -    M      A18X+052074Y+080515X0260Y         S2      
017m2303                  -    MD0100PA00X+052074Y+080515                       
327m2303            R922  -2          A18X+051551Y+080797X0198Y0197R180 S2      
327m2304            VIA   -           A18X+051907Y+070918X0200Y         S2      
327m2304            VIA   -           A18X+052330Y+070931X0200Y         S2      
327m2304            VIA   -           A18X+051697Y+071309X0260Y         S2      
327m2304            U114  -B6         A01X+052154Y+070827X0090Y         S1      
317m2304            VIA   -    MD0100PA00X+052116Y+070639X0193Y         S0      
327m2304            R1082 -1          A18X+052018Y+072358X0280Y0320R090 S2      
327m2304            C2654 -1          A18X+052295Y+071358X0198Y0197R180 S2      
327m2304            C2653 -1          A18X+052141Y+071790X0280Y0320R270 S2      
327m2305            VIA   -    M      A01X+101186Y+035428X0300Y    R090 S1      
327m2305            R1067 -2          A01X+099604Y+036101X0198Y0197R270 S1      
327m2305            U113  -B43        A01X+101448Y+034422X0110Y0180     S1      
317m2306            VIA   -    MD0080PA00X+028907Y+118179X0160Y         S0      
327m2306            VIA   -           A18X+029601Y+118551X0260Y         S2      
327m2306            R1244 -1   M      A18X+029144Y+118396X0198Y0197R270 S2      
327m2306            PEX0  -Y39        A01X+028720Y+118366X0180Y         S1      
327m2307            J35   -A8         A01X+060144Y+009051X0150Y0500R090 S1      
317m2307            VIA   -    M      A01X+060569Y+009065X0200Y         S2      
017m2307            VIA   -    M      A18X+060569Y+009065X0260Y         S2      
017m2307                  -    MD0100PA00X+060569Y+009065                       
317m2307            VIA   -    MD0100PA00X+064866Y+007659X0200Y         S0      
327m2307            R1668 -1          A01X+065106Y+007659X0198Y0197     S1      
327SMB_GPU_1_SDA    R1836 -2          A18X+039511Y+149406X0198Y0197R270 S2      
327SMB_GPU_1_SDA    VIA   -    M      A18X+038290Y+149498X0260Y         S2      
317SMB_GPU_1_SDA    J11   -R10  D0122PA00X+036106Y+149366X0282Y    R180 S3      
327m2308            R1001 -2          A01X+176408Y+082438X0198Y0197     S1      
327m2308            J54   -3          A01X+179644Y+082390X0170Y0590R090 S1      
327m2308            U108  -3   M      A01X+178347Y+082657X0240Y0280     S1      
317m2309            VIA   -    M      A01X+051989Y+079585X0200Y         S2      
017m2309            VIA   -    M      A18X+051989Y+079585X0260Y         S2      
017m2309                  -    MD0100PA00X+051989Y+079585                       
327m2309            R921  -2          A18X+051551Y+079997X0198Y0197R180 S2      
327m2309            U98   -63         A01X+052690Y+079907X0110Y0540R090 S1      
317m2310            VIA   -    MD0100PA00X+052626Y+066406X0200Y         S0      
327m2310            R1094 -1          A01X+052596Y+067008X0198Y0197R090 S1      
317m2310            VIA   -    MD0100PA00X+017492Y+054186X0200Y         S0      
327m2310            J20   -B15        A01X+018127Y+054238X0140Y0480R270 S1      
317m2311            VIA   -    MD0080PA00X+028533Y+117805X0160Y         S0      
327m2311            VIA   -           A18X+029645Y+117847X0260Y         S2      
327m2311            R1245 -1   M      A18X+029144Y+117962X0198Y0197R090 S2      
327m2311            PEX0  -AA39       A01X+028720Y+117992X0180Y         S1      
327m2312            J31   -A8         A01X+014435Y+009051X0150Y0500R090 S1      
317m2312            VIA   -    M      A01X+014860Y+009065X0200Y         S2      
017m2312            VIA   -    M      A18X+014860Y+009065X0260Y         S2      
017m2312                  -    MD0100PA00X+014860Y+009065                       
327m2312            R1640 -1          A01X+019397Y+007659X0198Y0197     S1      
317m2312            VIA   -    MD0100PA00X+019157Y+007659X0200Y         S0      
327USB2_MB_BMC_DP   R6727 -1   M      A01X+040090Y+151656X0180Y0200R090 S1      
327USB2_MB_BMC_DP   R5444 -2   M      A01X+040090Y+151656X0180Y0200R090 S1      
327USB2_MB_BMC_DP   R6294 -1   M      A01X+040090Y+151656X0180Y0200R180 S1      
327USB2_MB_BMC_DP   VIA   -    M      A18X+039274Y+151576X0160Y0041     S2      
317USB2_MB_BMC_DP   VIA   -    MD0100PA00X+039727Y+151465X0200Y    R270 S0      
317USB2_MB_BMC_DP   J11   -M9   D0122PA00X+035240Y+156098X0282Y    R180 S3      
317OSC_CLI_OUT      VIA   -    M      A01X+053945Y+078239X0200Y    R270 S2      
017OSC_CLI_OUT      VIA   -    M      A18X+053945Y+078239X0260Y    R270 S2      
017OSC_CLI_OUT            -    MD0100PA00X+053945Y+078239                       
327OSC_CLI_OUT      U98   -3          A01X+053861Y+078933X0110Y0540     S1      
327OSC_CLI_OUT      Y4    -3          A01X+054661Y+076747X0480Y0560R090 S1      
327OSC_CLI_OUT      C2598 -1   M      A01X+053945Y+077989X0198Y0197     S1      
327OSC_CLI_OUT      R916  -1   M      A01X+054042Y+077489X0280Y0320R090 S1      
317m2313            VIA   -    MD0100PA00X+056157Y+069281X0200Y    R090 S0      
327m2313            R1100 -1          A01X+055305Y+069251X0198Y0197R180 S1      
327m2313            J23   -B15        A01X+074550Y+046313X0140Y0480R090 S1      
317m2313            VIA   -    MD0100PA00X+075210Y+046362X0200Y         S0      
327m2314            VIA   -    M      A01X+100144Y+035752X0300Y    R090 S1      
327m2314            R1066 -2          A01X+099204Y+036101X0198Y0197R270 S1      
327m2314            U113  -A54        A01X+101349Y+034717X0070Y0220     S1      
317GPU_BASE_ID0     J11   -G9   D0122PA00X+035240Y+159169X0282Y    R180 S3      
317GPU_BASE_ID0     VIA   -    M      A01X+023569Y+152258X0200Y         S2      
017GPU_BASE_ID0     VIA   -    M      A18X+023569Y+152258X0260Y         S2      
017GPU_BASE_ID0           -    MD0100PA00X+023569Y+152258                       
327GPU_BASE_ID0     R1830 -2   M      A01X+023262Y+152258X0198Y0197     S1      
327GPU_BASE_ID0     C4042 -2          A01X+022279Y+152254X0198Y0197     S1      
317m2315            VIA   -    MD0100PA00X+055907Y+070421X0200Y    R090 S0      
327m2315            R1103 -1          A01X+055305Y+070451X0198Y0197R180 S1      
317m2315            VIA   -    MD0100PA00X+108910Y+054526X0200Y         S0      
327m2315            J24   -B14        A01X+109544Y+054474X0140Y0480R270 S1      
327m2316            C4010 -2          A01X+023794Y+154631X0198Y0197R270 S1      
317m2316            J3    -A3   D0122PA00X+012720Y+162240X0282Y    R180 S3      
317m2316            VIA   -    M      A01X+023995Y+154133X0200Y         S2      
017m2316            VIA   -    M      A18X+023995Y+154133X0260Y         S2      
017m2316                  -    MD0100PA00X+023995Y+154133                       
327m2316            R6256 -2          A01X+023775Y+153729X0198Y0197R090 S1      
317P3V3_NIC1        VIA   -    MD0100PA00X+027487Y+044661X0200Y         S0      
327P3V3_NIC1        R61   -1          A18X+027194Y+044661X0198Y0197     S2      
317P3V3_NIC1        VIA   -    MD0100PA00X+027495Y+044261X0200Y         S0      
327P3V3_NIC1        R60   -1          A18X+027194Y+044261X0198Y0197     S2      
327P3V3_NIC1        PU48  -1          A01X+036918Y+048245X0110Y0240R270 S1      
327P3V3_NIC1        PU48  -2          A01X+036918Y+048048X0110Y0240R270 S1      
327P3V3_NIC1        PU48  -3          A01X+036918Y+047851X0110Y0240R270 S1      
327P3V3_NIC1        PU48  -4          A01X+036918Y+047654X0110Y0240R270 S1      
327P3V3_NIC1        PU48  -5          A01X+036918Y+047457X0110Y0240R270 S1      
327P3V3_NIC1        PU79  -6_7        A01X+036073Y+045752X0295Y0354     S1      
327P3V3_NIC1        PC464 -1          A01X+036433Y+048188X0198Y0197R090 S1      
327P3V3_NIC1        PC663 -1          A01X+035868Y+046633X0400Y0500R180 S1      
317P3V3_NIC1        VIA   -    MD0100PA00X+039732Y+047556X0200Y    R270 S0      
327P3V3_NIC1        R5863 -1          A01X+039973Y+047556X0198Y0197     S1      
317P3V3_NIC1        VIA   -    MD0100PA00X+036369Y+047617X0200Y    R090 S0      
317P3V3_NIC1        VIA   -    MD0100PA00X+036369Y+047867X0200Y    R090 S0      
317P3V3_NIC1        VIA   -    MD0100PA00X+036642Y+047749X0200Y    R090 S0      
317P3V3_NIC1        VIA   -    MD0100PA00X+036642Y+047999X0200Y    R090 S0      
317P3V3_NIC1        VIA   -    MD0100PA00X+035367Y+047357X0200Y    R090 S0      
317P3V3_NIC1        VIA   -    MD0100PA00X+035774Y+047705X0200Y         S0      
317P3V3_NIC1        VIA   -    MD0100PA00X+036024Y+047705X0200Y         S0      
317P3V3_NIC1        VIA   -    MD0100PA00X+035367Y+047607X0200Y    R090 S0      
317P3V3_NIC1        VIA   -    MD0100PA00X+035367Y+047857X0200Y    R090 S0      
317P3V3_NIC1        VIA   -    MD0100PA00X+035367Y+048107X0200Y    R090 S0      
317P3V3_NIC1        VIA   -    MD0100PA00X+022827Y+039672X0200Y    R180 S0      
327P3V3_NIC1        R78   -2          A01X+023069Y+039672X0198Y0197R180 S1      
317P3V3_NIC1        VIA   -    MD0100PA00X+025468Y+044587X0200Y         S0      
317P3V3_NIC1        VIA   -    MD0100PA00X+029581Y+045418X0200Y         S0      
317P3V3_NIC1        VIA   -    MD0100PA00X+029331Y+045418X0200Y         S0      
317P3V3_NIC1        VIA   -    MD0100PA00X+029581Y+045168X0200Y         S0      
317P3V3_NIC1        VIA   -    MD0100PA00X+029331Y+045168X0200Y         S0      
317P3V3_NIC1        VIA   -    MD0100PA00X+031486Y+031174X0200Y         S0      
327P3V3_NIC1        R100  -1          A01X+031226Y+031174X0198Y0197R090 S1      
317P3V3_NIC1        VIA   -    MD0100PA00X+032703Y+030396X0200Y         S0      
327P3V3_NIC1        C868  -1   M      A01X+032703Y+030665X0198Y0197R180 S1      
327P3V3_NIC1        U17   -2          A01X+032743Y+031285X0400Y0500     S1      
317P3V3_NIC1        VIA   -    M      A01X+035875Y+046206X0200Y    R090 S2      
017P3V3_NIC1        VIA   -    M      A18X+035875Y+046206X0260Y    R090 S2      
017P3V3_NIC1              -    MD0100PA00X+035875Y+046206                       
317P3V3_NIC1        VIA   -    MD0100PA00X+036175Y+046206X0200Y    R090 S0      
317P3V3_NIC1        VIA   -    MD0100PA00X+039366Y+047038X0200Y    R090 S0      
327P3V3_NIC1        R880  -1          A01X+039124Y+047038X0198Y0197R180 S1      
327P3V3_NIC1        C867  -1          A18X+029851Y+045178X0198Y0197R090 S2      
327P3V3_NIC1        C869  -1          A18X+030246Y+045178X0198Y0197R090 S2      
327P3V3_NIC1        R76   -2          A18X+030686Y+039791X0198Y0197R180 S2      
327P3V3_NIC1        R63   -2          A18X+030686Y+038191X0198Y0197R180 S2      
327P3V3_NIC1        R62   -2          A18X+030686Y+037791X0198Y0197R180 S2      
327P3V3_NIC1        C870  -1          A18X+029005Y+045115X0198Y0197     S2      
327P3V3_NIC1        C874  -1          A18X+029005Y+045515X0198Y0197     S2      
327P3V3_NIC1        PC465 -1          A01X+035893Y+048102X0400Y0500R270 S1      
327P3V3_NIC1        PD54  -C          A01X+034833Y+047611X0670Y0990     S1      
327P3V3_NIC1        J21   -B11        A01X+028842Y+045368X0140Y0480R090 S1      
327P3V3_NIC1        VIA   -           A18X+025254Y+050708X0260Y         S2      
327P3V3_NIC1        VIA   -           A18X+024240Y+049991X0260Y         S2      
317P3V3_NIC1        VIA   -    MD0100PA00X+024728Y+061829X0200Y    R180 S0      
327P3V3_NIC1        R2471 -1          A01X+024728Y+062079X0198Y0197R090 S1      
327P3V3_NIC1        R86   -2          A01X+025228Y+044587X0198Y0197     S1      
317m2317            VIA   -    MD0100PA00X+056157Y+069621X0200Y    R090 S0      
327m2317            R1101 -1          A01X+055305Y+069651X0198Y0197R180 S1      
327m2317            J23   -B14        A01X+074550Y+046077X0140Y0480R090 S1      
317m2317            VIA   -    MD0100PA00X+075210Y+046022X0200Y         S0      
327m2318            VIA   -    M      A01X+102588Y+035285X0300Y    R090 S1      
327m2318            U113  -B38        A01X+102432Y+034422X0110Y0180     S1      
327m2318            R1063 -2          A01X+105513Y+036015X0198Y0197R180 S1      
327m2318            R1053 -1   M      A01X+105513Y+035615X0198Y0197     S1      
327I3C_MB_SCL       VIA   -    M      A01X+086812Y+087530X0300Y         S1      
327I3C_MB_SCL       R1483 -1          A01X+085683Y+088346X0198Y0197R180 S1      
327I3C_MB_SCL       U5    -M15        A01X+088294Y+087206X0160Y    R180 S1      
317m2319            J3    -L10  D0122PA00X+018784Y+156532X0282Y    R180 S3      
317m2319            J11   -L10  D0122PA00X+036106Y+156532X0282Y    R180 S3      
327P3V3_NIC7_SS     PU53  -7          A01X+175225Y+047261X0110Y0240R270 S1      
317P3V3_NIC7_SS     VIA   -    M      A01X+175655Y+046641X0200Y         S2      
017P3V3_NIC7_SS     VIA   -    M      A18X+175655Y+046641X0260Y         S2      
017P3V3_NIC7_SS           -    MD0100PA00X+175655Y+046641                       
327P3V3_NIC7_SS     PC495 -1          A01X+175935Y+046641X0198Y0197     S1      
317m2320            VIA   -    MD0100PA00X+166627Y+046362X0200Y         S0      
317m2320            VIA   -    MD0100PA00X+053898Y+073659X0200Y    R180 S0      
327m2320            J27   -B15        A01X+165968Y+046313X0140Y0480R090 S1      
327m2320            R1109 -1          A01X+053928Y+072857X0198Y0197R270 S1      
327m2321            VIA   -           A18X+035929Y+163366X0260Y         S2      
317m2321            J11   -J9   D0122PA00X+035240Y+157634X0282Y    R180 S3      
317m2322            VIA   -    MD0100PA00X+052966Y+066406X0200Y         S0      
327m2322            R1095 -1          A01X+052996Y+067008X0198Y0197R090 S1      
317m2322            VIA   -    MD0100PA00X+017492Y+054526X0200Y         S0      
327m2322            J20   -B14        A01X+018127Y+054474X0140Y0480R270 S1      
327SMB_GPU_2_SDA    VIA   -    M      A18X+038326Y+148779X0260Y         S2      
327SMB_GPU_2_SDA    R1832 -2          A18X+038780Y+148224X0198Y0197     S2      
317SMB_GPU_2_SDA    J11   -S9   D0122PA00X+035240Y+148933X0282Y    R180 S3      
317P3V3_NIC7        VIA   -    MD0100PA00X+164583Y+044661X0200Y         S0      
327P3V3_NIC7        R367  -1          A18X+164320Y+044661X0198Y0197     S2      
317P3V3_NIC7        VIA   -    MD0100PA00X+164621Y+044261X0200Y         S0      
327P3V3_NIC7        R366  -1          A18X+164320Y+044261X0198Y0197     S2      
327P3V3_NIC7        U47   -2          A01X+169869Y+031285X0400Y0500     S1      
327P3V3_NIC7        C957  -1   M      A01X+169829Y+030665X0198Y0197R180 S1      
317P3V3_NIC7        VIA   -    MD0100PA00X+169829Y+030396X0200Y         S0      
327P3V3_NIC7        PU53  -1          A01X+174044Y+048245X0110Y0240R270 S1      
327P3V3_NIC7        PU53  -2          A01X+174044Y+048048X0110Y0240R270 S1      
327P3V3_NIC7        PU53  -3          A01X+174044Y+047851X0110Y0240R270 S1      
327P3V3_NIC7        PU53  -4          A01X+174044Y+047654X0110Y0240R270 S1      
327P3V3_NIC7        PU53  -5          A01X+174044Y+047457X0110Y0240R270 S1      
317P3V3_NIC7        VIA   -    MD0100PA00X+086344Y+075325X0200Y         S0      
327P3V3_NIC7        R1531 -2   M      A01X+086458Y+075600X0198Y0197     S1      
327P3V3_NIC7        R1530 -2   M      A01X+086458Y+076000X0198Y0197     S1      
327P3V3_NIC7        R1529 -2          A01X+086458Y+076400X0198Y0197     S1      
327P3V3_NIC7        U122  -8          A01X+085430Y+076584X0140Y0590R270 S1      
327P3V3_NIC7        C2705 -2   M      A01X+086142Y+076800X0198Y0197R180 S1      
317P3V3_NIC7        VIA   -    MD0100PA00X+086142Y+077050X0200Y         S0      
327P3V3_NIC7        VIA   -           A18X+160026Y+047958X0260Y         S2      
327P3V3_NIC7        VIA   -           A18X+169920Y+036885X0260Y         S2      
327P3V3_NIC7        VIA   -           A18X+164906Y+033655X0260Y         S2      
327P3V3_NIC7        VIA   -           A18X+161760Y+039965X0260Y         S2      
327P3V3_NIC7        PC490 -1          A01X+173559Y+048188X0198Y0197R090 S1      
327P3V3_NIC7        PC913 -1          A01X+172994Y+046633X0400Y0500R180 S1      
327P3V3_NIC7        PU122 -6_7        A01X+173199Y+045752X0295Y0354     S1      
317P3V3_NIC7        VIA   -    MD0100PA00X+173495Y+047672X0200Y    R090 S0      
317P3V3_NIC7        VIA   -    MD0100PA00X+172493Y+047357X0200Y    R090 S0      
317P3V3_NIC7        VIA   -    MD0100PA00X+172493Y+048107X0200Y    R090 S0      
317P3V3_NIC7        VIA   -    MD0100PA00X+172493Y+047857X0200Y    R090 S0      
317P3V3_NIC7        VIA   -    MD0100PA00X+172493Y+047607X0200Y    R090 S0      
317P3V3_NIC7        VIA   -    MD0100PA00X+176858Y+047556X0200Y    R270 S0      
327P3V3_NIC7        R6051 -1          A01X+177099Y+047556X0198Y0197     S1      
317P3V3_NIC7        VIA   -    MD0100PA00X+173150Y+047705X0200Y         S0      
317P3V3_NIC7        VIA   -    MD0100PA00X+172900Y+047705X0200Y         S0      
317P3V3_NIC7        VIA   -    MD0100PA00X+173765Y+047971X0200Y    R090 S0      
317P3V3_NIC7        VIA   -    MD0100PA00X+173765Y+047721X0200Y    R090 S0      
317P3V3_NIC7        VIA   -    MD0100PA00X+173495Y+047922X0200Y    R090 S0      
317P3V3_NIC7        VIA   -    MD0100PA00X+162594Y+044587X0200Y         S0      
317P3V3_NIC7        VIA   -    MD0100PA00X+159953Y+039672X0200Y    R180 S0      
327P3V3_NIC7        R384  -2          A01X+160195Y+039672X0198Y0197R180 S1      
317P3V3_NIC7        VIA   -    MD0100PA00X+166707Y+045418X0200Y         S0      
317P3V3_NIC7        VIA   -    MD0100PA00X+166457Y+045418X0200Y         S0      
317P3V3_NIC7        VIA   -    MD0100PA00X+166707Y+045168X0200Y         S0      
317P3V3_NIC7        VIA   -    MD0100PA00X+166457Y+045168X0200Y         S0      
317P3V3_NIC7        VIA   -    MD0100PA00X+168052Y+039791X0200Y         S0      
317P3V3_NIC7        VIA   -    MD0100PA00X+168052Y+038191X0200Y         S0      
317P3V3_NIC7        VIA   -    MD0100PA00X+168052Y+037791X0200Y         S0      
317P3V3_NIC7        VIA   -    MD0100PA00X+168612Y+031174X0200Y         S0      
327P3V3_NIC7        R406  -1          A01X+168352Y+031174X0198Y0197R090 S1      
317P3V3_NIC7        VIA   -    MD0100PA00X+173001Y+046206X0200Y    R090 S0      
317P3V3_NIC7        VIA   -    MD0100PA00X+173301Y+046206X0200Y    R090 S0      
317P3V3_NIC7        VIA   -    MD0100PA00X+176490Y+047038X0200Y    R090 S0      
327P3V3_NIC7        R885  -1          A01X+176250Y+047038X0198Y0197R180 S1      
327P3V3_NIC7        C959  -1          A18X+166131Y+045115X0198Y0197     S2      
327P3V3_NIC7        C964  -1          A18X+166131Y+045515X0198Y0197     S2      
327P3V3_NIC7        C958  -1          A18X+167372Y+045178X0198Y0197R090 S2      
327P3V3_NIC7        C960  -1          A18X+166977Y+045178X0198Y0197R090 S2      
327P3V3_NIC7        R382  -2   M      A18X+167812Y+039791X0198Y0197R180 S2      
327P3V3_NIC7        R369  -2   M      A18X+167812Y+038191X0198Y0197R180 S2      
327P3V3_NIC7        R368  -2   M      A18X+167812Y+037791X0198Y0197R180 S2      
327P3V3_NIC7        PC491 -1          A01X+173019Y+048102X0400Y0500R270 S1      
327P3V3_NIC7        PD59  -C          A01X+171959Y+047611X0670Y0990     S1      
327P3V3_NIC7        J27   -B11        A01X+165968Y+045368X0140Y0480R090 S1      
317P3V3_NIC7        VIA   -    MD0100PA00X+088331Y+066661X0200Y         S0      
317P3V3_NIC7        VIA   -    MD0100PA00X+162722Y+064325X0200Y         S0      
317P3V3_NIC7        VIA   -    M      A01X+161854Y+061829X0200Y    R180 S2      
017P3V3_NIC7        VIA   -    M      A18X+161854Y+061829X0260Y    R180 S2      
017P3V3_NIC7              -    MD0100PA00X+161854Y+061829                       
327P3V3_NIC7        R2477 -1          A01X+161854Y+062079X0198Y0197R090 S1      
327P3V3_NIC7        R392  -2          A01X+162354Y+044587X0198Y0197     S1      
327m2323            J22   -B14        A01X+063836Y+054474X0140Y0480R270 S1      
317m2323            VIA   -    MD0100PA00X+055907Y+068821X0200Y    R090 S0      
327m2323            R1099 -1          A01X+055305Y+068851X0198Y0197R180 S1      
317m2323            VIA   -    MD0100PA00X+063201Y+054526X0200Y         S0      
327m2324            R6803 -2          A18X+086267Y+087894X0198Y0197     S2      
327m2324            VIA   -    M      A18X+086177Y+087437X0260Y         S2      
327m2324            R1489 -1   M      A18X+084265Y+087548X0198Y0197R180 S2      
327m2324            R6800 -1          A18X+083015Y+088039X0198Y0197     S2      
317m2325            J11   -C10  D0122PA01X+036106Y+161138X0282Y    R180 S3      
317m2325            J3    -C10  D0122PA01X+018784Y+161138X0282Y    R180 S3      
327P3V3_NIC6_SS     PU51  -7          A01X+141941Y+049762X0110Y0240R090 S1      
317P3V3_NIC6_SS     VIA   -    M      A01X+141506Y+050020X0200Y    R180 S2      
017P3V3_NIC6_SS     VIA   -    M      A18X+141506Y+050020X0260Y    R180 S2      
017P3V3_NIC6_SS           -    MD0100PA00X+141506Y+050020                       
327P3V3_NIC6_SS     PC483 -1          A01X+141264Y+049998X0198Y0197R180 S1      
327USB2_FIO_DN      J2    -B3         A01X+090330Y+023622X0150Y0530R090 S1      
327USB2_FIO_DN      U110  -6          A01X+090681Y+030924X0060Y0280     S1      
317USB2_FIO_DN      VIA   -    MD0100PA00X+089328Y+023674X0200Y         S0      
317USB2_FIO_DN      VIA   -    MD0100PA00X+090590Y+030235X0200Y         S0      
317m2326            VIA   -    MD0100PA00X+120918Y+046022X0200Y         S0      
317m2326            VIA   -    MD0100PA00X+056157Y+071221X0200Y    R090 S0      
327m2326            J25   -B14        A01X+120259Y+046077X0140Y0480R090 S1      
327m2326            R1106 -1          A01X+055305Y+071251X0198Y0197R180 S1      
327m2327            R1225 -2          A18X+041874Y+128564X0198Y0197R270 S2      
327m2327            U118  -13         A18X+041758Y+129597X0100Y0220     S2      
317SMB_MB_R_SDA     VIA   -    MD0100PA00X+118922Y+094070X0200Y    R270 S0      
327SMB_MB_R_SDA     R6243 -2          A01X+096257Y+093024X0198Y0197R270 S1      
317SMB_MB_R_SDA     VIA   -    M      A01X+096428Y+092778X0200Y    R270 S2      
017SMB_MB_R_SDA     VIA   -    M      A18X+096428Y+092778X0260Y    R270 S2      
017SMB_MB_R_SDA           -    MD0100PA00X+096428Y+092778                       
327SMB_MB_R_SDA     R4108 -2          A18X+118922Y+094321X0198Y0197R090 S2      
327SMB_MB_R_SDA     R5647 -1          A01X+126872Y+091495X0198Y0197     S1      
317P3V3_CLI_VPHY    VIA   -    MD0100PA00X+054058Y+079389X0200Y    R270 S0      
327P3V3_CLI_VPHY    VIA   -           A18X+053985Y+078810X0260Y         S2      
327P3V3_CLI_VPHY    C2601 -1          A18X+053732Y+079265X0198Y0197     S2      
327P3V3_CLI_VPHY    L7    -2          A18X+053810Y+080339X0280Y0320R270 S2      
327P3V3_CLI_VPHY    U98   -4          A01X+054058Y+078933X0110Y0540     S1      
327P3V3_CLI_VPHY    C2602 -1          A18X+053810Y+079789X0280Y0320R090 S2      
327m2328            J21   -B15        A01X+028842Y+046313X0140Y0480R090 S1      
317m2328            VIA   -    MD0100PA00X+029501Y+046362X0200Y         S0      
317m2328            VIA   -    MD0100PA00X+053426Y+066156X0200Y         S0      
327m2328            R1096 -1          A01X+053396Y+067008X0198Y0197R090 S1      
327m2329            VIA   -    M      A01X+131806Y+035951X0300Y         S1      
327m2329            R3511 -1          A01X+132090Y+036517X0198Y0197R090 S1      
327m2329            U116  -48         A01X+132242Y+035321X0070Y0340R180 S1      
327m2329            R3508 -2   M      A01X+131690Y+036517X0198Y0197R270 S1      
327m2330            R1232 -2          A18X+041843Y+132678X0198Y0197R090 S2      
327m2330            U118  -28         A18X+041758Y+131467X0100Y0220R180 S2      
327m2331            R1487 -1          A18X+085683Y+087146X0198Y0197     S2      
327m2331            R6802 -2          A18X+086426Y+086914X0198Y0197     S2      
327m2331            VIA   -    M      A18X+086731Y+087374X0260Y         S2      
327m2331            R6799 -1          A18X+085682Y+087547X0198Y0197     S2      
317m2332            J11   -F10  D0122PA01X+036106Y+159602X0282Y    R180 S3      
317m2332            J3    -F10  D0122PA01X+018784Y+159602X0282Y    R180 S3      
327USB2_FIO_DP      J2    -B2         A01X+090330Y+023386X0150Y0530R090 S1      
327USB2_FIO_DP      U110  -7          A01X+090838Y+030924X0060Y0280     S1      
317USB2_FIO_DP      VIA   -    MD0100PA00X+089328Y+023334X0200Y         S0      
317USB2_FIO_DP      VIA   -    MD0100PA00X+090930Y+030235X0200Y         S0      
327P1V8_CLI_VCORE   VIA   -           A18X+052617Y+080120X0260Y         S2      
327P1V8_CLI_VCORE   VIA   -           A18X+056076Y+079142X0260Y         S2      
317P1V8_CLI_VCORE   VIA   -    MD0100PA00X+055633Y+079374X0200Y    R090 S0      
327P1V8_CLI_VCORE   C2594 -1   M      A18X+055617Y+079099X0198Y0197R090 S2      
317P1V8_CLI_VCORE   VIA   -    MD0100PA00X+052270Y+079710X0200Y    R180 S0      
317P1V8_CLI_VCORE   VIA   -    M      A01X+055784Y+085167X0200Y         S2      
017P1V8_CLI_VCORE   VIA   -    M      A18X+055784Y+085167X0260Y         S2      
017P1V8_CLI_VCORE         -    MD0100PA00X+055784Y+085167                       
317P1V8_CLI_VCORE   VIA   -    MD0100PA00X+055633Y+082999X0200Y    R270 S0      
327P1V8_CLI_VCORE   C2596 -1   M      A01X+055510Y+084639X0280Y0320R090 S1      
327P1V8_CLI_VCORE   C2595 -1   M      A01X+055570Y+084139X0198Y0197R180 S1      
327P1V8_CLI_VCORE   U98   -37  M      A01X+055633Y+083440X0110Y0540     S1      
317P1V8_CLI_VCORE   VIA   -    MD0100PA00X+053131Y+082663X0200Y         S0      
327P1V8_CLI_VCORE   C2593 -1          A18X+053424Y+082572X0198Y0197R090 S2      
327P1V8_CLI_VCORE   U98   -49         A01X+052690Y+082663X0110Y0540R090 S1      
327P1V8_CLI_VCORE   U98   -12         A01X+055633Y+078933X0110Y0540     S1      
327P1V8_CLI_VCORE   C2592 -1   M      A18X+052524Y+079672X0198Y0197R090 S2      
327P1V8_CLI_VCORE   U98   -64         A01X+052690Y+079710X0110Y0540R090 S1      
317m2333            VIA   -    MD0100PA00X+166627Y+046022X0200Y         S0      
317m2333            VIA   -    MD0100PA00X+053558Y+073659X0200Y    R180 S0      
327m2333            J27   -B14        A01X+165968Y+046077X0140Y0480R090 S1      
327m2333            R1110 -1          A01X+053528Y+072857X0198Y0197R270 S1      
327m2334            U118  -19         A18X+040921Y+130236X0100Y0220R270 S2      
327m2334            R1227 -2          A18X+039589Y+129928X0198Y0197R180 S2      
327P3V3_CLI_VPLL    VIA   -           A18X+055090Y+078951X0260Y         S2      
317P3V3_CLI_VPLL    VIA   -    MD0100PA00X+055042Y+079374X0200Y    R090 S0      
327P3V3_CLI_VPLL    C2600 -1          A18X+055180Y+080139X0280Y0320R270 S2      
327P3V3_CLI_VPLL    L6    -2          A18X+055180Y+080689X0280Y0320R090 S2      
327P3V3_CLI_VPLL    C2599 -1          A18X+055213Y+079639X0198Y0197R180 S2      
327P3V3_CLI_VPLL    U98   -9          A01X+055042Y+078933X0110Y0540     S1      
327m2335            J21   -B14        A01X+028842Y+046077X0140Y0480R090 S1      
317m2335            VIA   -    MD0100PA00X+029501Y+046022X0200Y         S0      
317m2335            VIA   -    MD0100PA00X+053766Y+066156X0200Y         S0      
327m2335            R1097 -1          A01X+053796Y+067008X0198Y0197R090 S1      
327m2336            VIA   -    M      A01X+132501Y+036026X0300Y         S1      
327m2336            R3512 -1          A01X+132906Y+036517X0198Y0197R090 S1      
327m2336            U116  -47         A01X+132400Y+035321X0070Y0340R180 S1      
327m2336            R3509 -2   M      A01X+132501Y+036517X0198Y0197R270 S1      
327m2337            U118  -23         A18X+040921Y+131024X0100Y0220R270 S2      
327m2337            R1230 -2          A18X+039273Y+131529X0198Y0197R180 S2      
317GPU_PEX_STRAP1   VIA   -    M      A01X+025088Y+153278X0200Y         S2      
017GPU_PEX_STRAP1   VIA   -    M      A18X+025088Y+153278X0260Y         S2      
017GPU_PEX_STRAP1         -    MD0100PA00X+025088Y+153278                       
317GPU_PEX_STRAP1   J11   -I10  D0122PA00X+036106Y+158067X0282Y    R180 S3      
327GPU_PEX_STRAP1   C4048 -2   M      A01X+024804Y+152731X0198Y0197R270 S1      
327GPU_PEX_STRAP1   R1834 -2          A01X+023262Y+151458X0198Y0197     S1      
327USB2_MICRO_DN    VIA   -    M      A18X+162678Y+065953X0160Y0041R090 S2      
327USB2_MICRO_DN    U110  -4          A01X+090470Y+031105X0070Y0200R270 S1      
317USB2_MICRO_DN    VIA   -    MD0100PA00X+089935Y+031196X0200Y         S0      
317USB2_MICRO_DN    VIA   -    MD0100PA00X+175491Y+082074X0200Y    R090 S0      
327USB2_MICRO_DN    R1000 -1          A01X+176093Y+082088X0198Y0197     S1      
327m2338            J22   -B15        A01X+063836Y+054238X0140Y0480R270 S1      
317m2338            VIA   -    MD0100PA00X+055907Y+068481X0200Y    R090 S0      
327m2338            R1098 -1          A01X+055305Y+068451X0198Y0197R180 S1      
317m2338            VIA   -    MD0100PA00X+063201Y+054186X0200Y         S0      
327m2339            R1226 -2          A18X+041474Y+128564X0198Y0197R270 S2      
327m2339            U118  -14         A18X+041561Y+129597X0100Y0220     S2      
327m2340            PU48  -8          A01X+038099Y+047457X0110Y0240R270 S1      
317m2340            VIA   -    M      A01X+038563Y+047202X0200Y         S2      
017m2340            VIA   -    M      A18X+038563Y+047202X0260Y         S2      
017m2340                  -    MD0100PA00X+038563Y+047202                       
327m2340            R4476 -1          A01X+038809Y+047438X0198Y0197     S1      
327m2340            R880  -2   M      A01X+038809Y+047038X0198Y0197R180 S1      
317m2341            VIA   -    MD0100PA00X+055907Y+070081X0200Y    R090 S0      
327m2341            R1102 -1          A01X+055305Y+070051X0198Y0197R180 S1      
317m2341            VIA   -    MD0100PA00X+108910Y+054186X0200Y         S0      
327m2341            J24   -B15        A01X+109544Y+054238X0140Y0480R270 S1      
327m2342            U118  -20         A18X+040921Y+130433X0100Y0220R270 S2      
327m2342            R1228 -2          A18X+039589Y+130328X0198Y0197R180 S2      
317m2343            J11   -P9   D0122PA00X+035240Y+150468X0282Y    R180 S3      
317m2343            VIA   -    MD0100PA00X+045438Y+130524X0200Y    R180 S0      
327m2343            R1218 -2          A18X+044848Y+130554X0198Y0197R180 S2      
317RST_MB_BMC_N     VIA   -    MD0100PA00X+087822Y+085159X0180Y    R270 S0      
327RST_MB_BMC_N     U5    -E16        A01X+087979Y+085002X0160Y    R180 S1      
317RST_MB_BMC_N     VIA   -    MD0100PA00X+089466Y+099433X0200Y         S0      
317RST_MB_BMC_N     VIA   -    M      A01X+108947Y+163821X0200Y    R090 S2      
017RST_MB_BMC_N     VIA   -    M      A18X+108947Y+163821X0260Y    R090 S2      
017RST_MB_BMC_N           -    MD0100PA00X+108947Y+163821                       
327RST_MB_BMC_N     R1810 -2          A01X+108547Y+163500X0198Y0197R090 S1      
327RST_MB_BMC_N     R1817 -1   M      A01X+108947Y+163500X0198Y0197R270 S1      
327USB2_MICRO_DP    VIA   -    M      A18X+176355Y+080282X0160Y0041R090 S2      
317USB2_MICRO_DP    VIA   -    MD0100PA00X+175491Y+082433X0200Y    R090 S0      
327USB2_MICRO_DP    R1001 -1          A01X+176093Y+082438X0198Y0197     S1      
317USB2_MICRO_DP    VIA   -    MD0100PA00X+089935Y+030856X0200Y         S0      
327USB2_MICRO_DP    U110  -5          A01X+090470Y+030947X0070Y0200R270 S1      
317m2344            VIA   -    MD0100PA00X+055907Y+072021X0200Y    R090 S0      
317m2344            VIA   -    MD0100PA00X+154618Y+054526X0200Y         S0      
327m2344            J26   -B14        A01X+155253Y+054474X0140Y0480R270 S1      
327m2344            R1108 -1          A01X+055305Y+072051X0198Y0197R180 S1      
327m2345            U118  -22         A18X+040921Y+130827X0100Y0220R270 S2      
327m2345            R1229 -2          A18X+039273Y+131129X0198Y0197R180 S2      
317m2346            J11   -A9   D0122PA00X+035240Y+162240X0282Y    R180 S3      
317m2346            VIA   -    M      A01X+023262Y+153110X0200Y         S2      
017m2346            VIA   -    M      A18X+023262Y+153110X0260Y         S2      
017m2346                  -    MD0100PA00X+023262Y+153110                       
327m2346            R1826 -2          A01X+023375Y+153414X0198Y0197R270 S1      
327m2346            C4038 -2          A01X+023394Y+154631X0198Y0197R270 S1      
327P3V3_NIC3_OCP    PR253 -1          A01X+084518Y+047338X0198Y0197     S1      
327P3V3_NIC3_OCP    PU52  -9          A01X+083808Y+047154X0110Y0240R270 S1      
317P3V3_NIC3_OCP    VIA   -    M      A01X+084278Y+047308X0200Y         S2      
017P3V3_NIC3_OCP    VIA   -    M      A18X+084278Y+047308X0260Y         S2      
017P3V3_NIC3_OCP          -    MD0100PA00X+084278Y+047308                       
317m2347            VIA   -    MD0100PA00X+120918Y+046362X0200Y         S0      
317m2347            VIA   -    MD0100PA00X+056157Y+070881X0200Y    R090 S0      
327m2347            R1105 -1          A01X+055305Y+070851X0198Y0197R180 S1      
327m2347            J25   -B15        A01X+120259Y+046313X0140Y0480R090 S1      
327m2348            C2635 -1          A18X+102145Y+031733X0198Y0197R270 S2      
327m2348            C2634 -1          A18X+101492Y+031639X0280Y0320R090 S2      
327m2348            R1046 -2          A18X+102174Y+030693X0280Y0320R090 S2      
327m2348            VIA   -           A18X+101528Y+030962X0260Y         S2      
327m2348            U113  -B17        A01X+102235Y+031961X0110Y0180     S1      
317m2348            VIA   -    MD0100PA00X+102185Y+031040X0200Y         S0      
317m2348            VIA   -    MD0100PA00X+102244Y+031286X0200Y         S0      
327m2349            U118  -27         A18X+041561Y+131467X0100Y0220R180 S2      
327m2349            R1231 -2          A18X+041443Y+132678X0198Y0197R090 S2      
317m2350            J11   -C9   D0122PA00X+035240Y+161217X0282Y    R180 S3      
317m2350            VIA   -    M      A01X+022755Y+153068X0200Y         S2      
017m2350            VIA   -    M      A18X+022755Y+153068X0260Y         S2      
017m2350                  -    MD0100PA00X+022755Y+153068                       
327m2350            R1827 -1          A01X+022975Y+153414X0198Y0197R090 S1      
317m2351            VIA   -    MD0100PA00X+118860Y+038150X0200Y         S0      
317m2351            VIA   -    M      A01X+146314Y+039158X0200Y         S2      
017m2351            VIA   -    M      A18X+146314Y+039158X0260Y         S2      
017m2351                  -    MD0100PA00X+146314Y+039158                       
317m2351            VIA   -    MD0100PA00X+138305Y+087081X0180Y         S0      
327m2351            U6    -K22        A01X+138147Y+086924X0160Y         S1      
327m2351            R259  -2          A18X+118860Y+038450X0198Y0197     S2      
317m2352            VIA   -    MD0100PA00X+055907Y+071681X0200Y    R090 S0      
317m2352            VIA   -    MD0100PA00X+154618Y+054186X0200Y         S0      
327m2352            J26   -B15        A01X+155253Y+054238X0140Y0480R270 S1      
327m2352            R1107 -1          A01X+055305Y+071651X0198Y0197R180 S1      
327m2353            U113  -B21        A01X+103022Y+031961X0110Y0180     S1      
327m2353            U113  -B23        A01X+103465Y+032207X0110Y0180R270 S1      
327m2353            C2630 -1          A18X+104702Y+031695X0280Y0320R270 S2      
327m2353            C2633 -1          A18X+103688Y+032475X0198Y0197     S2      
327m2353            C2631 -1          A18X+102967Y+031733X0198Y0197R270 S2      
317m2353            VIA   -    MD0100PA00X+103022Y+031355X0200Y         S0      
317m2353            VIA   -    M      A01X+104178Y+032111X0200Y         S2      
017m2353            VIA   -    M      A18X+104178Y+032111X0260Y         S2      
017m2353                  -    MD0100PA00X+104178Y+032111                       
327m2353            C2632 -1          A18X+102592Y+031725X0198Y0197R270 S2      
327m2353            L8    -2          A18X+104618Y+031045X0440Y0540R180 S2      
327m2353            R1046 -1          A18X+102754Y+030693X0280Y0320R090 S2      
327m2354            R1231 -1          A18X+041443Y+132993X0198Y0197R090 S2      
317m2354            VIA   -    MD0080PA00X+153130Y+117618X0160Y    R270 S0      
327m2354            PEX3  -AB5        A01X+153130Y+117618X0180Y         S1      
327m2355            PU53  -8          A01X+175225Y+047457X0110Y0240R270 S1      
317m2355            VIA   -    M      A01X+175689Y+047202X0200Y         S2      
017m2355            VIA   -    M      A18X+175689Y+047202X0260Y         S2      
017m2355                  -    MD0100PA00X+175689Y+047202                       
327m2355            R4481 -1          A01X+175935Y+047438X0198Y0197     S1      
327m2355            R885  -2   M      A01X+175935Y+047038X0198Y0197R180 S1      
327PEX_USB2_SEL     U110  -10         A01X+091049Y+031262X0070Y0200R270 S1      
327PEX_USB2_SEL     R1003 -1   M      A01X+091699Y+031098X0198Y0197     S1      
327PEX_USB2_SEL     VIA   -    M      A01X+093757Y+030601X0300Y         S1      
327PEX_USB2_SEL     J4    -2          A01X+091580Y+050643X0500Y1350R090 S1      
327m2356            C2650 -1          A18X+100282Y+033695X0280Y0320R090 S2      
327m2356            VIA   -           A18X+099706Y+034852X0260Y         S2      
327m2356            R1048 -2   M      A18X+100282Y+034195X0280Y0320R270 S2      
327m2356            U113  -B6         A01X+101005Y+033192X0110Y0180R090 S1      
317m2356            VIA   -    MD0100PA00X+100308Y+033250X0200Y         S0      
327m2356            C2651 -1          A18X+100768Y+033309X0198Y0197R180 S2      
317m2357            VIA   -    M      A01X+039365Y+047438X0200Y         S2      
017m2357            VIA   -    M      A18X+039365Y+047438X0260Y         S2      
017m2357                  -    MD0100PA00X+039365Y+047438                       
327m2357            R5859 -2          A01X+039973Y+046756X0198Y0197R180 S1      
327m2357            R4476 -2          A01X+039124Y+047438X0198Y0197     S1      
317m2357            VIA   -    MD0100PA00X+137360Y+088656X0180Y         S0      
327m2357            U6    -E19        A01X+137202Y+088499X0160Y         S1      
317m2357            VIA   -    MD0100PA00X+046549Y+086197X0200Y         S0      
327P3V3_NIC2_SS     PU50  -7          A01X+050524Y+049762X0110Y0240R090 S1      
317P3V3_NIC2_SS     VIA   -    M      A01X+050089Y+050020X0200Y    R180 S2      
017P3V3_NIC2_SS     VIA   -    M      A18X+050089Y+050020X0260Y    R180 S2      
017P3V3_NIC2_SS           -    MD0100PA00X+050089Y+050020                       
327P3V3_NIC2_SS     PC482 -1          A01X+049847Y+049998X0198Y0197R180 S1      
327m2358            R1048 -1          A18X+099702Y+034195X0280Y0320R270 S2      
317m2358            VIA   -    MD0100PA00X+099702Y+034535X0200Y    R270 S0      
327m2358            VIA   -           A18X+102590Y+035389X0260Y         S2      
327m2358            U113  -B40        A01X+102038Y+034422X0110Y0180     S1      
327m2358            L10   -2          A18X+104218Y+035095X0440Y0540R180 S2      
327m2358            C2649 -1          A18X+104384Y+033745X0198Y0197R180 S2      
327m2358            C2648 -1          A18X+103686Y+033774X0198Y0197     S2      
327m2358            C2647 -1          A18X+103693Y+033352X0198Y0197     S2      
327m2358            C2644 -1          A18X+104302Y+034395X0280Y0320R270 S2      
327m2358            C2645 -1          A18X+102883Y+034422X0198Y0197R090 S2      
327m2358            C2646 -1          A18X+102034Y+034428X0198Y0197R090 S2      
327m2358            U113  -B35        A01X+103022Y+034422X0110Y0180     S1      
327m2358            U113  -B29        A01X+103465Y+033388X0110Y0180R270 S1      
327m2358            U113  -B32        A01X+103465Y+033979X0110Y0180R270 S1      
317m2358            VIA   -    M      A01X+103126Y+035043X0200Y         S2      
017m2358            VIA   -    M      A18X+103126Y+035043X0260Y         S2      
017m2358                  -    MD0100PA00X+103126Y+035043                       
317m2358            VIA   -    M      A01X+102041Y+035077X0200Y         S2      
017m2358            VIA   -    M      A18X+102041Y+035077X0260Y         S2      
017m2358                  -    MD0100PA00X+102041Y+035077                       
317m2358            VIA   -    MD0100PA00X+104311Y+034023X0200Y         S0      
317m2358            VIA   -    MD0100PA00X+104295Y+033370X0200Y         S0      
327m2359            R1232 -1          A18X+041843Y+132993X0198Y0197R090 S2      
317m2359            VIA   -    MD0080PA00X+152756Y+117618X0160Y    R270 S0      
327m2359            PEX3  -AB4        A01X+152756Y+117618X0180Y         S1      
317m2360            VIA   -    M      A01X+140200Y+089200X0200Y         S2      
017m2360            VIA   -    M      A18X+140200Y+089200X0260Y         S2      
017m2360                  -    MD0100PA00X+140200Y+089200                       
327m2360            R3623 -1          A01X+140792Y+089200X0198Y0197     S1      
317m2360            VIA   -    MD0100PA00X+136730Y+088026X0180Y         S0      
327m2360            U6    -G17        A01X+136572Y+087869X0160Y         S1      
317m2361            VIA   -    M      A01X+091565Y+030744X0200Y         S2      
017m2361            VIA   -    M      A18X+091565Y+030744X0260Y         S2      
017m2361                  -    MD0100PA00X+091565Y+030744                       
327m2361            U110  -8          A01X+091049Y+030947X0070Y0200R270 S1      
327m2361            R1005 -2          A01X+091677Y+030458X0198Y0197R180 S1      
327P3V3_NIC4        R214  -1          A01X+113575Y+055880X0198Y0197R180 S1      
327P3V3_NIC4        R213  -1          A01X+113575Y+056280X0198Y0197R180 S1      
327P3V3_NIC4        C912  -1          A18X+109420Y+055440X0198Y0197R180 S2      
327P3V3_NIC4        C914  -1          A18X+109420Y+055040X0198Y0197R180 S2      
327P3V3_NIC4        VIA   -           A18X+107589Y+054606X0260Y         S2      
327P3V3_NIC4        VIA   -           A18X+105460Y+054680X0260Y         S2      
327P3V3_NIC4        VIA   -           A18X+103171Y+054792X0260Y         S2      
317P3V3_NIC4        VIA   -    MD0100PA00X+094982Y+049598X0200Y    R180 S0      
327P3V3_NIC4        R879  -1          A01X+095240Y+049598X0198Y0197     S1      
317P3V3_NIC4        VIA   -    MD0100PA00X+096382Y+047290X0200Y    R180 S0      
327P3V3_NIC4        R6038 -1          A01X+096382Y+047049X0198Y0197R270 S1      
327P3V3_NIC4        PU47  -1          A01X+097414Y+048778X0110Y0240R090 S1      
327P3V3_NIC4        PU47  -2          A01X+097414Y+048974X0110Y0240R090 S1      
327P3V3_NIC4        PU47  -3          A01X+097414Y+049171X0110Y0240R090 S1      
327P3V3_NIC4        PU47  -4          A01X+097414Y+049368X0110Y0240R090 S1      
327P3V3_NIC4        PU47  -5          A01X+097414Y+049565X0110Y0240R090 S1      
327P3V3_NIC4        C919  -1   M      A01X+115917Y+067583X0198Y0197R180 S1      
317P3V3_NIC4        VIA   -    MD0100PA00X+115917Y+067846X0200Y         S0      
327P3V3_NIC4        U32   -2          A01X+115676Y+066991X0400Y0500R180 S1      
327P3V3_NIC4        R253  -1          A01X+116286Y+067589X0198Y0197     S1      
317P3V3_NIC4        VIA   -    MD0100PA00X+116286Y+067852X0200Y         S0      
327P3V3_NIC4        R2467 -1          A01X+115628Y+065382X0198Y0197R270 S1      
317P3V3_NIC4        VIA   -    MD0100PA00X+115628Y+065632X0200Y         S0      
327P3V3_NIC4        R215  -2          A01X+106460Y+062360X0198Y0197R180 S1      
317P3V3_NIC4        VIA   -    MD0100PA00X+106210Y+062360X0200Y         S0      
317P3V3_NIC4        VIA   -    MD0100PA00X+090075Y+065692X0200Y         S0      
317P3V3_NIC4        VIA   -    MD0100PA00X+086700Y+081000X0200Y         S0      
327P3V3_NIC4        R1510 -2   M      A01X+086458Y+081000X0198Y0197     S1      
327P3V3_NIC4        R1508 -2          A01X+086458Y+081800X0198Y0197     S1      
327P3V3_NIC4        R1509 -2   M      A01X+086458Y+081400X0198Y0197     S1      
317P3V3_NIC4        VIA   -    MD0100PA00X+086142Y+082450X0200Y         S0      
327P3V3_NIC4        C2555 -2   M      A01X+086142Y+082200X0198Y0197R180 S1      
327P3V3_NIC4        U119  -8          A01X+085430Y+081984X0140Y0590R270 S1      
327P3V3_NIC4        R231  -2          A18X+110770Y+061040X0198Y0197     S2      
317P3V3_NIC4        VIA   -    MD0100PA00X+110530Y+061040X0200Y    R180 S0      
327P3V3_NIC4        R216  -2          A01X+106460Y+061960X0198Y0197R180 S1      
317P3V3_NIC4        VIA   -    MD0100PA00X+106210Y+061960X0200Y         S0      
327P3V3_NIC4        R229  -2          A01X+106460Y+060360X0198Y0197R180 S1      
317P3V3_NIC4        VIA   -    MD0100PA00X+106210Y+060360X0200Y         S0      
317P3V3_NIC4        VIA   -    MD0100PA00X+113828Y+056280X0200Y         S0      
327P3V3_NIC4        R239  -2          A01X+114120Y+055770X0198Y0197R180 S1      
317P3V3_NIC4        VIA   -    MD0100PA00X+113821Y+055880X0200Y         S0      
317P3V3_NIC4        VIA   -    MD0100PA00X+098780Y+045965X0200Y         S0      
317P3V3_NIC4        VIA   -    MD0100PA00X+098780Y+046215X0200Y         S0      
317P3V3_NIC4        VIA   -    MD0100PA00X+098780Y+046465X0200Y         S0      
317P3V3_NIC4        VIA   -    MD0100PA00X+098530Y+045965X0200Y         S0      
317P3V3_NIC4        VIA   -    MD0100PA00X+098530Y+046215X0200Y         S0      
317P3V3_NIC4        VIA   -    MD0100PA00X+098530Y+046465X0200Y         S0      
327P3V3_NIC4        PU119 -6_7        A01X+097880Y+045549X0295Y0354R270 S1      
327P3V3_NIC4        PC901 -1          A01X+098682Y+045592X0400Y0500R090 S1      
327P3V3_NIC4        J24   -B11        A01X+109544Y+055183X0140Y0480R270 S1      
327P3V3_NIC4        C915  -1          A01X+105713Y+054192X0198Y0197R270 S1      
327P3V3_NIC4        C913  -1          A01X+105314Y+054197X0198Y0197R270 S1      
327P3V3_NIC4        PD53  -C          A01X+099755Y+049610X0670Y0990R180 S1      
317P3V3_NIC4        VIA   -    MD0100PA00X+099221Y+049613X0200Y    R270 S0      
317P3V3_NIC4        VIA   -    MD0100PA00X+099221Y+049363X0200Y    R270 S0      
317P3V3_NIC4        VIA   -    MD0100PA00X+098813Y+049815X0200Y    R180 S0      
317P3V3_NIC4        VIA   -    MD0100PA00X+098058Y+049549X0200Y    R270 S0      
317P3V3_NIC4        VIA   -    M      A01X+098533Y+049815X0200Y    R180 S2      
017P3V3_NIC4        VIA   -    M      A18X+098533Y+049815X0260Y    R180 S2      
017P3V3_NIC4              -    MD0100PA00X+098533Y+049815                       
317P3V3_NIC4        VIA   -    MD0100PA00X+098058Y+049299X0200Y    R270 S0      
317P3V3_NIC4        VIA   -    MD0100PA00X+098563Y+049515X0200Y    R180 S0      
317P3V3_NIC4        VIA   -    MD0100PA00X+098813Y+049515X0200Y    R180 S0      
317P3V3_NIC4        VIA   -    MD0100PA00X+099221Y+049863X0200Y    R270 S0      
317P3V3_NIC4        VIA   -    MD0100PA00X+097687Y+049371X0200Y    R270 S0      
327P3V3_NIC4        PC455 -1          A01X+098674Y+049131X0400Y0500R090 S1      
327P3V3_NIC4        PC454 -1          A01X+098052Y+049024X0198Y0197R270 S1      
317P3V3_NIC4        VIA   -    MD0100PA00X+099221Y+049113X0200Y    R270 S0      
317P3V3_NIC4        VIA   -    MD0100PA00X+097687Y+049121X0200Y    R270 S0      
317P3V3_NIC4        VIA   -    MD0100PA00X+108729Y+055341X0200Y         S0      
317P3V3_NIC4        VIA   -    MD0100PA00X+108979Y+055341X0200Y         S0      
317P3V3_NIC4        VIA   -    MD0100PA00X+108729Y+055091X0200Y         S0      
317P3V3_NIC4        VIA   -    MD0100PA00X+108979Y+055091X0200Y         S0      
327P3V3_SSD4_OCP    PU55  -9          A01X+048520Y+022506X0110Y0240     S1      
317P3V3_SSD4_OCP    VIA   -    M      A01X+048443Y+023056X0200Y    R090 S2      
017P3V3_SSD4_OCP    VIA   -    M      A18X+048443Y+023056X0260Y    R090 S2      
017P3V3_SSD4_OCP          -    MD0100PA00X+048443Y+023056                       
327P3V3_SSD4_OCP    PR258 -1          A01X+048505Y+023296X0198Y0197R090 S1      
327m2362            VIA   -           A18X+134651Y+035566X0260Y         S2      
327m2362            C2678 -1          A18X+134149Y+033700X0198Y0197     S2      
327m2362            C2674 -1          A18X+132660Y+033116X0198Y0197R270 S2      
327m2362            C2676 -1          A18X+133372Y+033111X0198Y0197R270 S2      
327m2362            VIA   -           A18X+132255Y+032323X0260Y         S2      
327m2362            L14   -2          A18X+130752Y+032747X0280Y0320     S2      
327m2362            C2673 -1          A18X+131354Y+032858X0400Y0500R270 S2      
317m2362            VIA   -    MD0100PA00X+133847Y+035696X0200Y         S0      
327m2362            C2679 -1   M      A18X+134071Y+035277X0198Y0197     S2      
327m2362            U116  -38         A01X+133817Y+035321X0070Y0340R180 S1      
317m2362            VIA   -    MD0100PA00X+134606Y+034711X0200Y         S0      
327m2362            U116  -34         A01X+134270Y+034710X0070Y0340R090 S1      
327m2362            C2677 -1   M      A18X+134182Y+034597X0198Y0197     S2      
317m2362            VIA   -    MD0100PA00X+133100Y+035667X0200Y         S0      
327m2362            C2680 -1   M      A18X+133070Y+035279X0198Y0197R180 S2      
327m2362            U116  -42         A01X+133187Y+035321X0070Y0340R180 S1      
317m2362            VIA   -    M      A01X+129996Y+035695X0200Y         S2      
017m2362            VIA   -    M      A18X+129996Y+035695X0260Y         S2      
017m2362                  -    MD0100PA00X+129996Y+035695                       
327m2362            R1162 -1          A01X+130331Y+035695X0280Y0320R270 S1      
317m2362            VIA   -    MD0100PA00X+134601Y+033608X0200Y         S0      
327m2362            U116  -27         A01X+134270Y+033608X0070Y0340R090 S1      
317m2362            VIA   -    MD0100PA00X+131526Y+033651X0200Y         S0      
327m2362            C2675 -1   M      A18X+132058Y+033762X0198Y0197R180 S2      
327m2362            U116  -10         A01X+131947Y+033608X0070Y0340R270 S1      
317m2362            VIA   -    MD0100PA00X+132557Y+032672X0200Y         S0      
327m2362            U116  -15         A01X+132557Y+032998X0070Y0340     S1      
317m2362            VIA   -    MD0100PA00X+133256Y+032636X0200Y         S0      
327m2362            U116  -19         A01X+133187Y+032998X0070Y0340     S1      
317m2363            VIA   -    MD0080PA00X+106860Y+117805X0160Y    R270 S0      
327m2363            PEX2  -AB4        A01X+107047Y+117618X0180Y         S1      
327m2363            R1230 -1          A18X+038958Y+131529X0198Y0197R180 S2      
317m2363            VIA   -    MD0100PA00X+092465Y+132442X0200Y         S0      
327P3V3_NIC2_OCP    PR249 -1          A01X+049847Y+048798X0198Y0197R180 S1      
327P3V3_NIC2_OCP    PU50  -9          A01X+050524Y+049368X0110Y0240R090 S1      
317P3V3_NIC2_OCP    VIA   -    M      A01X+050122Y+049205X0200Y    R180 S2      
017P3V3_NIC2_OCP    VIA   -    M      A18X+050122Y+049205X0260Y    R180 S2      
017P3V3_NIC2_OCP          -    MD0100PA00X+050122Y+049205                       
317P3V3_SSD5        VIA   -    MD0100PA00X+059165Y+023871X0200Y    R090 S0      
327P3V3_SSD5        R889  -1          A01X+059165Y+023613X0198Y0197R270 S1      
327P3V3_SSD5        PU57  -1          A01X+058166Y+021324X0110Y0240     S1      
327P3V3_SSD5        PU57  -2          A01X+058363Y+021324X0110Y0240     S1      
327P3V3_SSD5        PU57  -3          A01X+058560Y+021324X0110Y0240     S1      
327P3V3_SSD5        PU57  -4          A01X+058756Y+021324X0110Y0240     S1      
327P3V3_SSD5        PU57  -5          A01X+058953Y+021324X0110Y0240     S1      
327P3V3_SSD5        VIA   -    M      A18X+058502Y+019873X0260Y         S2      
327P3V3_SSD5        PC515 -1          A01X+058519Y+020064X0400Y0500     S1      
327P3V3_SSD5        PC514 -1          A01X+058412Y+020686X0198Y0197R180 S1      
327P3V3_SSD5        PD63  -C          A01X+058998Y+018984X0670Y0990R090 S1      
317P3V3_SSD5        VIA   -    MD0100PA00X+058937Y+020681X0200Y    R180 S0      
317P3V3_SSD5        VIA   -    MD0100PA00X+059203Y+020205X0200Y    R090 S0      
317P3V3_SSD5        VIA   -    MD0100PA00X+058687Y+020681X0200Y    R180 S0      
317P3V3_SSD5        VIA   -    MD0100PA00X+058903Y+020175X0200Y    R090 S0      
317P3V3_SSD5        VIA   -    MD0100PA00X+058510Y+021051X0200Y    R180 S0      
317P3V3_SSD5        VIA   -    MD0100PA00X+058760Y+021051X0200Y    R180 S0      
317P3V3_SSD5        VIA   -    M      A01X+059203Y+019925X0200Y    R090 S2      
017P3V3_SSD5        VIA   -    M      A18X+059203Y+019925X0260Y    R090 S2      
017P3V3_SSD5              -    MD0100PA00X+059203Y+019925                       
317P3V3_SSD5        VIA   -    MD0100PA00X+059252Y+019518X0200Y    R180 S0      
317P3V3_SSD5        VIA   -    MD0100PA00X+059002Y+019518X0200Y    R180 S0      
317P3V3_SSD5        VIA   -    MD0100PA00X+058903Y+019925X0200Y    R090 S0      
317P3V3_SSD5        VIA   -    MD0100PA00X+058502Y+019518X0200Y    R180 S0      
317P3V3_SSD5        VIA   -    MD0100PA00X+058752Y+019518X0200Y    R180 S0      
317P3V3_SSD5        VIA   -    MD0100PA00X+052851Y+014754X0200Y         S0      
327P3V3_SSD5        R6063 -1          A01X+053129Y+014754X0198Y0197     S1      
317P3V3_SSD5        VIA   -    MD0100PA00X+064304Y+010619X0200Y    R090 S0      
327P3V3_SSD5        R5741 -1          A01X+064561Y+010824X0198Y0197R270 S1      
317P3V3_SSD5        VIA   -    MD0100PA00X+063611Y+010378X0200Y    R270 S0      
327P3V3_SSD5        R424  -1          A01X+063611Y+010135X0198Y0197R270 S1      
327P3V3_SSD5        R5664 -2          A01X+058187Y+013484X0198Y0197     S1      
327P3V3_SSD5        PC923 -1   M      A01X+058069Y+011967X0400Y0500R090 S1      
327P3V3_SSD5        PU124 -6_7        A01X+057188Y+011762X0295Y0354R270 S1      
317P3V3_SSD5        VIA   -    MD0100PA00X+057642Y+011959X0200Y         S0      
317P3V3_SSD5        VIA   -    MD0100PA00X+057642Y+011659X0200Y         S0      
327P3V3_SSD5        J35   -B11        A01X+061955Y+009760X0150Y0500R090 S1      
317P3V3_SSD5        VIA   -    MD0100PA00X+063256Y+009855X0200Y    R090 S0      
327P3V3_SSD5        C970  -2   M      A01X+063003Y+009855X0198Y0197R270 S1      
317P3V3_SSD5        VIA   -    M      A01X+058604Y+009767X0200Y         S2      
017P3V3_SSD5        VIA   -    M      A18X+058604Y+009767X0260Y         S2      
017P3V3_SSD5              -    MD0100PA00X+058604Y+009767                       
327P3V3_SSD5        R426  -1          A01X+058847Y+009767X0198Y0197     S1      
317P3V3_SSD5        VIA   -    MD0100PA00X+065657Y+008058X0200Y         S0      
327P3V3_SSD5        R1664 -1          A01X+065416Y+008058X0198Y0197R180 S1      
317P3V3_SSD5        VIA   -    MD0100PA00X+065656Y+006858X0200Y         S0      
327P3V3_SSD5        R1663 -1          A01X+065416Y+006858X0198Y0197R180 S1      
317P3V3_SSD5        VIA   -    MD0100PA00X+065751Y+005801X0200Y         S0      
327P3V3_SSD5        C2722 -2   M      A01X+066034Y+005801X0198Y0197R180 S1      
327P3V3_SSD5        U131  -1          A01X+066008Y+006472X0240Y0460R180 S1      
317m2364            VIA   -    M      A01X+090616Y+036719X0200Y    R090 S2      
017m2364            VIA   -    M      A18X+090616Y+036719X0260Y    R090 S2      
017m2364                  -    MD0100PA00X+090616Y+036719                       
327m2364            U112  -23         A01X+091184Y+036719X0100Y0290R090 S1      
327m2364            R1022 -1          A01X+090234Y+036237X0198Y0197R180 S1      
327m2365            VIA   -           A18X+131581Y+035378X0260Y         S2      
327m2365            VIA   -           A18X+132092Y+035664X0260Y         S2      
327m2365            C2681 -1          A01X+130911Y+035145X0280Y0320R090 S1      
327m2365            R1162 -2          A01X+130911Y+035695X0280Y0320R270 S1      
327m2365            U116  -3          A01X+131947Y+034710X0070Y0340R270 S1      
317m2365            VIA   -    M      A01X+130801Y+034811X0200Y         S2      
017m2365            VIA   -    M      A18X+130801Y+034811X0260Y         S2      
017m2365                  -    MD0100PA00X+130801Y+034811                       
327m2365            C2682 -1   M      A18X+132020Y+034603X0198Y0197R180 S2      
317m2365            VIA   -    MD0100PA00X+132649Y+035694X0200Y         S0      
327m2365            U116  -44         A01X+132872Y+035321X0070Y0340R180 S1      
327m2365            C2683 -1   M      A18X+132649Y+035365X0198Y0197R090 S2      
327NIC1_CLK_EN_N    R3616 -2          A01X+140792Y+089600X0198Y0197R180 S1      
317NIC1_CLK_EN_N    VIA   -    M      A01X+140550Y+089600X0200Y         S2      
017NIC1_CLK_EN_N    VIA   -    M      A18X+140550Y+089600X0260Y         S2      
017NIC1_CLK_EN_N          -    MD0100PA00X+140550Y+089600                       
317NIC1_CLK_EN_N    VIA   -    MD0100PA00X+137360Y+088341X0180Y         S0      
327NIC1_CLK_EN_N    U6    -F19        A01X+137202Y+088184X0160Y         S1      
327P3V3_NIC5_OCP    PR246 -1          A01X+130227Y+047838X0198Y0197     S1      
327P3V3_NIC5_OCP    PU49  -9          A01X+129516Y+047654X0110Y0240R270 S1      
317P3V3_NIC5_OCP    VIA   -    M      A01X+129987Y+047732X0200Y    R090 S2      
017P3V3_NIC5_OCP    VIA   -    M      A18X+129987Y+047732X0260Y    R090 S2      
017P3V3_NIC5_OCP          -    MD0100PA00X+129987Y+047732                       
327P3V3_SSD2_SS     PU59  -7          A01X+023678Y+022506X0110Y0240     S1      
317P3V3_SSD2_SS     VIA   -    M      A01X+024091Y+023012X0200Y    R090 S2      
017P3V3_SSD2_SS     VIA   -    M      A18X+024091Y+023012X0260Y    R090 S2      
017P3V3_SSD2_SS           -    MD0100PA00X+024091Y+023012                       
327P3V3_SSD2_SS     PC530 -1          A01X+024092Y+023298X0198Y0197R090 S1      
327m2366            PEX2  -AB5        A01X+107421Y+117618X0180Y         S1      
317m2366            VIA   -    MD0080PA00X+107234Y+117805X0160Y    R270 S0      
317m2366            VIA   -    MD0100PA00X+092465Y+132782X0200Y         S0      
327m2366            R1229 -1          A18X+038958Y+131129X0198Y0197R180 S2      
327m2367            R2    -2          A01X+015042Y+062760X0198Y0197R180 S1      
327m2367            R23   -1   M      A01X+015042Y+063142X0198Y0197     S1      
317m2367            VIA   -    M      A01X+014947Y+063419X0200Y         S2      
017m2367            VIA   -    M      A18X+014947Y+063419X0260Y         S2      
017m2367                  -    MD0100PA00X+014947Y+063419                       
317m2367            VIA   -    MD0100PA00X+020305Y+069372X0200Y         S0      
327m2367            U6    -D21        A01X+137832Y+088814X0160Y         S1      
317m2367            VIA   -    MD0100PA00X+137990Y+088971X0180Y         S0      
317MB_BIC_MON       VIA   -    MD0100PA00X+088840Y+099458X0200Y         S0      
317MB_BIC_MON       VIA   -    MD0100PA00X+089397Y+084529X0180Y    R270 S0      
327MB_BIC_MON       U5    -D11        A01X+089554Y+084687X0160Y    R180 S1      
327MB_BIC_MON       VIA   -           A18X+089025Y+083598X0260Y         S2      
327MB_BIC_MON       R1809 -2          A01X+110147Y+163185X0198Y0197R270 S1      
327MB_BIC_MON       R1815 -1   M      A01X+110547Y+163500X0198Y0197R270 S1      
317MB_BIC_MON       VIA   -    M      A01X+110547Y+163843X0200Y         S2      
017MB_BIC_MON       VIA   -    M      A18X+110547Y+163843X0260Y         S2      
017MB_BIC_MON             -    MD0100PA00X+110547Y+163843                       
317m2368            VIA   -    M      A01X+119175Y+039268X0200Y         S2      
017m2368            VIA   -    M      A18X+119175Y+039268X0260Y         S2      
017m2368                  -    MD0100PA00X+119175Y+039268                       
317m2368            VIA   -    MD0100PA00X+145987Y+039170X0200Y         S0      
317m2368            VIA   -    MD0100PA00X+137990Y+086766X0180Y         S0      
327m2368            U6    -L21        A01X+137832Y+086609X0160Y         S1      
327m2368            R257  -2          A18X+119510Y+038800X0198Y0197     S2      
327m2368            R278  -1   M      A18X+119175Y+038800X0198Y0197     S2      
327m2369            PU47  -8          A01X+096233Y+049565X0110Y0240R090 S1      
317m2369            VIA   -    M      A01X+095960Y+049649X0200Y    R180 S2      
017m2369            VIA   -    M      A18X+095960Y+049649X0260Y    R180 S2      
017m2369                  -    MD0100PA00X+095960Y+049649                       
327m2369            R4475 -1          A01X+095555Y+049198X0198Y0197R180 S1      
327m2369            R879  -2   M      A01X+095555Y+049598X0198Y0197     S1      
317m2370            VIA   -    MD0100PA00X+038509Y+130085X0200Y         S0      
327m2370            R1228 -1          A18X+039274Y+130328X0198Y0197R180 S2      
327m2370            PEX1  -AB4        A01X+061339Y+117618X0180Y         S1      
317m2370            VIA   -    MD0080PA00X+061152Y+117805X0160Y    R270 S0      
317m2371            VIA   -    M      A01X+015266Y+064539X0200Y         S2      
017m2371            VIA   -    M      A18X+015266Y+064539X0260Y         S2      
017m2371                  -    MD0100PA00X+015266Y+064539                       
327m2371            R4    -2          A01X+015042Y+064197X0198Y0197R180 S1      
317m2371            VIA   -    MD0100PA00X+138305Y+088971X0180Y         S0      
327m2371            U6    -D22        A01X+138147Y+088814X0160Y         S1      
317m2371            VIA   -    MD0100PA00X+020112Y+069558X0200Y         S0      
317MB_BMC_MON       J12   -I10  D0122PA00X+053429Y+158067X0282Y    R180 S3      
317MB_BMC_MON       VIA   -    M      A01X+109157Y+156130X0200Y    R090 S2      
017MB_BMC_MON       VIA   -    M      A18X+109157Y+156130X0260Y    R090 S2      
017MB_BMC_MON             -    MD0100PA00X+109157Y+156130                       
327MB_BMC_MON       U146  -1          A01X+109370Y+156693X0140Y0440     S1      
327MB_BMC_MON       R1803 -2          A01X+109338Y+155733X0198Y0197R090 S1      
327MB_BMC_MON       C4080 -2   M      A01X+056424Y+152511X0198Y0197R270 S1      
327MB_BMC_MON       R6298 -1          A01X+057218Y+152622X0198Y0197     S1      
317MB_BMC_MON       VIA   -    MD0100PA00X+056732Y+152815X0200Y         S0      
327m2372            R6035 -2          A01X+131390Y+046756X0198Y0197R180 S1      
327m2372            R4477 -2          A01X+130542Y+047438X0198Y0197     S1      
317m2372            VIA   -    M      A01X+130782Y+047438X0200Y         S2      
017m2372            VIA   -    M      A18X+130782Y+047438X0260Y         S2      
017m2372                  -    MD0100PA00X+130782Y+047438                       
317m2372            VIA   -    MD0100PA00X+146454Y+043311X0200Y         S0      
317m2372            VIA   -    MD0100PA00X+137360Y+086766X0180Y         S0      
327m2372            U6    -L19        A01X+137202Y+086609X0160Y         S1      
327P3V3_SSD2_OCP    PU59  -9          A01X+023284Y+022506X0110Y0240     S1      
317P3V3_SSD2_OCP    VIA   -    M      A01X+023206Y+023056X0200Y    R090 S2      
017P3V3_SSD2_OCP    VIA   -    M      A18X+023206Y+023056X0260Y    R090 S2      
017P3V3_SSD2_OCP          -    MD0100PA00X+023206Y+023056                       
327P3V3_SSD2_OCP    PR265 -1          A01X+023269Y+023296X0198Y0197R090 S1      
317m2373            VIA   -    MD0100PA00X+038509Y+129745X0200Y         S0      
327m2373            R1227 -1          A18X+039274Y+129928X0198Y0197R180 S2      
327m2373            PEX1  -AB5        A01X+061713Y+117618X0180Y         S1      
317m2373            VIA   -    MD0080PA00X+061526Y+117805X0160Y    R270 S0      
327SMB_PEX_LS_SDA   R1540 -2   M      A01X+083883Y+092975X0198Y0197R090 S1      
327SMB_PEX_LS_SDA   R6359 -2   M      A01X+084540Y+092975X0198Y0197R090 S1      
327SMB_PEX_LS_SDA   R6318 -1          A01X+084920Y+092978X0198Y0197R270 S1      
327SMB_PEX_LS_SDA   VIA   -    M      A18X+084169Y+094124X0260Y         S2      
317SMB_PEX_LS_SDA   VIA   -    MD0100PA00X+083624Y+093958X0200Y    R090 S0      
327SMB_PEX_LS_SDA   R1544 -2          A18X+083695Y+094272X0198Y0197R090 S2      
327SMB_PEX_LS_SDA   U123  -3   M      A01X+083624Y+093578X0170Y0460R180 S1      
327NIC0_CLK_EN_N    R3605 -2          A18X+138250Y+091792X0198Y0197R090 S2      
327NIC0_CLK_EN_N    VIA   -    M      A18X+138250Y+090750X0260Y         S2      
327NIC0_CLK_EN_N    U6    -D20        A01X+137517Y+088814X0160Y         S1      
317NIC0_CLK_EN_N    VIA   -    MD0100PA00X+137675Y+088971X0180Y         S0      
317SMB_FIO_R1_SDA   VIA   -    MD0100PA00X+084832Y+088842X0200Y         S0      
327SMB_FIO_R1_SDA   R1492 -2          A18X+085372Y+088771X0198Y0197     S2      
317SMB_FIO_R1_SDA   VIA   -    MD0100PA00X+134477Y+078135X0200Y    R180 S0      
317SMB_FIO_R1_SDA   VIA   -    MD0100PA00X+081365Y+074686X0200Y         S0      
327SMB_FIO_R1_SDA   R4233 -1          A01X+134237Y+078168X0198Y0197R180 S1      
327SMB_FIO_R1_SDA   R3762 -2          A01X+087974Y+026028X0198Y0197R090 S1      
317SMB_FIO_R1_SDA   VIA   -    M      A01X+088312Y+026269X0200Y         S2      
017SMB_FIO_R1_SDA   VIA   -    M      A18X+088312Y+026269X0260Y         S2      
017SMB_FIO_R1_SDA         -    MD0100PA00X+088312Y+026269                       
327m2374            VIA   -    M      A18X+019894Y+055104X0260Y         S2      
317m2374            VIA   -    MD0100PA00X+020050Y+057794X0200Y         S0      
327m2374            R3    -2          A18X+019396Y+054497X0198Y0197R180 S2      
327m2374            R24   -1   M      A18X+019781Y+054497X0198Y0197R180 S2      
317m2374            VIA   -    MD0100PA00X+020594Y+066893X0200Y         S0      
327m2374            U6    -G16        A01X+136257Y+087869X0160Y         S1      
317m2374            VIA   -    MD0100PA00X+136415Y+088026X0180Y         S0      
327m2375            R1226 -1          A18X+041474Y+128249X0198Y0197R270 S2      
317m2375            VIA   -    MD0080PA00X+015630Y+117618X0160Y    R270 S0      
327m2375            PEX0  -AB4        A01X+015630Y+117618X0180Y         S1      
327USB2_MB_BMC_DN   R6728 -1   M      A01X+039362Y+151645X0180Y0200R090 S1      
327USB2_MB_BMC_DN   R5445 -2   M      A01X+039362Y+151645X0180Y0200R090 S1      
327USB2_MB_BMC_DN   R6293 -1   M      A01X+039362Y+151645X0180Y0200     S1      
327USB2_MB_BMC_DN   VIA   -    M      A18X+037203Y+153403X0160Y0041R123 S2      
317USB2_MB_BMC_DN   J11   -L9   D0122PA00X+035240Y+156610X0282Y    R180 S3      
317USB2_MB_BMC_DN   VIA   -    MD0100PA00X+039727Y+151805X0200Y    R270 S0      
327NIC2_CLK_EN_N    R3624 -2          A01X+140792Y+088400X0198Y0197R180 S1      
317NIC2_CLK_EN_N    VIA   -    M      A01X+140200Y+088400X0200Y         S2      
017NIC2_CLK_EN_N    VIA   -    M      A18X+140200Y+088400X0260Y         S2      
017NIC2_CLK_EN_N          -    MD0100PA00X+140200Y+088400                       
317NIC2_CLK_EN_N    VIA   -    MD0100PA00X+137675Y+087711X0180Y         S0      
327NIC2_CLK_EN_N    U6    -H20        A01X+137517Y+087554X0160Y         S1      
317SMB_FIO_R1_SCL   VIA   -    MD0100PA00X+084927Y+089257X0200Y         S0      
327SMB_FIO_R1_SCL   R1490 -2          A18X+085372Y+089274X0198Y0197     S2      
327SMB_FIO_R1_SCL   R4232 -1          A01X+081699Y+074250X0198Y0197     S1      
327SMB_FIO_R1_SCL   R3761 -2          A01X+081382Y+073845X0198Y0197R090 S1      
317SMB_FIO_R1_SCL   VIA   -    M      A01X+081368Y+074098X0200Y         S2      
017SMB_FIO_R1_SCL   VIA   -    M      A18X+081368Y+074098X0260Y         S2      
017SMB_FIO_R1_SCL         -    MD0100PA00X+081368Y+074098                       
327SMB_PEX_LS_SCL   VIA   -           A18X+083368Y+093674X0260Y         S2      
317SMB_PEX_LS_SCL   VIA   -    MD0100PA00X+083368Y+093958X0200Y    R090 S0      
327SMB_PEX_LS_SCL   R1546 -2          A18X+083295Y+094272X0198Y0197R090 S2      
327SMB_PEX_LS_SCL   U123  -2   M      A01X+083368Y+093578X0170Y0460R180 S1      
327SMB_PEX_LS_SCL   R1539 -2   M      A01X+083483Y+092975X0198Y0197R090 S1      
327SMB_PEX_LS_SCL   R6358 -2   M      A01X+083091Y+092975X0198Y0197R090 S1      
327SMB_PEX_LS_SCL   R6319 -1          A01X+082699Y+092978X0198Y0197R270 S1      
327m2376            R1225 -1          A18X+041874Y+128249X0198Y0197R270 S2      
317m2376            VIA   -    MD0080PA00X+016004Y+117618X0160Y    R270 S0      
327m2376            PEX0  -AB5        A01X+016004Y+117618X0180Y         S1      
327SMB_FIO_R2_SDA   J2    -B12        A01X+090330Y+025748X0150Y0530R090 S1      
327SMB_FIO_R2_SDA   R3762 -1          A01X+087974Y+025713X0198Y0197R090 S1      
317SMB_FIO_R2_SDA   VIA   -    M      A01X+089700Y+025748X0200Y         S2      
017SMB_FIO_R2_SDA   VIA   -    M      A18X+089700Y+025748X0260Y         S2      
017SMB_FIO_R2_SDA         -    MD0100PA00X+089700Y+025748                       
327P3V3_SSD1_OCP    PU56  -9          A01X+013048Y+022506X0110Y0240     S1      
317P3V3_SSD1_OCP    VIA   -    M      A01X+012970Y+023056X0200Y    R090 S2      
017P3V3_SSD1_OCP    VIA   -    M      A18X+012970Y+023056X0260Y    R090 S2      
017P3V3_SSD1_OCP          -    MD0100PA00X+012970Y+023056                       
327P3V3_SSD1_OCP    PR261 -1          A01X+013033Y+023296X0198Y0197R090 S1      
317SMB_FIO_R2_SCL   VIA   -    MD0100PA00X+081390Y+073074X0200Y         S0      
327SMB_FIO_R2_SCL   R3761 -1          A01X+081382Y+073530X0198Y0197R090 S1      
327SMB_FIO_R2_SCL   J2    -B11        A01X+090330Y+025512X0150Y0530R090 S1      
317SMB_FIO_R2_SCL   VIA   -    M      A01X+088588Y+025512X0200Y         S2      
017SMB_FIO_R2_SCL   VIA   -    M      A18X+088588Y+025512X0260Y         S2      
017SMB_FIO_R2_SCL         -    MD0100PA00X+088588Y+025512                       
317m2377            VIA   -    M      A01X+140200Y+087600X0200Y         S2      
017m2377            VIA   -    M      A18X+140200Y+087600X0260Y         S2      
017m2377                  -    MD0100PA00X+140200Y+087600                       
327m2377            R3639 -1          A01X+140792Y+087600X0198Y0197     S1      
317m2377            VIA   -    MD0100PA00X+136730Y+087081X0180Y         S0      
327m2377            U6    -K17        A01X+136572Y+086924X0160Y         S1      
327m2378            R1106 -2          A01X+054990Y+071251X0198Y0197R180 S1      
327m2378            U114  -C12        A01X+053335Y+070630X0090Y         S1      
327m2379            R367  -2          A18X+164005Y+044661X0198Y0197     S2      
317m2379            VIA   -    MD0100PA00X+084950Y+076350X0200Y         S0      
327m2379            R6312 -1          A18X+083900Y+076292X0198Y0197R270 S2      
317m2379            VIA   -    M      A01X+163518Y+044660X0200Y         S2      
017m2379            VIA   -    M      A18X+163518Y+044660X0260Y         S2      
017m2379                  -    MD0100PA00X+163518Y+044660                       
317m2379            VIA   -    MD0100PA00X+084264Y+066281X0200Y         S0      
327m2379            J27   -A8         A01X+164156Y+044660X0140Y0480R090 S1      
327m2380            U6    -L20        A01X+137517Y+086609X0160Y         S1      
317m2380            VIA   -    MD0100PA00X+137675Y+086766X0180Y         S0      
317m2380            VIA   -    M      A01X+146147Y+065581X0200Y         S2      
017m2380            VIA   -    M      A18X+146147Y+065581X0260Y         S2      
017m2380                  -    MD0100PA00X+146147Y+065581                       
327m2380            R258  -2          A18X+119325Y+046324X0198Y0197     S2      
327m2380            R279  -1   M      A18X+119327Y+046737X0198Y0197R180 S2      
327m2381            R1109 -2          A01X+053928Y+072542X0198Y0197R270 S1      
327m2381            U114  -A11        A01X+053138Y+071024X0090Y         S1      
327SMB_PEX3_SCL     R6334 -1          A18X+084438Y+092049X0198Y0197R270 S2      
327SMB_PEX3_SCL     R1549 -2          A01X+084106Y+091902X0198Y0197R270 S1      
317SMB_PEX3_SCL     VIA   -    MD0100PA00X+177381Y+099082X0200Y         S0      
317SMB_PEX3_SCL     VIA   -    MD0100PA00X+174203Y+111625X0200Y         S0      
317SMB_PEX3_SCL     VIA   -    MD0100PA00X+107876Y+103152X0200Y         S0      
317SMB_PEX3_SCL     VIA   -    MD0100PA00X+084332Y+091661X0200Y    R090 S0      
317SMB_PEX3_SCL     VIA   -    M      A01X+102957Y+091772X0200Y         S2      
017SMB_PEX3_SCL     VIA   -    M      A18X+102957Y+091772X0260Y         S2      
017SMB_PEX3_SCL           -    MD0100PA00X+102957Y+091772                       
327SMB_PEX3_SCL     R6812 -2          A01X+170983Y+120326X0198Y0197R270 S1      
317m2382            VIA   -    MD0100PA00X+145576Y+068345X0200Y         S0      
317m2382            VIA   -    M      A01X+106693Y+064539X0200Y         S2      
017m2382            VIA   -    M      A18X+106693Y+064539X0260Y         S2      
017m2382                  -    MD0100PA00X+106693Y+064539                       
327m2382            R208  -2          A01X+106460Y+064197X0198Y0197R180 S1      
317m2382            VIA   -    MD0100PA00X+137360Y+087081X0180Y         S0      
327m2382            U6    -K19        A01X+137202Y+086924X0160Y         S1      
327m2383            U114  -A10        A01X+052941Y+071024X0090Y         S1      
327m2383            R1110 -2          A01X+053528Y+072542X0198Y0197R270 S1      
327m2384            R366  -2          A18X+164005Y+044261X0198Y0197     S2      
317m2384            VIA   -    MD0100PA00X+084950Y+075850X0200Y         S0      
327m2384            R6313 -1          A18X+083900Y+075908X0198Y0197R090 S2      
317m2384            VIA   -    MD0100PA00X+163517Y+044286X0200Y         S0      
327m2384            J27   -A7         A01X+164156Y+044423X0140Y0480R090 S1      
317m2384            VIA   -    M      A01X+084235Y+065924X0200Y         S2      
017m2384            VIA   -    M      A18X+084235Y+065924X0260Y         S2      
017m2384                  -    MD0100PA00X+084235Y+065924                       
327SMB_PEX3_SDA     R6811 -2          A01X+171372Y+120331X0198Y0197R270 S1      
327SMB_PEX3_SDA     R1550 -2          A01X+084091Y+091162X0198Y0197R090 S1      
317SMB_PEX3_SDA     VIA   -    MD0100PA00X+174453Y+111625X0200Y         S0      
317SMB_PEX3_SDA     VIA   -    MD0100PA00X+177448Y+099505X0200Y         S0      
317SMB_PEX3_SDA     VIA   -    MD0100PA00X+107611Y+102954X0200Y         S0      
317SMB_PEX3_SDA     VIA   -    MD0100PA00X+084127Y+091406X0200Y    R090 S0      
317SMB_PEX3_SDA     VIA   -    M      A01X+102235Y+091767X0200Y         S2      
017SMB_PEX3_SDA     VIA   -    M      A18X+102235Y+091767X0260Y         S2      
017SMB_PEX3_SDA           -    MD0100PA00X+102235Y+091767                       
327SMB_PEX3_SDA     R6332 -1          A18X+084038Y+092049X0198Y0197R270 S2      
327m2385            U6    -K20        A01X+137517Y+086924X0160Y         S1      
317m2385            VIA   -    MD0100PA00X+137675Y+087081X0180Y         S0      
317m2385            VIA   -    MD0100PA00X+111467Y+057794X0200Y         S0      
327m2385            VIA   -    M      A18X+111311Y+055104X0260Y         S2      
327m2385            R207  -2          A18X+110813Y+054497X0198Y0197R180 S2      
327m2385            R228  -1   M      A18X+111198Y+054497X0198Y0197R180 S2      
317m2385            VIA   -    MD0100PA00X+117193Y+073386X0200Y         S0      
327m2386            R1102 -2          A01X+054990Y+070051X0198Y0197R180 S1      
327m2386            U114  -G12        A01X+053335Y+069843X0090Y         S1      
327m2387            Q242  -2   M      A01X+160041Y+146336X0160Y0240R180 S1      
317m2387            J9    -I10  D0122PA00X+172949Y+158067X0282Y    R180 S3      
317m2387            VIA   -    M      A01X+161379Y+152333X0200Y         S2      
017m2387            VIA   -    M      A18X+161379Y+152333X0260Y         S2      
017m2387                  -    MD0100PA00X+161379Y+152333                       
327m2387            C4162 -2          A01X+161086Y+152339X0198Y0197R090 S1      
327m2387            R6693 -1   M      A01X+177434Y+144368X0198Y0197R270 S1      
327m2387            R6691 -2   M      A01X+177823Y+144368X0198Y0197R090 S1      
327m2387            R6694 -2          A01X+178706Y+143096X0198Y0197R180 S1      
327m2387            VIA   -    M      A01X+178209Y+143096X0300Y         S1      
317PRSNT_SWB_C_N    J11   -A7   D0122PA00X+033508Y+162240X0282Y    R180 S3      
317PRSNT_SWB_C_N    VIA   -    M      A01X+024081Y+151994X0200Y         S2      
017PRSNT_SWB_C_N    VIA   -    M      A18X+024081Y+151994X0260Y         S2      
017PRSNT_SWB_C_N          -    MD0100PA00X+024081Y+151994                       
327PRSNT_SWB_C_N    R1802 -1          A01X+023262Y+151044X0198Y0197R180 S1      
327SMB_PEX2_SCL     R6810 -2          A01X+124923Y+118935X0198Y0197R270 S1      
327SMB_PEX2_SCL     R6330 -1          A18X+083000Y+092000X0198Y0197R270 S2      
317SMB_PEX2_SCL     VIA   -    MD0100PA00X+085345Y+100705X0200Y         S0      
317SMB_PEX2_SCL     VIA   -    M      A01X+131576Y+103934X0200Y         S2      
017SMB_PEX2_SCL     VIA   -    M      A18X+131576Y+103934X0260Y         S2      
017SMB_PEX2_SCL           -    MD0100PA00X+131576Y+103934                       
327SMB_PEX2_SCL     R1547 -2          A01X+083141Y+091922X0198Y0197R270 S1      
317SMB_PEX2_SCL     VIA   -    MD0100PA00X+083106Y+091674X0200Y         S0      
327P3V3_SSD4        R887  -1          A01X+048929Y+023613X0198Y0197R270 S1      
317P3V3_SSD4        VIA   -    MD0100PA00X+048929Y+023871X0200Y    R090 S0      
327P3V3_SSD4        PU55  -1          A01X+047930Y+021324X0110Y0240     S1      
327P3V3_SSD4        PU55  -2          A01X+048126Y+021324X0110Y0240     S1      
327P3V3_SSD4        PU55  -3          A01X+048323Y+021324X0110Y0240     S1      
327P3V3_SSD4        PU55  -4          A01X+048520Y+021324X0110Y0240     S1      
327P3V3_SSD4        PU55  -5          A01X+048717Y+021324X0110Y0240     S1      
327P3V3_SSD4        PC502 -1          A01X+048176Y+020686X0198Y0197R180 S1      
327P3V3_SSD4        PC503 -1          A01X+048283Y+020064X0400Y0500     S1      
327P3V3_SSD4        PD61  -C          A01X+048762Y+018984X0670Y0990R090 S1      
317P3V3_SSD4        VIA   -    MD0100PA00X+048701Y+020681X0200Y    R180 S0      
317P3V3_SSD4        VIA   -    MD0100PA00X+048451Y+020681X0200Y    R180 S0      
317P3V3_SSD4        VIA   -    MD0100PA00X+048667Y+020175X0200Y    R090 S0      
317P3V3_SSD4        VIA   -    MD0100PA00X+048967Y+020205X0200Y    R090 S0      
317P3V3_SSD4        VIA   -    MD0100PA00X+048274Y+021051X0200Y    R180 S0      
317P3V3_SSD4        VIA   -    MD0100PA00X+048524Y+021051X0200Y    R180 S0      
317P3V3_SSD4        VIA   -    MD0100PA00X+049015Y+019518X0200Y    R180 S0      
317P3V3_SSD4        VIA   -    MD0100PA00X+048667Y+019925X0200Y    R090 S0      
317P3V3_SSD4        VIA   -    MD0100PA00X+048265Y+019518X0200Y    R180 S0      
317P3V3_SSD4        VIA   -    MD0100PA00X+048515Y+019518X0200Y    R180 S0      
317P3V3_SSD4        VIA   -    M      A01X+048967Y+019925X0200Y    R090 S2      
017P3V3_SSD4        VIA   -    M      A18X+048967Y+019925X0260Y    R090 S2      
017P3V3_SSD4              -    MD0100PA00X+048967Y+019925                       
317P3V3_SSD4        VIA   -    MD0100PA00X+048765Y+019518X0200Y    R180 S0      
327P3V3_SSD4        R6062 -1          A01X+042892Y+014754X0198Y0197     S1      
317P3V3_SSD4        VIA   -    MD0100PA00X+042615Y+014754X0200Y         S0      
327P3V3_SSD4        R5739 -1          A01X+054325Y+010824X0198Y0197R270 S1      
317P3V3_SSD4        VIA   -    MD0100PA00X+054068Y+010619X0200Y    R090 S0      
327P3V3_SSD4        R421  -1          A01X+053375Y+010135X0198Y0197R270 S1      
317P3V3_SSD4        VIA   -    MD0100PA00X+053375Y+010378X0200Y    R270 S0      
317P3V3_SSD4        VIA   -    M      A01X+047406Y+011659X0200Y         S2      
017P3V3_SSD4        VIA   -    M      A18X+047406Y+011659X0260Y         S2      
017P3V3_SSD4              -    MD0100PA00X+047406Y+011659                       
317P3V3_SSD4        VIA   -    MD0100PA00X+047406Y+011959X0200Y         S0      
327P3V3_SSD4        PU123 -6_7        A01X+046952Y+011762X0295Y0354R270 S1      
327P3V3_SSD4        PC921 -1   M      A01X+047832Y+011967X0400Y0500R090 S1      
327P3V3_SSD4        R5667 -2          A01X+047950Y+013484X0198Y0197     S1      
327P3V3_SSD4        C969  -2   M      A01X+052766Y+009855X0198Y0197R270 S1      
317P3V3_SSD4        VIA   -    MD0100PA00X+053020Y+009855X0200Y    R090 S0      
327P3V3_SSD4        J34   -B11        A01X+051718Y+009760X0150Y0500R090 S1      
327P3V3_SSD4        R422  -1          A01X+048611Y+009767X0198Y0197     S1      
317P3V3_SSD4        VIA   -    M      A01X+048368Y+009767X0200Y         S2      
017P3V3_SSD4        VIA   -    M      A18X+048368Y+009767X0260Y         S2      
017P3V3_SSD4              -    MD0100PA00X+048368Y+009767                       
327P3V3_SSD4        R1661 -1          A01X+055180Y+008058X0198Y0197R180 S1      
317P3V3_SSD4        VIA   -    MD0100PA00X+055421Y+008058X0200Y         S0      
327P3V3_SSD4        R1660 -1          A01X+055180Y+006858X0198Y0197R180 S1      
317P3V3_SSD4        VIA   -    MD0100PA00X+055420Y+006858X0200Y         S0      
327P3V3_SSD4        U130  -1          A01X+055772Y+006472X0240Y0460R180 S1      
327P3V3_SSD4        C2720 -2   M      A01X+055797Y+005801X0198Y0197R180 S1      
317P3V3_SSD4        VIA   -    MD0100PA00X+055797Y+005551X0200Y         S0      
317m2388            VIA   -    M      A01X+069199Y+075958X0200Y    R090 S2      
017m2388            VIA   -    M      A18X+069199Y+075958X0260Y    R090 S2      
017m2388                  -    MD0100PA00X+069199Y+075958                       
327m2388            U50   -8          A01X+068715Y+075958X0140Y0630R270 S1      
327m2388            R1036 -2          A18X+069694Y+075347X0198Y0197     S2      
327m2388            R1032 -1   M      A18X+069694Y+075697X0198Y0197R180 S2      
327m2389            R1103 -2          A01X+054990Y+070451X0198Y0197R180 S1      
327m2389            U114  -F12        A01X+053335Y+070040X0090Y         S1      
327SMB_NIC7_LS_EN   R1531 -1          A01X+086142Y+075600X0198Y0197     S1      
317SMB_NIC7_LS_EN   VIA   -    M      A01X+085900Y+075600X0200Y         S2      
017SMB_NIC7_LS_EN   VIA   -    M      A18X+085900Y+075600X0260Y         S2      
017SMB_NIC7_LS_EN         -    MD0100PA00X+085900Y+075600                       
327SMB_NIC7_LS_EN   U122  -5          A01X+085430Y+075816X0140Y0590R270 S1      
317SMB_PEX2_SDA     VIA   -    MD0100PA00X+085069Y+100692X0200Y         S0      
317SMB_PEX2_SDA     VIA   -    MD0100PA00X+131561Y+104282X0200Y         S0      
327SMB_PEX2_SDA     R1548 -2          A01X+083291Y+091162X0198Y0197R090 S1      
317SMB_PEX2_SDA     VIA   -    M      A01X+082985Y+091421X0200Y         S2      
017SMB_PEX2_SDA     VIA   -    M      A18X+082985Y+091421X0260Y         S2      
017SMB_PEX2_SDA           -    MD0100PA00X+082985Y+091421                       
327SMB_PEX2_SDA     R6328 -1          A18X+082592Y+092139X0198Y0197     S2      
327SMB_PEX2_SDA     R6809 -2          A01X+125548Y+119885X0198Y0197R270 S1      
327m2390            R1105 -2          A01X+054990Y+070851X0198Y0197R180 S1      
327m2390            U114  -D12        A01X+053335Y+070433X0090Y         S1      
317m2391            VIA   -    M      A01X+055148Y+100665X0200Y         S2      
017m2391            VIA   -    M      A18X+055148Y+100665X0260Y         S2      
017m2391                  -    MD0100PA00X+055148Y+100665                       
327m2391            R1327 -2          A01X+055470Y+101082X0198Y0197R270 S1      
327m2391            D2    -A          A01X+055148Y+100335X0240Y0280R180 S1      
327m2392            J26   -A8         A01X+157064Y+055892X0140Y0480R270 S1      
327m2392            R316  -1          A01X+158968Y+055880X0198Y0197     S1      
317m2392            VIA   -    MD0100PA00X+157593Y+055892X0200Y    R180 S0      
317m2392            VIA   -    MD0100PA00X+084950Y+078150X0200Y         S0      
327m2392            R6310 -1          A18X+083900Y+078092X0198Y0197R270 S2      
317m2392            VIA   -    MD0100PA00X+083964Y+066653X0200Y         S0      
317m2392            VIA   -    M      A01X+157708Y+063171X0200Y         S2      
017m2392            VIA   -    M      A18X+157708Y+063171X0260Y         S2      
017m2392                  -    MD0100PA00X+157708Y+063171                       
317m2393            J9    -G9   D0122PA00X+172083Y+159169X0282Y    R180 S3      
317m2393            VIA   -    M      A01X+160935Y+152733X0200Y         S2      
017m2393            VIA   -    M      A18X+160935Y+152733X0260Y         S2      
017m2393                  -    MD0100PA00X+160935Y+152733                       
327m2393            R1856 -1          A01X+160668Y+152733X0198Y0197R180 S1      
327SMB_PEX1_SCL     R6808 -2          A01X+079832Y+119503X0198Y0197R270 S1      
317SMB_PEX1_SCL     VIA   -    MD0100PA00X+082786Y+111625X0200Y         S0      
327SMB_PEX1_SCL     R6326 -1          A18X+081851Y+092003X0198Y0197     S2      
317SMB_PEX1_SCL     VIA   -    M      A01X+082534Y+091677X0200Y         S2      
017SMB_PEX1_SCL     VIA   -    M      A18X+082534Y+091677X0260Y         S2      
017SMB_PEX1_SCL           -    MD0100PA00X+082534Y+091677                       
327SMB_PEX1_SCL     R1543 -2          A01X+082741Y+091922X0198Y0197R270 S1      
317m2394            VIA   -    MD0100PA00X+073343Y+046737X0200Y         S0      
327m2394            R156  -2          A18X+073617Y+046324X0198Y0197     S2      
327m2394            R177  -1   M      A18X+073618Y+046737X0198Y0197R180 S2      
317m2394            VIA   -    MD0100PA00X+081550Y+082400X0200Y         S0      
317m2394            VIA   -    M      A01X+096784Y+086480X0200Y         S2      
017m2394            VIA   -    M      A18X+096784Y+086480X0260Y         S2      
017m2394                  -    MD0100PA00X+096784Y+086480                       
317m2394            VIA   -    MD0100PA00X+097004Y+084290X0200Y         S0      
317m2394            VIA   -    MD0100PA00X+136415Y+087711X0180Y         S0      
327m2394            U6    -H16        A01X+136257Y+087554X0160Y         S1      
317m2395            VIA   -    M      A01X+093413Y+035517X0200Y    R090 S2      
017m2395            VIA   -    M      A18X+093413Y+035517X0260Y    R090 S2      
017m2395                  -    MD0100PA00X+093413Y+035517                       
327m2395            U112  -8          A01X+093084Y+035735X0100Y0290R090 S1      
327m2395            R1019 -2          A01X+093860Y+035128X0198Y0197R180 S1      
317m2396            VIA   -    M      A01X+069236Y+076461X0200Y    R090 S2      
017m2396            VIA   -    M      A18X+069236Y+076461X0260Y    R090 S2      
017m2396                  -    MD0100PA00X+069236Y+076461                       
327m2396            U50   -7          A01X+068715Y+076214X0140Y0630R270 S1      
327m2396            R1035 -2          A18X+069694Y+076647X0198Y0197     S2      
327m2396            R1031 -1   M      A18X+069694Y+076297X0198Y0197R180 S2      
327m2397            R1108 -2          A01X+054990Y+072051X0198Y0197R180 S1      
327m2397            U114  -A12        A01X+053335Y+071024X0090Y         S1      
317m2398            VIA   -    M      A01X+054472Y+100752X0200Y         S2      
017m2398            VIA   -    M      A18X+054472Y+100752X0260Y         S2      
017m2398                  -    MD0100PA00X+054472Y+100752                       
327m2398            D2    -C          A01X+054774Y+100335X0240Y0280R180 S1      
327m2398            Q14   -3          A01X+054177Y+100926X0240Y0240R270 S1      
317SMB_PEX1_SDA     VIA   -    MD0100PA00X+083036Y+111625X0200Y         S0      
327SMB_PEX1_SDA     R6324 -1          A18X+081304Y+091570X0198Y0197     S2      
317SMB_PEX1_SDA     VIA   -    M      A01X+081788Y+091542X0200Y         S2      
017SMB_PEX1_SDA     VIA   -    M      A18X+081788Y+091542X0260Y         S2      
017SMB_PEX1_SDA           -    MD0100PA00X+081788Y+091542                       
327SMB_PEX1_SDA     R1545 -2          A01X+082891Y+091162X0198Y0197R090 S1      
327SMB_PEX1_SDA     R6807 -2          A01X+079923Y+120346X0198Y0197R270 S1      
327NIC5_CLK_EN_N    R3648 -2          A01X+140792Y+086800X0198Y0197R180 S1      
317NIC5_CLK_EN_N    VIA   -    MD0100PA00X+136730Y+086137X0180Y         S0      
327NIC5_CLK_EN_N    U6    -M17        A01X+136572Y+086294X0160Y         S1      
317NIC5_CLK_EN_N    VIA   -    M      A01X+140550Y+086800X0200Y         S2      
017NIC5_CLK_EN_N    VIA   -    M      A18X+140550Y+086800X0260Y         S2      
017NIC5_CLK_EN_N          -    MD0100PA00X+140550Y+086800                       
327m2399            R1107 -2          A01X+054990Y+071651X0198Y0197R180 S1      
327m2399            U114  -B12        A01X+053335Y+070827X0090Y         S1      
317m2400            VIA   -    M      A01X+054885Y+101831X0200Y         S2      
017m2400            VIA   -    M      A18X+054885Y+101831X0260Y         S2      
017m2400                  -    MD0100PA00X+054885Y+101831                       
327m2400            Q14   -6   M      A01X+054885Y+101517X0240Y0240R270 S1      
327m2400            Q14   -5          A01X+054885Y+101221X0160Y0240R270 S1      
327m2400            R1328 -1   M      A01X+054852Y+102118X0198Y0197     S1      
327m2400            R5800 -1          A01X+054814Y+102523X0198Y0197R090 S1      
317m2401            VIA   -    MD0100PA00X+084950Y+077650X0200Y         S0      
327m2401            R6311 -1          A18X+083900Y+077708X0198Y0197R090 S2      
317m2401            VIA   -    MD0100PA00X+157630Y+062760X0200Y         S0      
317m2401            VIA   -    M      A01X+083727Y+066391X0200Y         S2      
017m2401            VIA   -    M      A18X+083727Y+066391X0260Y         S2      
017m2401                  -    MD0100PA00X+083727Y+066391                       
327m2401            J26   -A7         A01X+157064Y+056128X0140Y0480R270 S1      
327m2401            R315  -1          A01X+158968Y+056280X0198Y0197     S1      
317m2401            VIA   -    MD0100PA00X+157593Y+056142X0200Y    R180 S0      
317m2402            VIA   -    MD0100PA00X+136415Y+087396X0180Y         S0      
327m2402            U6    -J16        A01X+136257Y+087239X0160Y         S1      
317m2402            VIA   -    MD0100PA00X+073151Y+038111X0200Y         S0      
317m2402            VIA   -    M      A01X+082158Y+072714X0200Y         S2      
017m2402            VIA   -    M      A18X+082158Y+072714X0260Y         S2      
017m2402                  -    MD0100PA00X+082158Y+072714                       
327m2402            R157  -2          A18X+073151Y+038450X0198Y0197     S2      
317m2403            VIA   -    M      A01X+069222Y+077345X0200Y    R090 S2      
017m2403            VIA   -    M      A18X+069222Y+077345X0260Y    R090 S2      
017m2403                  -    MD0100PA00X+069222Y+077345                       
327m2403            U50   -2          A01X+068715Y+077494X0140Y0630R270 S1      
327m2403            R1034 -2          A18X+069693Y+077116X0198Y0197     S2      
327m2403            R1030 -1   M      A18X+069693Y+077516X0198Y0197R180 S2      
317m2404            VIA   -    M      A01X+161379Y+153133X0200Y         S2      
017m2404            VIA   -    M      A18X+161379Y+153133X0260Y         S2      
017m2404                  -    MD0100PA00X+161379Y+153133                       
317m2404            J9    -D9   D0122PA00X+172083Y+160705X0282Y    R180 S3      
327m2404            C4160 -2   M      A01X+161261Y+152856X0198Y0197R180 S1      
327m2404            VIA   -    M      A01X+178694Y+146792X0300Y         S1      
327m2404            R6688 -2          A01X+178620Y+146270X0198Y0197     S1      
327m2404            Q243  -2   M      A01X+178306Y+147590X0160Y0240R270 S1      
327m2404            R6687 -1   M      A01X+177422Y+147588X0198Y0197R270 S1      
327m2404            R6685 -2   M      A01X+177810Y+147587X0198Y0197R090 S1      
317m2405            VIA   -    M      A01X+106364Y+063419X0200Y         S2      
017m2405            VIA   -    M      A18X+106364Y+063419X0260Y         S2      
017m2405                  -    MD0100PA00X+106364Y+063419                       
327m2405            R206  -2          A01X+106460Y+062760X0198Y0197R180 S1      
317m2405            VIA   -    MD0100PA00X+103320Y+073170X0200Y         S0      
327m2405            R227  -1   M      A01X+106460Y+063142X0198Y0197     S1      
317m2405            VIA   -    MD0100PA00X+137045Y+087081X0180Y         S0      
327m2405            U6    -K18        A01X+136887Y+086924X0160Y         S1      
327SMB_NIC6_LS_EN   R1524 -1          A01X+086142Y+077400X0198Y0197     S1      
317SMB_NIC6_LS_EN   VIA   -    M      A01X+085900Y+077400X0200Y         S2      
017SMB_NIC6_LS_EN   VIA   -    M      A18X+085900Y+077400X0260Y         S2      
017SMB_NIC6_LS_EN         -    MD0100PA00X+085900Y+077400                       
327SMB_NIC6_LS_EN   U121  -5          A01X+085430Y+077616X0140Y0590R270 S1      
317m2406            VIA   -    M      A01X+053195Y+038075X0200Y         S2      
017m2406            VIA   -    M      A18X+053195Y+038075X0260Y         S2      
017m2406                  -    MD0100PA00X+053195Y+038075                       
327m2406            R1559 -2          A01X+054561Y+038172X0198Y0197R180 S1      
327m2406            R1568 -1   M      A01X+053561Y+038172X0198Y0197     S1      
327m2406            U124  -21         A01X+052387Y+037713X0120Y0630R270 S1      
317m2407            J11   -H10  D0122PA00X+036106Y+158579X0282Y    R180 S3      
317m2407            VIA   -    M      A01X+024460Y+153170X0200Y         S2      
017m2407            VIA   -    M      A18X+024460Y+153170X0260Y         S2      
017m2407                  -    MD0100PA00X+024460Y+153170                       
327m2407            R1833 -1          A01X+023262Y+151858X0198Y0197R180 S1      
327m2408            VIA   -    M      A01X+090587Y+033600X0160Y0041R270 S1      
327m2408            R1010 -2          A01X+090461Y+034029X0198Y0197R270 S1      
327m2408            U110  -2          A01X+090681Y+031286X0060Y0280     S1      
317m2409            VIA   -    M      A01X+069216Y+077897X0200Y    R090 S2      
017m2409            VIA   -    M      A18X+069216Y+077897X0260Y    R090 S2      
017m2409                  -    MD0100PA00X+069216Y+077897                       
327m2409            U50   -1          A01X+068715Y+077750X0140Y0630R270 S1      
327m2409            R1033 -2          A18X+069693Y+078466X0198Y0197     S2      
327m2409            R1029 -1   M      A18X+069693Y+078066X0198Y0197R180 S2      
317m2410            VIA   -    MD0100PA00X+084950Y+079950X0200Y         S0      
327m2410            R6308 -1          A18X+083900Y+079892X0198Y0197R270 S2      
317m2410            VIA   -    MD0100PA00X+117918Y+044660X0200Y         S0      
317m2410            VIA   -    M      A01X+084844Y+065776X0200Y         S2      
017m2410            VIA   -    M      A18X+084844Y+065776X0260Y         S2      
017m2410                  -    MD0100PA00X+084844Y+065776                       
317m2410            VIA   -    MD0100PA00X+106150Y+061279X0200Y         S0      
317m2410            VIA   -    MD0100PA00X+112270Y+059102X0200Y         S0      
327m2410            J25   -A8         A01X+118448Y+044660X0140Y0480R090 S1      
327m2410            R265  -1          A18X+118296Y+044661X0198Y0197R180 S2      
317m2411            VIA   -    MD0100PA00X+178609Y+144372X0200Y         S0      
327m2411            Q244  -2          A01X+178318Y+144372X0160Y0240R270 S1      
317m2411            VIA   -    MD0100PA00X+159264Y+146071X0200Y         S0      
327m2411            R6680 -2   M      A01X+158775Y+146071X0198Y0197R090 S1      
327m2411            VIA   -    M      A01X+158775Y+146545X0300Y         S1      
317m2411            VIA   -    M      A01X+160935Y+153533X0200Y         S2      
017m2411            VIA   -    M      A18X+160935Y+153533X0260Y         S2      
017m2411                  -    MD0100PA00X+160935Y+153533                       
317m2411            J9    -A9   D0122PA00X+172083Y+162240X0282Y    R180 S3      
327m2411            C4159 -2          A01X+161231Y+153526X0198Y0197R180 S1      
327m2411            R6682 -1   M      A01X+160154Y+147197X0198Y0197     S1      
327m2411            R6681 -2   M      A01X+159929Y+146802X0198Y0197R180 S1      
317m2412            VIA   -    M      A01X+049520Y+038689X0200Y         S2      
017m2412            VIA   -    M      A18X+049520Y+038689X0260Y         S2      
017m2412                  -    MD0100PA00X+049520Y+038689                       
327m2412            R1558 -2          A01X+047848Y+038709X0198Y0197     S1      
327m2412            R1567 -1   M      A01X+048848Y+038709X0198Y0197R180 S1      
327m2412            U124  -2          A01X+050182Y+038225X0120Y0630R270 S1      
317m2413            VIA   -    MD0100PA00X+027442Y+038150X0200Y         S0      
317m2413            VIA   -    M      A01X+038188Y+074034X0200Y         S2      
017m2413            VIA   -    M      A18X+038188Y+074034X0260Y         S2      
017m2413                  -    MD0100PA00X+038188Y+074034                       
317m2413            VIA   -    MD0100PA00X+138305Y+088341X0180Y         S0      
327m2413            U6    -F22        A01X+138147Y+088184X0160Y         S1      
317m2413            VIA   -    MD0100PA00X+024427Y+069691X0200Y         S0      
327m2413            R55   -2          A18X+027442Y+038450X0198Y0197     S2      
327m2414            VIA   -    M      A01X+090695Y+032267X0160Y0041R270 S1      
327m2414            R1008 -2          A01X+090811Y+034029X0198Y0197R270 S1      
327m2414            U110  -1          A01X+090838Y+031286X0060Y0280     S1      
327m2415            R6309 -1          A18X+083900Y+079508X0198Y0197R090 S2      
317m2415            VIA   -    MD0100PA00X+084950Y+079450X0200Y         S0      
317m2415            VIA   -    MD0100PA00X+117808Y+044286X0200Y         S0      
317m2415            VIA   -    M      A01X+085398Y+065751X0200Y         S2      
017m2415            VIA   -    M      A18X+085398Y+065751X0260Y         S2      
017m2415                  -    MD0100PA00X+085398Y+065751                       
317m2415            VIA   -    MD0100PA00X+106134Y+061027X0200Y         S0      
317m2415            VIA   -    MD0100PA00X+112270Y+058852X0200Y         S0      
327m2415            J25   -A7         A01X+118448Y+044423X0140Y0480R090 S1      
327m2415            R264  -1          A18X+118296Y+044261X0198Y0197R180 S2      
317m2416            VIA   -    M      A01X+087620Y+008601X0200Y    R180 S2      
017m2416            VIA   -    M      A18X+087620Y+008601X0260Y    R180 S2      
017m2416                  -    MD0100PA00X+087620Y+008601                       
327m2416            R1676 -1          A01X+087620Y+008882X0198Y0197R090 S1      
327m2416            U133  -5          A01X+087307Y+008185X0240Y0460R180 S1      
327GPU_BB_RSVD_1    VIA   -    M      A01X+161152Y+154031X0300Y         S1      
327GPU_BB_RSVD_1    C4158 -2          A01X+161621Y+153936X0198Y0197R180 S1      
327GPU_BB_RSVD_1    R1853 -2          A01X+160668Y+153933X0198Y0197     S1      
317m2417            VIA   -    M      A01X+027758Y+039508X0200Y         S2      
017m2417            VIA   -    M      A18X+027758Y+039508X0260Y         S2      
017m2417                  -    MD0100PA00X+027758Y+039508                       
327m2417            R53   -2          A18X+028092Y+038800X0198Y0197     S2      
327m2417            R74   -1   M      A18X+027758Y+038800X0198Y0197     S2      
317m2417            VIA   -    MD0100PA00X+138305Y+088026X0180Y         S0      
327m2417            U6    -G22        A01X+138147Y+087869X0160Y         S1      
317m2417            VIA   -    MD0100PA00X+025463Y+069824X0200Y         S0      
317m2418            VIA   -    M      A01X+049129Y+039159X0200Y         S2      
017m2418            VIA   -    M      A18X+049129Y+039159X0260Y         S2      
017m2418                  -    MD0100PA00X+049129Y+039159                       
327m2418            U124  -1          A01X+050182Y+038480X0120Y0630R270 S1      
327m2418            R1557 -2          A01X+047848Y+039159X0198Y0197     S1      
327m2418            R1566 -1   M      A01X+048848Y+039159X0198Y0197R180 S1      
317m2419            VIA   -    MD0100PA00X+086834Y+009435X0200Y         S0      
327m2419            R1686 -2          A01X+086834Y+009195X0198Y0197R090 S1      
317m2419            VIA   -    M      A01X+086766Y+006051X0200Y         S2      
017m2419            VIA   -    M      A18X+086766Y+006051X0260Y         S2      
017m2419                  -    MD0100PA00X+086766Y+006051                       
327m2419            U133  -2   M      A01X+086766Y+006472X0170Y0460R180 S1      
327m2419            R1680 -2   M      A01X+085893Y+007259X0198Y0197     S1      
327m2419            R1677 -2          A01X+085573Y+006858X0198Y0197R180 S1      
317m2420            J11   -B10  D0122PA01X+036106Y+161650X0282Y    R180 S3      
317m2420            J3    -B10  D0122PA01X+018784Y+161650X0282Y    R180 S3      
317m2421            VIA   -    MD0100PA00X+136730Y+087396X0180Y         S0      
327m2421            U6    -J17        A01X+136572Y+087239X0160Y         S1      
317m2421            VIA   -    M      A01X+073466Y+039363X0200Y         S2      
017m2421            VIA   -    M      A18X+073466Y+039363X0260Y         S2      
017m2421                  -    MD0100PA00X+073466Y+039363                       
327m2421            R155  -2          A18X+073801Y+038800X0198Y0197     S2      
327m2421            R176  -1   M      A18X+073466Y+038800X0198Y0197     S2      
317m2421            VIA   -    MD0100PA00X+081831Y+072414X0200Y         S0      
327m2422            R1010 -1          A01X+090461Y+034344X0198Y0197R270 S1      
327m2422            U112  -1          A01X+091544Y+035376X0100Y0290R180 S1      
327SMB_NIC5_LS_EN   R1517 -1          A01X+086142Y+079200X0198Y0197     S1      
317SMB_NIC5_LS_EN   VIA   -    M      A01X+085900Y+079200X0200Y         S2      
017SMB_NIC5_LS_EN   VIA   -    M      A18X+085900Y+079200X0260Y         S2      
017SMB_NIC5_LS_EN         -    MD0100PA00X+085900Y+079200                       
327SMB_NIC5_LS_EN   U120  -5          A01X+085430Y+079416X0140Y0590R270 S1      
317m2423            VIA   -    M      A01X+087229Y+009428X0200Y         S2      
017m2423            VIA   -    M      A18X+087229Y+009428X0260Y         S2      
017m2423                  -    MD0100PA00X+087229Y+009428                       
327m2423            R1684 -2          A01X+087229Y+009188X0198Y0197R090 S1      
317m2423            VIA   -    MD0100PA00X+087052Y+006044X0200Y         S0      
327m2423            U133  -3   M      A01X+087022Y+006472X0170Y0460R180 S1      
327m2423            R1682 -2   M      A01X+085893Y+007659X0198Y0197     S1      
327m2423            R1678 -2          A01X+085573Y+008058X0198Y0197R180 S1      
327m2424            R1008 -1          A01X+090811Y+034344X0198Y0197R270 S1      
327m2424            U112  -2          A01X+091741Y+035376X0100Y0290R180 S1      
327P3V3_SSD4_SS     PU55  -7          A01X+048914Y+022506X0110Y0240     S1      
317P3V3_SSD4_SS     VIA   -    M      A01X+049327Y+023012X0200Y    R090 S2      
017P3V3_SSD4_SS     VIA   -    M      A18X+049327Y+023012X0260Y    R090 S2      
017P3V3_SSD4_SS           -    MD0100PA00X+049327Y+023012                       
327P3V3_SSD4_SS     PC507 -1          A01X+049329Y+023298X0198Y0197R090 S1      
327m2425            R1101 -2          A01X+054990Y+069651X0198Y0197R180 S1      
327m2425            U114  -H12        A01X+053335Y+069646X0090Y         S1      
317m2426            J14   -G9   D0122PA00X+154760Y+159169X0282Y    R180 S3      
317m2426            VIA   -    M      A01X+159075Y+152338X0200Y         S2      
017m2426            VIA   -    M      A18X+159075Y+152338X0260Y         S2      
017m2426                  -    MD0100PA00X+159075Y+152338                       
327m2426            R1856 -2          A01X+160353Y+152733X0198Y0197R180 S1      
327m2426            C4175 -2   M      A01X+159814Y+152731X0198Y0197R270 S1      
317m2427            VIA   -    M      A01X+077384Y+008601X0200Y    R180 S2      
017m2427            VIA   -    M      A18X+077384Y+008601X0260Y    R180 S2      
017m2427                  -    MD0100PA00X+077384Y+008601                       
327m2427            R1673 -1          A01X+077384Y+008882X0198Y0197R090 S1      
327m2427            U132  -5          A01X+077071Y+008185X0240Y0460R180 S1      
327m2428            R1780 -2          A18X+127071Y+032726X0198Y0197R180 S2      
317m2428            VIA   -    MD0100PA00X+130300Y+032669X0200Y         S0      
317m2428            VIA   -    MD0100PA00X+154474Y+030516X0200Y         S0      
317m2428            VIA   -    M      A01X+155118Y+034728X0200Y         S2      
017m2428            VIA   -    M      A18X+155118Y+034728X0260Y         S2      
017m2428                  -    MD0100PA00X+155118Y+034728                       
327m2428            U142  -20         A01X+152850Y+034168X0120Y0630R270 S1      
317m2429            VIA   -    MD0100PA00X+095582Y+047342X0200Y         S0      
327m2429            R6034 -2   M      A01X+095582Y+047049X0198Y0197R090 S1      
317m2429            VIA   -    MD0100PA00X+094982Y+049198X0200Y    R180 S0      
317m2429            VIA   -    M      A01X+138391Y+051659X0200Y         S2      
017m2429            VIA   -    M      A18X+138391Y+051659X0260Y         S2      
017m2429                  -    MD0100PA00X+138391Y+051659                       
317m2429            VIA   -    MD0100PA00X+112662Y+050626X0200Y         S0      
327m2429            R4475 -2          A01X+095240Y+049198X0198Y0197R180 S1      
317m2429            VIA   -    MD0100PA00X+137675Y+087396X0180Y         S0      
327m2429            U6    -J20        A01X+137517Y+087239X0160Y         S1      
327m2430            R1100 -2          A01X+054990Y+069251X0198Y0197R180 S1      
327m2430            U114  -J12        A01X+053335Y+069449X0090Y         S1      
317m2431            VIA   -    MD0100PA00X+076816Y+006044X0200Y         S0      
327m2431            U132  -3   M      A01X+076786Y+006472X0170Y0460R180 S1      
327m2431            R1675 -2          A01X+075337Y+008058X0198Y0197R180 S1      
327m2431            R1681 -2   M      A01X+075657Y+007659X0198Y0197     S1      
317m2431            VIA   -    M      A01X+076993Y+009428X0200Y         S2      
017m2431            VIA   -    M      A18X+076993Y+009428X0260Y         S2      
017m2431                  -    MD0100PA00X+076993Y+009428                       
327m2431            R1683 -2          A01X+076993Y+009188X0198Y0197R090 S1      
327m2432            J41   -A8         A01X+126325Y+009051X0150Y0500R090 S1      
317m2432            VIA   -    M      A01X+126750Y+009065X0200Y         S2      
017m2432            VIA   -    M      A18X+126750Y+009065X0260Y         S2      
017m2432                  -    MD0100PA00X+126750Y+009065                       
327m2432            R1710 -1          A01X+131886Y+004305X0198Y0197R270 S1      
317m2432            VIA   -    MD0100PA00X+131886Y+004545X0200Y    R270 S0      
317m2433            VIA   -    M      A01X+154495Y+034336X0200Y         S2      
017m2433            VIA   -    M      A18X+154495Y+034336X0260Y         S2      
017m2433                  -    MD0100PA00X+154495Y+034336                       
327m2433            U142  -19         A01X+152850Y+033912X0120Y0630R270 S1      
327m2433            R1778 -2          A01X+154830Y+034336X0198Y0197R180 S1      
317m2434            VIA   -    MD0100PA00X+043053Y+128920X0200Y         S0      
327m2434            VIA   -    M      A18X+043264Y+129683X0260Y         S2      
327m2434            U118  -7          A18X+042791Y+130040X0100Y0220R090 S2      
317m2434            VIA   -    MD0100PA00X+052220Y+067761X0200Y         S0      
327m2434            R1476 -1          A18X+052530Y+067112X0198Y0197     S2      
327m2435            U6    -G18        A01X+136887Y+087869X0160Y         S1      
317m2435            VIA   -    MD0100PA00X+137045Y+088026X0180Y         S0      
317m2435            VIA   -    MD0100PA00X+069248Y+073064X0200Y         S0      
327m2435            VIA   -    M      A18X+065603Y+055104X0260Y         S2      
317m2435            VIA   -    MD0100PA00X+065758Y+057794X0200Y         S0      
327m2435            R105  -2          A18X+065105Y+054497X0198Y0197R180 S2      
327m2435            R126  -1   M      A18X+065490Y+054497X0198Y0197R180 S2      
317m2436            VIA   -    M      A01X+076530Y+006051X0200Y         S2      
017m2436            VIA   -    M      A18X+076530Y+006051X0260Y         S2      
017m2436                  -    MD0100PA00X+076530Y+006051                       
327m2436            R1679 -2   M      A01X+075657Y+007256X0198Y0197     S1      
327m2436            R1674 -2          A01X+075337Y+006858X0198Y0197R180 S1      
327m2436            U132  -2   M      A01X+076530Y+006472X0170Y0460R180 S1      
317m2436            VIA   -    MD0100PA00X+076598Y+009435X0200Y         S0      
327m2436            R1685 -2          A01X+076598Y+009195X0198Y0197R090 S1      
327m2437            J42   -A7         A01X+141325Y+008815X0150Y0500R090 S1      
317m2437            VIA   -    M      A01X+142281Y+009062X0200Y         S2      
017m2437            VIA   -    M      A18X+142281Y+009062X0260Y         S2      
017m2437                  -    MD0100PA00X+142281Y+009062                       
327m2437            R1721 -1          A01X+146287Y+007259X0198Y0197     S1      
317m2437            VIA   -    MD0100PA00X+146047Y+007262X0200Y         S0      
327m2438            R1780 -1          A18X+126756Y+032726X0198Y0197R180 S2      
317m2438            VIA   -    MD0100PA00X+126250Y+033066X0200Y         S0      
327m2438            U420  -7          A01X+126829Y+033066X0170Y0460R270 S1      
327m2438            R6264 -1          A18X+127642Y+033050X0198Y0197R180 S2      
317m2438            VIA   -    M      A01X+119580Y+032400X0200Y         S2      
017m2438            VIA   -    M      A18X+119580Y+032400X0260Y         S2      
017m2438                  -    MD0100PA00X+119580Y+032400                       
327m2438            R487  -1          A01X+119204Y+032940X0198Y0197R180 S1      
327m2438            R1764 -2   M      A18X+126380Y+032726X0198Y0197R180 S2      
327m2439            VIA   -    M      A18X+043764Y+129683X0260Y         S2      
327m2439            U118  -6          A18X+042791Y+130236X0100Y0220R090 S2      
327m2439            R1475 -1          A18X+043791Y+129235X0198Y0197R090 S2      
327m2440            VIA   -    M      A01X+061056Y+064826X0300Y         S1      
317m2440            VIA   -    MD0100PA00X+138305Y+087711X0180Y         S0      
327m2440            U6    -H22        A01X+138147Y+087554X0160Y         S1      
317m2440            VIA   -    MD0100PA00X+072098Y+071166X0200Y         S0      
327m2440            R106  -2          A01X+060751Y+064197X0198Y0197R180 S1      
327m2441            R1099 -2          A01X+054990Y+068851X0198Y0197R180 S1      
327m2441            U114  -K12        A01X+053335Y+069252X0090Y         S1      
327m2442            J45   -A7         A01X+172033Y+008815X0150Y0500R090 S1      
317m2442            VIA   -    M      A01X+172990Y+009062X0200Y         S2      
017m2442            VIA   -    M      A18X+172990Y+009062X0260Y         S2      
017m2442                  -    MD0100PA00X+172990Y+009062                       
327m2442            R1736 -1          A01X+176995Y+007259X0198Y0197     S1      
317m2442            VIA   -    MD0100PA00X+176755Y+007262X0200Y         S0      
317m2443            VIA   -    MD0100PA00X+126422Y+033322X0200Y         S0      
317m2443            VIA   -    M      A01X+155093Y+030516X0200Y         S2      
017m2443            VIA   -    M      A18X+155093Y+030516X0260Y         S2      
017m2443                  -    MD0100PA00X+155093Y+030516                       
317m2443            VIA   -    MD0100PA00X+155386Y+034487X0200Y         S0      
327m2443            R1763 -2          A01X+155830Y+034336X0198Y0197R180 S1      
327m2443            R1778 -1          A01X+155145Y+034336X0198Y0197R180 S1      
317m2443            VIA   -    MD0100PA00X+130300Y+033100X0200Y         S0      
327m2443            U420  -6          A01X+126829Y+033322X0170Y0460R270 S1      
327m2443            R6263 -1          A18X+127642Y+033450X0198Y0197R180 S2      
317m2443            VIA   -    MD0100PA00X+119013Y+032414X0200Y         S0      
327m2443            R488  -1          A01X+118716Y+032414X0198Y0197R180 S1      
317NIC4_CLK_EN_N    VIA   -    MD0100PA00X+136415Y+087081X0180Y         S0      
327NIC4_CLK_EN_N    U6    -K16        A01X+136257Y+086924X0160Y         S1      
327NIC4_CLK_EN_N    R3640 -2          A01X+140792Y+090000X0198Y0197R180 S1      
317NIC4_CLK_EN_N    VIA   -    M      A01X+140200Y+090000X0200Y         S2      
017NIC4_CLK_EN_N    VIA   -    M      A18X+140200Y+090000X0260Y         S2      
017NIC4_CLK_EN_N          -    MD0100PA00X+140200Y+090000                       
327P3V3_SSD7_SS     PU61  -7          A01X+079622Y+022506X0110Y0240     S1      
317P3V3_SSD7_SS     VIA   -    M      A01X+080036Y+023012X0200Y    R090 S2      
017P3V3_SSD7_SS     VIA   -    M      A18X+080036Y+023012X0260Y    R090 S2      
017P3V3_SSD7_SS           -    MD0100PA00X+080036Y+023012                       
327P3V3_SSD7_SS     PC542 -1          A01X+080037Y+023298X0198Y0197R090 S1      
327m2444            R1776 -2          A01X+141414Y+098840X0198Y0197     S1      
317m2444            VIA   -    MD0100PA00X+141414Y+098549X0200Y         S0      
317m2444            VIA   -    M      A01X+164756Y+098143X0200Y         S2      
017m2444            VIA   -    M      A18X+164756Y+098143X0260Y         S2      
017m2444                  -    MD0100PA00X+164756Y+098143                       
327m2444            U142  -18         A01X+152850Y+033656X0120Y0630R270 S1      
317m2445            VIA   -    MD0100PA00X+049673Y+047042X0200Y         S0      
317m2445            VIA   -    M      A01X+049274Y+049198X0200Y    R180 S2      
017m2445            VIA   -    M      A18X+049274Y+049198X0260Y    R180 S2      
017m2445                  -    MD0100PA00X+049274Y+049198                       
317m2445            VIA   -    MD0100PA00X+052329Y+093920X0200Y         S0      
327m2445            U6    -G19        A01X+137202Y+087869X0160Y         S1      
317m2445            VIA   -    MD0100PA00X+137360Y+088026X0180Y         S0      
327m2445            R4478 -2          A01X+049532Y+049198X0198Y0197R180 S1      
327m2445            R5958 -2          A01X+049673Y+046749X0198Y0197R090 S1      
327m2446            U112  -6          A01X+092528Y+035376X0100Y0290R180 S1      
317m2446            VIA   -    MD0100PA01X+092456Y+034404X0200Y         S0      
317m2446            VIA   -    MD0100PA01X+094100Y+033531X0200Y         S0      
327m2446            R1017 -1   M      A01X+093829Y+033367X0180Y0200R270 S1      
327m2446            R6624 -2          A01X+093829Y+033367X0180Y0200R270 S1      
327m2447            R1098 -2          A01X+054990Y+068451X0198Y0197R180 S1      
327m2447            U114  -L12        A01X+053335Y+069055X0090Y         S1      
317m2448            VIA   -    M      A01X+067148Y+008601X0200Y    R180 S2      
017m2448            VIA   -    M      A18X+067148Y+008601X0260Y    R180 S2      
017m2448                  -    MD0100PA00X+067148Y+008601                       
327m2448            U131  -5          A01X+066835Y+008185X0240Y0460R180 S1      
327m2448            R1662 -1          A01X+067148Y+008882X0198Y0197R090 S1      
317m2449            VIA   -    M      A01X+154585Y+033436X0200Y         S2      
017m2449            VIA   -    M      A18X+154585Y+033436X0260Y         S2      
017m2449                  -    MD0100PA00X+154585Y+033436                       
327m2449            U142  -17         A01X+152850Y+033400X0120Y0630R270 S1      
327m2449            R1774 -2          A01X+154830Y+033436X0198Y0197R180 S1      
317m2450            VIA   -           A01X+160073Y+153933X0200Y         S2      
017m2450            VIA   -           A18X+160073Y+153933X0260Y         S2      
017m2450                  -     D0100PA00X+160073Y+153933                       
327m2450            R1853 -1          A01X+160353Y+153933X0198Y0197     S1      
327P3V3_SSD5_SS     PU57  -7          A01X+059150Y+022506X0110Y0240     S1      
317P3V3_SSD5_SS     VIA   -    M      A01X+059563Y+023012X0200Y    R090 S2      
017P3V3_SSD5_SS     VIA   -    M      A18X+059563Y+023012X0260Y    R090 S2      
017P3V3_SSD5_SS           -    MD0100PA00X+059563Y+023012                       
327P3V3_SSD5_SS     PC519 -1          A01X+059565Y+023298X0198Y0197R090 S1      
327m2451            U112  -7          A01X+092725Y+035376X0100Y0290R180 S1      
317m2451            VIA   -    MD0100PA01X+092796Y+034404X0200Y         S0      
317m2451            VIA   -    MD0100PA01X+094100Y+033191X0200Y         S0      
327m2451            R1015 -1   M      A01X+094379Y+033367X0180Y0200R270 S1      
327m2451            R6623 -2          A01X+094379Y+033367X0180Y0200R270 S1      
317m2452            VIA   -    M      A01X+066757Y+009428X0200Y         S2      
017m2452            VIA   -    M      A18X+066757Y+009428X0260Y         S2      
017m2452                  -    MD0100PA00X+066757Y+009428                       
327m2452            R1670 -2          A01X+066757Y+009188X0198Y0197R090 S1      
317m2452            VIA   -    MD0100PA00X+066580Y+006044X0200Y         S0      
327m2452            R1668 -2   M      A01X+065420Y+007659X0198Y0197     S1      
327m2452            R1664 -2          A01X+065101Y+008058X0198Y0197R180 S1      
327m2452            U131  -3   M      A01X+066550Y+006472X0170Y0460R180 S1      
327m2453            J40   -A8         A01X+116088Y+009051X0150Y0500R090 S1      
317m2453            VIA   -    M      A01X+116514Y+009065X0200Y         S2      
017m2453            VIA   -    M      A18X+116514Y+009065X0260Y         S2      
017m2453                  -    MD0100PA00X+116514Y+009065                       
327m2453            R1709 -1          A01X+121050Y+007659X0198Y0197     S1      
317m2453            VIA   -    MD0100PA00X+120810Y+007659X0200Y         S0      
327m2454            PR69  -2          A01X+050502Y+098924X0198Y0197R180 S1      
327m2454            R828  -1          A01X+049209Y+099219X0198Y0197R090 S1      
327m2454            R836  -1          A01X+140626Y+099219X0198Y0197R090 S1      
327m2454            VIA   -    M      A18X+140509Y+098190X0260Y         S2      
327m2454            R6716 -2          A18X+141189Y+099286X0198Y0197R180 S2      
327m2454            R6245 -1          A01X+051065Y+097388X0198Y0197     S1      
317m2454            VIA   -    MD0100PA00X+120001Y+101116X0200Y         S0      
317m2454            VIA   -    MD0100PA00X+050393Y+098139X0200Y         S0      
317m2454            VIA   -    MD0100PA00X+049309Y+098955X0200Y         S0      
317m2454            VIA   -    MD0100PA00X+052788Y+095219X0200Y         S0      
317m2454            VIA   -    MD0100PA00X+140726Y+098946X0200Y         S0      
327m2454            R1776 -1          A01X+141099Y+098840X0198Y0197     S1      
327m2454            R1762 -2   M      A01X+141099Y+099231X0198Y0197R180 S1      
317m2455            VIA   -    MD0100PA00X+072366Y+070586X0200Y         S0      
327m2455            R104  -2          A01X+060751Y+062760X0198Y0197R180 S1      
327m2455            R125  -1   M      A01X+060751Y+063142X0198Y0197     S1      
317m2455            VIA   -    M      A01X+098660Y+071764X0200Y         S2      
017m2455            VIA   -    M      A18X+098660Y+071764X0260Y         S2      
017m2455                  -    MD0100PA00X+098660Y+071764                       
327m2455            U6    -H21        A01X+137832Y+087554X0160Y         S1      
317m2455            VIA   -    MD0100PA00X+137990Y+087711X0180Y         S0      
327m2456            VIA   -    M      A18X+146083Y+076328X0160Y0041R090 S2      
327m2456            U70   -8          A01X+151321Y+091668X0110Y0540     S1      
317m2456            VIA   -    MD0100PA00X+091963Y+033633X0200Y         S0      
327m2456            R1011 -2          A01X+092075Y+032960X0180Y0200R270 S1      
327m2456            R6288 -1   M      A01X+092075Y+032960X0180Y0200R180 S1      
317m2456            VIA   -    MD0100PA00X+151393Y+090895X0200Y         S0      
327m2457            R1097 -2          A01X+053796Y+067323X0198Y0197R090 S1      
327m2457            U114  -M12        A01X+053335Y+068858X0090Y         S1      
317m2458            VIA   -    MD0100PA00X+066362Y+009435X0200Y         S0      
327m2458            R1672 -2          A01X+066362Y+009195X0198Y0197R090 S1      
317m2458            VIA   -    M      A01X+066294Y+006051X0200Y         S2      
017m2458            VIA   -    M      A18X+066294Y+006051X0260Y         S2      
017m2458                  -    MD0100PA00X+066294Y+006051                       
327m2458            U131  -2   M      A01X+066294Y+006472X0170Y0460R180 S1      
327m2458            R1666 -2   M      A01X+065420Y+007259X0198Y0197     S1      
327m2458            R1663 -2          A01X+065101Y+006858X0198Y0197R180 S1      
327m2459            PR73  -2          A01X+050108Y+098961X0198Y0197R270 S1      
327m2459            R829  -1          A01X+048809Y+099219X0198Y0197R090 S1      
327m2459            R837  -1          A01X+140226Y+099219X0198Y0197R090 S1      
327m2459            R6715 -2   M      A18X+139759Y+098404X0198Y0197R180 S2      
327m2459            R6246 -1          A01X+051070Y+096993X0198Y0197     S1      
317m2459            VIA   -    MD0100PA00X+050670Y+097895X0200Y         S0      
317m2459            VIA   -    MD0100PA00X+048709Y+098955X0200Y         S0      
317m2459            VIA   -    MD0100PA00X+052135Y+095227X0200Y         S0      
317m2459            VIA   -    MD0100PA00X+120342Y+101116X0200Y         S0      
317m2459            VIA   -    MD0100PA00X+165144Y+098152X0200Y         S0      
317m2459            VIA   -    MD0100PA00X+140126Y+098946X0200Y         S0      
317m2459            VIA   -           A01X+155360Y+033660X0200Y         S2      
017m2459            VIA   -           A18X+155360Y+033660X0260Y         S2      
017m2459                  -     D0100PA00X+155360Y+033660                       
327m2459            R1774 -1          A01X+155145Y+033436X0198Y0197R180 S1      
327m2459            R1760 -2   M      A01X+155830Y+033436X0198Y0197R180 S1      
327SMB_GPU_1_SCL    VIA   -    M      A18X+038947Y+149752X0260Y         S2      
327SMB_GPU_1_SCL    R1835 -2          A18X+039540Y+149784X0198Y0197     S2      
317SMB_GPU_1_SCL    J11   -Q10  D0122PA00X+036106Y+149878X0282Y    R180 S3      
317m2460            J13   -A7   D0122PA00X+135705Y+162240X0282Y    R180 S3      
317m2460            VIA   -    M      A01X+126289Y+152733X0200Y         S2      
017m2460            VIA   -    M      A18X+126289Y+152733X0260Y         S2      
017m2460                  -    MD0100PA00X+126289Y+152733                       
327m2460            R1852 -1          A01X+126022Y+152733X0198Y0197R180 S1      
317m2461            VIA   -    M      A01X+140550Y+088800X0200Y         S2      
017m2461            VIA   -    M      A18X+140550Y+088800X0260Y         S2      
017m2461                  -    MD0100PA00X+140550Y+088800                       
327m2461            R3631 -1          A01X+140792Y+088800X0198Y0197     S1      
317m2461            VIA   -    MD0100PA00X+137045Y+087396X0180Y         S0      
327m2461            U6    -J18        A01X+136887Y+087239X0160Y         S1      
317m2462            VIA   -    MD0100PA01X+091788Y+032482X0200Y         S0      
327m2462            R6603 -2   M      A01X+092075Y+032645X0180Y0200R270 S1      
327m2462            R1011 -1          A01X+092075Y+032645X0180Y0200R270 S1      
327m2462            U112  -4          A01X+092134Y+035376X0100Y0290R180 S1      
317m2462            VIA   -    MD0100PA01X+091935Y+034415X0200Y         S0      
317m2463            VIA   -    M      A01X+154280Y+032986X0200Y         S2      
017m2463            VIA   -    M      A18X+154280Y+032986X0260Y         S2      
017m2463                  -    MD0100PA00X+154280Y+032986                       
327m2463            U142  -16         A01X+152850Y+033144X0120Y0630R270 S1      
327m2463            R1772 -2          A01X+154830Y+032986X0198Y0197R180 S1      
317m2464            J3    -E10  D0122PA01X+018784Y+160114X0282Y    R180 S3      
317m2464            J11   -E10  D0122PA01X+036106Y+160114X0282Y    R180 S3      
317m2465            VIA   -    MD0100PA00X+136730Y+087711X0180Y         S0      
327m2465            U6    -H17        A01X+136572Y+087554X0160Y         S1      
317m2465            VIA   -    M      A01X+085073Y+046938X0200Y         S2      
017m2465            VIA   -    M      A18X+085073Y+046938X0260Y         S2      
017m2465                  -    MD0100PA00X+085073Y+046938                       
327m2465            R5959 -2          A01X+086388Y+047930X0198Y0197R180 S1      
327m2465            R4480 -2          A01X+084833Y+046938X0198Y0197     S1      
317m2465            VIA   -    MD0100PA00X+082439Y+072625X0200Y         S0      
327m2466            U98   -7          A01X+054648Y+078933X0110Y0540     S1      
317m2466            VIA   -    MD0100PA01X+054577Y+078160X0200Y         S0      
317m2466            VIA   -    MD0100PA01X+093930Y+034636X0200Y         S0      
327m2466            R6285 -1          A01X+093829Y+033682X0180Y0200     S1      
327m2466            R1017 -2   M      A01X+093829Y+033682X0180Y0200R270 S1      
327m2467            R1096 -2          A01X+053396Y+067323X0198Y0197R090 S1      
327m2467            U114  -M11        A01X+053138Y+068858X0090Y         S1      
317m2468            VIA   -    M      A01X+154564Y+032536X0200Y         S2      
017m2468            VIA   -    M      A18X+154564Y+032536X0260Y         S2      
017m2468                  -    MD0100PA00X+154564Y+032536                       
327m2468            U142  -15         A01X+152850Y+032888X0120Y0630R270 S1      
327m2468            R1770 -2          A01X+154830Y+032536X0198Y0197R180 S1      
317m2469            J13   -A5   D0122PA00X+133972Y+162240X0282Y    R180 S3      
317m2469            VIA   -    M      A01X+126733Y+153133X0200Y         S2      
017m2469            VIA   -    M      A18X+126733Y+153133X0260Y         S2      
017m2469                  -    MD0100PA00X+126733Y+153133                       
327m2469            R1851 -1          A01X+126022Y+153133X0198Y0197R180 S1      
317m2470            VIA   -    M      A01X+110023Y+158800X0200Y         S2      
017m2470            VIA   -    M      A18X+110023Y+158800X0260Y         S2      
017m2470                  -    MD0100PA00X+110023Y+158800                       
327m2470            R1808 -2   M      A01X+110023Y+158558X0198Y0197R090 S1      
327m2470            R1806 -2          A01X+110423Y+158243X0198Y0197R270 S1      
317m2470            VIA   -    MD0100PA00X+087004Y+080103X0200Y         S0      
317m2470            VIA   -    MD0100PA00X+085565Y+069271X0200Y         S0      
317m2470            VIA   -    MD0100PA00X+097821Y+082122X0200Y         S0      
317m2470            VIA   -    MD0100PA00X+105570Y+084090X0200Y         S0      
317m2470            VIA   -    MD0100PA00X+087414Y+074891X0200Y         S0      
327m2470            U360  -1          A01X+085984Y+069271X0220Y0530R270 S1      
317m2470            VIA   -    MD0100PA00X+094826Y+129596X0200Y         S0      
317m2470            VIA   -    MD0100PA00X+085552Y+089850X0200Y         S0      
317m2470            VIA   -    MD0100PA00X+136415Y+085192X0180Y         S0      
327m2470            U6    -R16        A01X+136257Y+085349X0160Y         S1      
317m2471            VIA   -    MD0100PA00X+027634Y+046737X0200Y         S0      
317m2471            VIA   -    M      A01X+035821Y+083646X0200Y         S2      
017m2471            VIA   -    M      A18X+035821Y+083646X0260Y         S2      
017m2471                  -    MD0100PA00X+035821Y+083646                       
327m2471            U6    -E20        A01X+137517Y+088499X0160Y         S1      
317m2471            VIA   -    MD0100PA00X+137675Y+088656X0180Y         S0      
327m2471            R54   -2          A18X+027908Y+046324X0198Y0197     S2      
327m2471            R75   -1   M      A18X+027910Y+046737X0198Y0197R180 S2      
327P3V3_SSD6_OCP    PU58  -9          A01X+068992Y+022506X0110Y0240     S1      
317P3V3_SSD6_OCP    VIA   -    M      A01X+068915Y+023056X0200Y    R090 S2      
017P3V3_SSD6_OCP    VIA   -    M      A18X+068915Y+023056X0260Y    R090 S2      
017P3V3_SSD6_OCP          -    MD0100PA00X+068915Y+023056                       
327P3V3_SSD6_OCP    PR266 -1          A01X+068978Y+023296X0198Y0197R090 S1      
327m2472            U70   -7          A01X+151124Y+091668X0110Y0540     S1      
327m2472            VIA   -    M      A18X+145975Y+080688X0160Y0041R090 S2      
317m2472            VIA   -    MD0100PA00X+151053Y+090895X0200Y         S0      
327m2472            R1013 -2   M      A01X+091524Y+032960X0180Y0200R270 S1      
327m2472            R6287 -1          A01X+091524Y+032960X0180Y0200     S1      
317m2472            VIA   -    MD0100PA00X+091623Y+033633X0200Y         S0      
317m2473            VIA   -    M      A01X+056911Y+008601X0200Y    R180 S2      
017m2473            VIA   -    M      A18X+056911Y+008601X0260Y    R180 S2      
017m2473                  -    MD0100PA00X+056911Y+008601                       
327m2473            U130  -5          A01X+056599Y+008185X0240Y0460R180 S1      
327m2473            R1659 -1          A01X+056911Y+008882X0198Y0197R090 S1      
327m2474            J38   -A8         A01X+095616Y+009051X0150Y0500R090 S1      
317m2474            VIA   -    M      A01X+096041Y+009065X0200Y         S2      
017m2474            VIA   -    M      A18X+096041Y+009065X0260Y         S2      
017m2474                  -    MD0100PA00X+096041Y+009065                       
327m2474            R1695 -1          A01X+100578Y+007659X0198Y0197     S1      
317m2474            VIA   -    MD0100PA00X+100338Y+007659X0200Y         S0      
317m2475            VIA   -    MD0100PA00X+155391Y+033180X0200Y         S0      
327m2475            R1757 -2          A01X+155830Y+032986X0198Y0197R180 S1      
327m2475            R1772 -1          A01X+155145Y+032986X0198Y0197R180 S1      
317m2475            VIA   -    M      A01X+157842Y+033831X0200Y         S2      
017m2475            VIA   -    M      A18X+157842Y+033831X0260Y         S2      
017m2475                  -    MD0100PA00X+157842Y+033831                       
327m2475            R6271 -1          A18X+158544Y+033779X0198Y0197R180 S2      
327m2475            U421  -7          A01X+158244Y+033831X0170Y0460R270 S1      
317m2476            J3    -K10  D0122PA00X+018784Y+157043X0282Y    R180 S3      
317m2476            J11   -K10  D0122PA00X+036106Y+157043X0282Y    R180 S3      
317m2477            VIA   -    MD0100PA01X+091788Y+032822X0200Y         S0      
327m2477            R1013 -1   M      A01X+091524Y+032645X0180Y0200R270 S1      
327m2477            R6604 -2          A01X+091524Y+032645X0180Y0200R270 S1      
317m2477            VIA   -    MD0100PA01X+091595Y+034415X0200Y         S0      
327m2477            U112  -3          A01X+091938Y+035376X0100Y0290R180 S1      
327m2478            R1095 -2          A01X+052996Y+067323X0198Y0197R090 S1      
327m2478            U114  -M10        A01X+052941Y+068858X0090Y         S1      
317m2479            VIA   -    M      A01X+009176Y+101831X0200Y         S2      
017m2479            VIA   -    M      A18X+009176Y+101831X0260Y         S2      
017m2479                  -    MD0100PA00X+009176Y+101831                       
327m2479            Q12   -6   M      A01X+009176Y+101517X0240Y0240R270 S1      
327m2479            Q12   -5          A01X+009176Y+101221X0160Y0240R270 S1      
327m2479            R1261 -1   M      A01X+009144Y+102118X0198Y0197     S1      
327m2479            R5727 -1          A01X+009106Y+102523X0198Y0197R090 S1      
317m2480            VIA   -    M      A01X+056521Y+009428X0200Y         S2      
017m2480            VIA   -    M      A18X+056521Y+009428X0260Y         S2      
017m2480                  -    MD0100PA00X+056521Y+009428                       
317m2480            VIA   -    MD0100PA00X+056343Y+006044X0200Y         S0      
327m2480            U130  -3   M      A01X+056313Y+006472X0170Y0460R180 S1      
327m2480            R1667 -2   M      A01X+055184Y+007659X0198Y0197     S1      
327m2480            R1661 -2          A01X+054865Y+008058X0198Y0197R180 S1      
327m2480            R1669 -2          A01X+056521Y+009188X0198Y0197R090 S1      
327m2481            J39   -A7         A01X+105852Y+008815X0150Y0500R090 S1      
317m2481            VIA   -    M      A01X+106808Y+009062X0200Y         S2      
017m2481            VIA   -    M      A18X+106808Y+009062X0260Y         S2      
017m2481                  -    MD0100PA00X+106808Y+009062                       
327m2481            R1694 -1          A01X+110814Y+007259X0198Y0197     S1      
317m2481            VIA   -    MD0100PA00X+110574Y+007262X0200Y         S0      
327m2482            R1770 -1          A01X+155145Y+032536X0198Y0197R180 S1      
327m2482            R1756 -2          A01X+155830Y+032536X0198Y0197R180 S1      
317m2482            VIA   -    M      A01X+155353Y+032734X0200Y         S2      
017m2482            VIA   -    M      A18X+155353Y+032734X0260Y         S2      
017m2482                  -    MD0100PA00X+155353Y+032734                       
327m2482            U421  -6          A01X+158244Y+034087X0170Y0460R270 S1      
317m2482            VIA   -    MD0100PA00X+157859Y+034179X0200Y         S0      
327m2482            R6270 -1          A18X+158544Y+034179X0198Y0197R180 S2      
317m2483            VIA   -    M      A01X+110048Y+157932X0200Y    R090 S2      
017m2483            VIA   -    M      A18X+110048Y+157932X0260Y    R090 S2      
017m2483                  -    MD0100PA00X+110048Y+157932                       
327m2483            R1808 -1          A01X+110023Y+158243X0198Y0197R090 S1      
327m2483            U146  -4          A01X+109882Y+157481X0140Y0440     S1      
327m2484            VIA   -    M      A18X+137750Y+090400X0260Y         S2      
327m2484            R3604 -1          A18X+137450Y+091792X0198Y0197R270 S2      
327m2484            U6    -D19        A01X+137202Y+088814X0160Y         S1      
317m2484            VIA   -    MD0100PA00X+137360Y+088971X0180Y         S0      
317m2485            VIA   -    MD0100PA01X+054917Y+078160X0200Y         S0      
327m2485            U98   -8          A01X+054845Y+078933X0110Y0540     S1      
317m2485            VIA   -    MD0100PA01X+094270Y+034636X0200Y         S0      
327m2485            R6286 -1          A01X+094379Y+033682X0180Y0200R180 S1      
327m2485            R1015 -2   M      A01X+094379Y+033682X0180Y0200R270 S1      
317m2486            VIA   -    M      A01X+008763Y+100752X0200Y         S2      
017m2486            VIA   -    M      A18X+008763Y+100752X0260Y         S2      
017m2486                  -    MD0100PA00X+008763Y+100752                       
327m2486            D1    -C          A01X+009066Y+100335X0240Y0280R180 S1      
327m2486            Q12   -3          A01X+008468Y+100926X0240Y0240R270 S1      
317m2487            VIA   -    MD0100PA00X+056126Y+009435X0200Y         S0      
317m2487            VIA   -    M      A01X+056057Y+006051X0200Y         S2      
017m2487            VIA   -    M      A18X+056057Y+006051X0260Y         S2      
017m2487                  -    MD0100PA00X+056057Y+006051                       
327m2487            U130  -2   M      A01X+056057Y+006472X0170Y0460R180 S1      
327m2487            R1665 -2   M      A01X+055184Y+007259X0198Y0197     S1      
327m2487            R1660 -2          A01X+054865Y+006858X0198Y0197R180 S1      
327m2487            R1671 -2          A01X+056126Y+009195X0198Y0197R090 S1      
327m2488            J44   -A7         A01X+161797Y+008815X0150Y0500R090 S1      
317m2488            VIA   -    M      A01X+162753Y+009062X0200Y         S2      
017m2488            VIA   -    M      A18X+162753Y+009062X0260Y         S2      
017m2488                  -    MD0100PA00X+162753Y+009062                       
327m2488            R1735 -1          A01X+166759Y+007259X0198Y0197     S1      
317m2488            VIA   -    MD0100PA00X+166519Y+007262X0200Y         S0      
317m2489            VIA   -    MD0100PA00X+178767Y+030313X0200Y         S0      
327m2489            R1768 -2          A01X+179276Y+019653X0198Y0197     S1      
317m2489            VIA   -    M      A01X+153914Y+032086X0200Y         S2      
017m2489            VIA   -    M      A18X+153914Y+032086X0260Y         S2      
017m2489                  -    MD0100PA00X+153914Y+032086                       
327m2489            U142  -14         A01X+152850Y+032632X0120Y0630R270 S1      
317m2490            VIA   -    M      A01X+109047Y+158844X0200Y    R090 S2      
017m2490            VIA   -    M      A18X+109047Y+158844X0260Y    R090 S2      
017m2490                  -    MD0100PA00X+109047Y+158844                       
327m2490            R1807 -2   M      A01X+109047Y+158556X0198Y0197R090 S1      
327m2490            R1805 -2          A01X+108647Y+158241X0198Y0197R270 S1      
317m2490            VIA   -    MD0100PA00X+088137Y+083584X0180Y         S0      
327m2490            U5    -A15        A01X+088294Y+083742X0160Y    R180 S1      
317m2490            VIA   -    MD0100PA00X+087539Y+099380X0200Y         S0      
317m2490            VIA   -    MD0100PA00X+088693Y+129871X0200Y         S0      
327P3V3_SSD3_SS     PU60  -7          A01X+033914Y+022506X0110Y0240     S1      
317P3V3_SSD3_SS     VIA   -    M      A01X+034327Y+023012X0200Y    R090 S2      
017P3V3_SSD3_SS     VIA   -    M      A18X+034327Y+023012X0260Y    R090 S2      
017P3V3_SSD3_SS           -    MD0100PA00X+034327Y+023012                       
327P3V3_SSD3_SS     PC543 -1          A01X+034329Y+023298X0198Y0197R090 S1      
327m2491            R1094 -2          A01X+052596Y+067323X0198Y0197R090 S1      
327m2491            U114  -M9         A01X+052744Y+068858X0090Y         S1      
317m2492            VIA   -    M      A01X+009440Y+100665X0200Y         S2      
017m2492            VIA   -    M      A18X+009440Y+100665X0260Y         S2      
017m2492                  -    MD0100PA00X+009440Y+100665                       
327m2492            R1260 -2          A01X+009761Y+101082X0198Y0197R270 S1      
327m2492            D1    -A          A01X+009440Y+100335X0240Y0280R180 S1      
327m2493            J40   -A7         A01X+116088Y+008815X0150Y0500R090 S1      
317m2493            VIA   -    M      A01X+117045Y+009062X0200Y         S2      
017m2493            VIA   -    M      A18X+117045Y+009062X0260Y         S2      
017m2493                  -    MD0100PA00X+117045Y+009062                       
327m2493            R1707 -1          A01X+121050Y+007259X0198Y0197     S1      
317m2493            VIA   -    MD0100PA00X+120810Y+007262X0200Y         S0      
317m2494            VIA   -    M      A01X+154558Y+031636X0200Y         S2      
017m2494            VIA   -    M      A18X+154558Y+031636X0260Y         S2      
017m2494                  -    MD0100PA00X+154558Y+031636                       
327m2494            U142  -13         A01X+152850Y+032377X0120Y0630R270 S1      
327m2494            R1766 -2          A01X+154830Y+031636X0198Y0197R180 S1      
317m2495            J13   -A1   D0122PA00X+130508Y+162240X0282Y0282R180 S3      
317m2495            VIA   -    M      A01X+126718Y+153933X0200Y         S2      
017m2495            VIA   -    M      A18X+126718Y+153933X0260Y         S2      
017m2495                  -    MD0100PA00X+126718Y+153933                       
327m2495            R1849 -1          A01X+126022Y+153933X0198Y0197R180 S1      
327m2496            VIA   -    M      A01X+139891Y+087200X0300Y         S1      
327m2496            U6    -L22        A01X+138147Y+086609X0160Y         S1      
327m2496            R3647 -1          A01X+140792Y+087200X0198Y0197     S1      
317m2497            VIA   -    MD0100PA00X+112408Y+019666X0200Y         S0      
327m2497            R610  -1          A01X+112143Y+019666X0198Y0197R180 S1      
317m2497            VIA   -    MD0100PA00X+102171Y+019666X0200Y         S0      
327m2497            R599  -1          A01X+101907Y+019666X0198Y0197R180 S1      
327m2497            R1768 -1   M      A01X+178961Y+019653X0198Y0197     S1      
317m2497            VIA   -    MD0100PA00X+132880Y+019666X0200Y         S0      
317m2497            VIA   -    M      A01X+147880Y+019666X0200Y         S2      
017m2497            VIA   -    M      A18X+147880Y+019666X0260Y         S2      
017m2497                  -    MD0100PA00X+147880Y+019666                       
317m2497            VIA   -    MD0100PA00X+158116Y+019666X0200Y         S0      
327m2497            R665  -1          A01X+167041Y+019662X0198Y0197     S1      
317m2497            VIA   -    MD0100PA00X+166732Y+019883X0200Y         S0      
317m2497            VIA   -    MD0100PA00X+178589Y+019666X0200Y         S0      
327m2497            R676  -1          A01X+178324Y+019666X0198Y0197R180 S1      
327m2497            R654  -1          A01X+157852Y+019666X0198Y0197R180 S1      
327m2497            R643  -1          A01X+147616Y+019666X0198Y0197R180 S1      
327m2497            R632  -1          A01X+132616Y+019666X0198Y0197R180 S1      
317m2497            VIA   -    MD0100PA00X+121027Y+019867X0200Y         S0      
327m2497            R621  -1          A01X+121332Y+019662X0198Y0197     S1      
327m2497            R1755 -2          A01X+178959Y+020072X0198Y0197R180 S1      
317MB_BMC_MON_ISO   VIA   -    M      A01X+109253Y+157942X0200Y    R090 S2      
017MB_BMC_MON_ISO   VIA   -    M      A18X+109253Y+157942X0260Y    R090 S2      
017MB_BMC_MON_ISO         -    MD0100PA00X+109253Y+157942                       
327MB_BMC_MON_ISO   R1807 -1          A01X+109047Y+158241X0198Y0197R090 S1      
327MB_BMC_MON_ISO   U146  -6          A01X+109370Y+157481X0140Y0440     S1      
317m2498            VIA   -    MD0100PA00X+137045Y+088341X0180Y         S0      
327m2498            U6    -F18        A01X+136887Y+088184X0160Y         S1      
317m2498            VIA   -    M      A01X+140550Y+090400X0200Y         S2      
017m2498            VIA   -    M      A18X+140550Y+090400X0260Y         S2      
017m2498                  -    MD0100PA00X+140550Y+090400                       
327m2498            R3615 -1          A01X+140792Y+090400X0198Y0197     S1      
327P3V3_SSD6_SS     PU58  -7          A01X+069386Y+022506X0110Y0240     S1      
317P3V3_SSD6_SS     VIA   -    M      A01X+069800Y+023012X0200Y    R090 S2      
017P3V3_SSD6_SS     VIA   -    M      A18X+069800Y+023012X0260Y    R090 S2      
017P3V3_SSD6_SS           -    MD0100PA00X+069800Y+023012                       
327P3V3_SSD6_SS     PC531 -1          A01X+069801Y+023298X0198Y0197R090 S1      
317m2499            VIA   -    MD0100PA00X+101566Y+068305X0200Y         S0      
327m2499            R1092 -1          A01X+051746Y+067008X0198Y0197R090 S1      
327m2499            PEX3  -AC1        A01X+151634Y+117244X0180Y         S1      
317m2499            VIA   -    MD0080PA00X+151447Y+117057X0160Y         S0      
317m2500            VIA   -    M      A01X+041079Y+002263X0200Y    R090 S2      
017m2500            VIA   -    M      A18X+041079Y+002263X0260Y    R090 S2      
017m2500                  -    MD0100PA00X+041079Y+002263                       
327m2500            U129  -5          A01X+040995Y+002575X0240Y0460R090 S1      
327m2500            R1648 -1          A01X+041692Y+002263X0198Y0197     S1      
317m2501            VIA   -    M      A01X+112408Y+019266X0200Y         S2      
017m2501            VIA   -    M      A18X+112408Y+019266X0260Y         S2      
017m2501                  -    MD0100PA00X+112408Y+019266                       
327m2501            R611  -1          A01X+112143Y+019266X0198Y0197R180 S1      
317m2501            VIA   -    MD0100PA00X+101029Y+019958X0200Y         S0      
327m2501            R600  -1          A01X+101175Y+019662X0198Y0197R180 S1      
317m2501            VIA   -    MD0100PA00X+122644Y+019266X0200Y         S0      
317m2501            VIA   -    MD0100PA00X+132880Y+019266X0200Y         S0      
317m2501            VIA   -    MD0100PA00X+147880Y+019266X0200Y         S0      
317m2501            VIA   -    MD0100PA00X+158116Y+019266X0200Y         S0      
317m2501            VIA   -    MD0100PA00X+168352Y+019266X0200Y         S0      
317m2501            VIA   -    MD0100PA00X+179352Y+030334X0200Y         S0      
317m2501            VIA   -    MD0100PA00X+178578Y+019266X0200Y         S0      
327m2501            R677  -1          A01X+178324Y+019266X0198Y0197R180 S1      
327m2501            R666  -1          A01X+168088Y+019266X0198Y0197R180 S1      
327m2501            R655  -1          A01X+157852Y+019266X0198Y0197R180 S1      
327m2501            R644  -1          A01X+147616Y+019266X0198Y0197R180 S1      
327m2501            R633  -1          A01X+132616Y+019266X0198Y0197R180 S1      
327m2501            R622  -1          A01X+122379Y+019266X0198Y0197R180 S1      
317m2501            VIA   -    MD0100PA00X+155440Y+031636X0200Y         S0      
327m2501            R1754 -2          A01X+155830Y+031636X0198Y0197R180 S1      
327m2501            R1766 -1          A01X+155145Y+031636X0198Y0197R180 S1      
317m2502            VIA   -    M      A01X+124989Y+152780X0200Y         S2      
017m2502            VIA   -    M      A18X+124989Y+152780X0260Y         S2      
017m2502                  -    MD0100PA00X+124989Y+152780                       
317m2502            J7    -A7   D0122PA00X+118382Y+162240X0282Y    R180 S3      
327m2502            C4116 -2   M      A01X+125711Y+152346X0198Y0197R180 S1      
327m2502            R1852 -2          A01X+125707Y+152733X0198Y0197R180 S1      
327RST_MB_BIC_N     R1804 -2   M      A01X+109838Y+155733X0198Y0197R090 S1      
327RST_MB_BIC_N     U146  -3          A01X+109882Y+156693X0140Y0440     S1      
317RST_MB_BIC_N     VIA   -    M      A01X+109937Y+156115X0200Y    R090 S2      
017RST_MB_BIC_N     VIA   -    M      A18X+109937Y+156115X0260Y    R090 S2      
017RST_MB_BIC_N           -    MD0100PA00X+109937Y+156115                       
317RST_MB_BIC_N     VIA   -    MD0100PA00X+143926Y+141460X0200Y         S0      
327RST_MB_BIC_N     C4168 -2          A01X+143626Y+141089X0198Y0197R090 S1      
317RST_MB_BIC_N     VIA   -    MD0100PA00X+141082Y+130542X0200Y         S0      
317RST_MB_BIC_N     J14   -Z6   D0122PA00X+152161Y+145272X0282Y    R180 S3      
317RST_MB_BIC_N     VIA   -    MD0100PA00X+104967Y+134746X0200Y         S0      
327NIC3_CLK_EN_N    R3632 -2          A01X+140792Y+088000X0198Y0197R180 S1      
317NIC3_CLK_EN_N    VIA   -    M      A01X+140550Y+088000X0200Y         S2      
017NIC3_CLK_EN_N    VIA   -    M      A18X+140550Y+088000X0260Y         S2      
017NIC3_CLK_EN_N          -    MD0100PA00X+140550Y+088000                       
317NIC3_CLK_EN_N    VIA   -    MD0100PA00X+137360Y+087396X0180Y         S0      
327NIC3_CLK_EN_N    U6    -J19        A01X+137202Y+087239X0160Y         S1      
327P3V3_SSD1_SS     PU56  -7          A01X+013441Y+022506X0110Y0240     S1      
317P3V3_SSD1_SS     VIA   -    M      A01X+013855Y+023012X0200Y    R090 S2      
017P3V3_SSD1_SS     VIA   -    M      A18X+013855Y+023012X0260Y    R090 S2      
017P3V3_SSD1_SS           -    MD0100PA00X+013855Y+023012                       
327P3V3_SSD1_SS     PC518 -1          A01X+013856Y+023298X0198Y0197R090 S1      
327m2503            R1650 -2          A01X+040868Y+004309X0198Y0197R090 S1      
317m2503            VIA   -    MD0100PA00X+042238Y+002653X0200Y    R270 S0      
327m2503            R1656 -2          A01X+041998Y+002653X0198Y0197     S1      
317m2503            VIA   -    M      A01X+038795Y+002729X0200Y    R270 S2      
017m2503            VIA   -    M      A18X+038795Y+002729X0260Y    R270 S2      
017m2503                  -    MD0100PA00X+038795Y+002729                       
327m2503            R1654 -2   M      A01X+040469Y+003990X0198Y0197R270 S1      
327m2503            U129  -3   M      A01X+039282Y+002861X0170Y0460R090 S1      
317m2504            VIA   -    M      A01X+149552Y+034070X0200Y         S2      
017m2504            VIA   -    M      A18X+149552Y+034070X0260Y         S2      
017m2504                  -    MD0100PA00X+149552Y+034070                       
327m2504            U142  -6          A01X+150646Y+033912X0120Y0630R270 S1      
327m2504            R1769 -2          A01X+149312Y+034070X0198Y0197     S1      
327m2505            C4051 -2          A01X+040769Y+144294X0198Y0197     S1      
327m2505            R6299 -1   M      A01X+040754Y+144681X0198Y0197R180 S1      
317m2505            J11   -Z10  D0122PA00X+036106Y+145272X0282Y    R180 S3      
317m2505            VIA   -    MD0100PA00X+040797Y+144975X0200Y         S0      
317m2505            VIA   -    MD0100PA00X+078347Y+142466X0200Y         S0      
327m2505            U143  -1          A01X+130647Y+095610X0140Y0440R180 S1      
327m2505            R1784 -2          A01X+130700Y+096392X0198Y0197R270 S1      
317m2505            VIA   -    M      A01X+130700Y+096050X0200Y         S2      
017m2505            VIA   -    M      A18X+130700Y+096050X0260Y         S2      
017m2505                  -    MD0100PA00X+130700Y+096050                       
317m2505            VIA   -    MD0100PA00X+093637Y+095148X0200Y         S0      
317m2505            VIA   -    MD0100PA00X+091079Y+129946X0200Y         S0      
317m2506            VIA   -    MD0100PA00X+101566Y+067965X0200Y         S0      
327m2506            R1085 -1          A01X+051346Y+067008X0198Y0197R090 S1      
327m2506            PEX3  -AC2        A01X+152008Y+117244X0180Y         S1      
317m2506            VIA   -    MD0080PA00X+151821Y+117057X0160Y         S0      
327m2507            C2642 -1          A18X+100932Y+034895X0280Y0320R090 S2      
327m2507            R1047 -2          A18X+100932Y+035395X0280Y0320R270 S2      
327m2507            VIA   -           A18X+101441Y+034462X0260Y         S2      
317m2507            VIA   -    MD0100PA00X+100977Y+034449X0200Y         S0      
327m2507            U113  -B1         A01X+101005Y+034176X0110Y0180R090 S1      
327m2507            C2643 -1          A18X+100768Y+033988X0198Y0197R180 S2      
327m2508            R1649 -2          A01X+039668Y+004309X0198Y0197R090 S1      
317m2508            VIA   -    M      A01X+042245Y+003048X0200Y    R270 S2      
017m2508            VIA   -    M      A18X+042245Y+003048X0260Y    R270 S2      
017m2508                  -    MD0100PA00X+042245Y+003048                       
327m2508            R1658 -2          A01X+042005Y+003048X0198Y0197     S1      
317m2508            VIA   -    MD0100PA00X+038861Y+003117X0200Y    R270 S0      
327m2508            R1652 -2   M      A01X+040069Y+003990X0198Y0197R270 S1      
327m2508            U129  -2   M      A01X+039282Y+003117X0170Y0460R090 S1      
327m2509            J42   -A8         A01X+141325Y+009051X0150Y0500R090 S1      
317m2509            VIA   -    M      A01X+141750Y+009065X0200Y         S2      
017m2509            VIA   -    M      A18X+141750Y+009065X0260Y         S2      
017m2509                  -    MD0100PA00X+141750Y+009065                       
327m2509            R1723 -1          A01X+146287Y+007659X0198Y0197     S1      
317m2509            VIA   -    MD0100PA00X+146047Y+007659X0200Y         S0      
327m2510            R1779 -2          A01X+087850Y+020050X0198Y0197R090 S1      
317m2510            VIA   -    MD0100PA00X+094502Y+027605X0200Y         S0      
317m2510            VIA   -    MD0100PA00X+102722Y+028944X0200Y         S0      
317m2510            VIA   -    MD0100PA00X+110343Y+034054X0200Y         S0      
317m2510            VIA   -    M      A01X+148732Y+031820X0200Y         S2      
017m2510            VIA   -    M      A18X+148732Y+031820X0260Y         S2      
017m2510                  -    MD0100PA00X+148732Y+031820                       
327m2510            U142  -11         A01X+150646Y+032632X0120Y0630R270 S1      
327m2511            C4112 -2          A01X+125069Y+153134X0198Y0197     S1      
317m2511            J7    -A5   D0122PA00X+116650Y+162240X0282Y    R180 S3      
317m2511            VIA   -    M      A01X+125428Y+153133X0200Y         S2      
017m2511            VIA   -    M      A18X+125428Y+153133X0260Y         S2      
017m2511                  -    MD0100PA00X+125428Y+153133                       
327m2511            R1851 -2          A01X+125707Y+153133X0198Y0197R180 S1      
327P3V3_SSD5_OCP    PU57  -9          A01X+058756Y+022506X0110Y0240     S1      
317P3V3_SSD5_OCP    VIA   -    M      A01X+058679Y+023056X0200Y    R090 S2      
017P3V3_SSD5_OCP    VIA   -    M      A18X+058679Y+023056X0260Y    R090 S2      
017P3V3_SSD5_OCP          -    MD0100PA00X+058679Y+023056                       
327P3V3_SSD5_OCP    PR262 -1          A01X+058742Y+023296X0198Y0197R090 S1      
327m2512            C2641 -1          A18X+100768Y+032751X0198Y0197R180 S2      
327m2512            C2640 -1          A18X+099968Y+032783X0198Y0197R270 S2      
327m2512            C2639 -1          A18X+100768Y+032339X0198Y0197R180 S2      
327m2512            C2638 -1          A18X+099492Y+032605X0280Y0320     S2      
327m2512            L9    -2          A18X+098892Y+032671X0440Y0540R270 S2      
317m2512            VIA   -    MD0100PA00X+100042Y+035395X0200Y    R270 S0      
317m2512            VIA   -    M      A01X+100318Y+032306X0200Y         S2      
017m2512            VIA   -    M      A18X+100318Y+032306X0260Y         S2      
017m2512                  -    MD0100PA00X+100318Y+032306                       
327m2512            U113  -A12        A01X+100709Y+032306X0070Y0220R090 S1      
327m2512            R1047 -1          A18X+100352Y+035395X0280Y0320R270 S2      
327m2513            J38   -A7         A01X+095616Y+008815X0150Y0500R090 S1      
317m2513            VIA   -    M      A01X+096572Y+009062X0200Y         S2      
017m2513            VIA   -    M      A18X+096572Y+009062X0260Y         S2      
017m2513                  -    MD0100PA00X+096572Y+009062                       
327m2513            R1693 -1          A01X+100578Y+007259X0198Y0197     S1      
317m2513            VIA   -    MD0100PA00X+100338Y+007262X0200Y         S0      
317m2514            VIA   -    M      A01X+149560Y+032270X0200Y         S2      
017m2514            VIA   -    M      A18X+149560Y+032270X0260Y         S2      
017m2514                  -    MD0100PA00X+149560Y+032270                       
327m2514            U142  -10         A01X+150646Y+032888X0120Y0630R270 S1      
327m2514            R1777 -2          A01X+149312Y+032270X0198Y0197     S1      
317m2515            VIA   -    MD0100PA00X+097020Y+066765X0200Y         S0      
327m2515            R1091 -1          A01X+050946Y+067008X0198Y0197R090 S1      
317m2515            VIA   -    MD0080PA00X+105738Y+117057X0160Y         S0      
327m2515            PEX2  -AC1        A01X+105925Y+117244X0180Y         S1      
327m2516            R1324 -1          A01X+057734Y+122555X0198Y0197R225 S1      
317m2516            VIA   -    M      A01X+059288Y+122940X0200Y         S2      
017m2516            VIA   -    M      A18X+059288Y+122940X0260Y         S2      
017m2516                  -    MD0100PA00X+059288Y+122940                       
327m2516            PEX1  -L16        A01X+065827Y+121732X0180Y         S1      
317m2516            VIA   -    MD0080PA00X+065640Y+121545X0160Y         S0      
317TP_PEX1_TDI      VIA   -    MD0080PA00X+066014Y+121545X0160Y    R090 S0      
327TP_PEX1_TDI      VIA   -           A18X+066201Y+121732X0260Y         S2      
327TP_PEX1_TDI      PEX1  -L17        A01X+066201Y+121732X0180Y         S1      
317m2517            VIA   -    M      A01X+031675Y+008601X0200Y    R180 S2      
017m2517            VIA   -    M      A18X+031675Y+008601X0260Y    R180 S2      
017m2517                  -    MD0100PA00X+031675Y+008601                       
327m2517            U128  -5          A01X+031362Y+008185X0240Y0460R180 S1      
327m2517            R1645 -1          A01X+031675Y+008882X0198Y0197R090 S1      
317m2518            VIA   -    MD0080PA00X+106112Y+117057X0160Y         S0      
327m2518            PEX2  -AC2        A01X+106299Y+117244X0180Y         S1      
317m2518            VIA   -    MD0100PA00X+096680Y+066765X0200Y         S0      
327m2518            R1090 -1          A01X+050546Y+067008X0198Y0197R090 S1      
317PEX1_DFT_IDDT    VIA   -    M      A01X+057562Y+120774X0200Y    R315 S2      
017PEX1_DFT_IDDT    VIA   -    M      A18X+057562Y+120774X0260Y    R315 S2      
017PEX1_DFT_IDDT          -    MD0100PA00X+057562Y+120774                       
327PEX1_DFT_IDDT    R1308 -1          A01X+057451Y+120445X0198Y0197R225 S1      
327PEX1_DFT_IDDT    R1319 -2   M      A01X+057168Y+120728X0198Y0197R045 S1      
327PEX1_DFT_IDDT    PEX1  -M16        A01X+065827Y+121358X0180Y         S1      
317PEX1_DFT_IDDT    VIA   -    MD0080PA00X+065640Y+121171X0160Y         S0      
317m2519            VIA   -    M      A01X+030792Y+006053X0200Y         S2      
017m2519            VIA   -    M      A18X+030792Y+006053X0260Y         S2      
017m2519                  -    MD0100PA00X+030792Y+006053                       
327m2519            R1651 -2   M      A01X+029948Y+007259X0198Y0197     S1      
327m2519            R1646 -2          A01X+029628Y+006858X0198Y0197R180 S1      
327m2519            U128  -2   M      A01X+030821Y+006472X0170Y0460R180 S1      
317m2519            VIA   -    MD0100PA00X+030890Y+009435X0200Y         S0      
327m2519            R1657 -2          A01X+030890Y+009195X0198Y0197R090 S1      
327m2520            J43   -A8         A01X+151561Y+009051X0150Y0500R090 S1      
317m2520            VIA   -    M      A01X+151986Y+009065X0200Y         S2      
017m2520            VIA   -    M      A18X+151986Y+009065X0260Y         S2      
017m2520                  -    MD0100PA00X+151986Y+009065                       
327m2520            R1724 -1          A01X+156523Y+007659X0198Y0197     S1      
317m2520            VIA   -    MD0100PA00X+156283Y+007659X0200Y         S0      
327m2521            R1775 -2          A01X+149312Y+032720X0198Y0197     S1      
317m2521            VIA   -    M      A01X+150066Y+033002X0200Y         S2      
017m2521            VIA   -    M      A18X+150066Y+033002X0260Y         S2      
017m2521                  -    MD0100PA00X+150066Y+033002                       
327m2521            U142  -9          A01X+150646Y+033144X0120Y0630R270 S1      
327m2522            C4108 -2          A01X+125711Y+154356X0198Y0197R180 S1      
317m2522            J7    -A1   D0122PA00X+113185Y+162240X0282Y0282R180 S3      
317m2522            VIA   -    M      A01X+125428Y+153933X0200Y         S2      
017m2522            VIA   -    M      A18X+125428Y+153933X0260Y         S2      
017m2522                  -    MD0100PA00X+125428Y+153933                       
327m2522            R1849 -2   M      A01X+125707Y+153933X0198Y0197R180 S1      
327m2523            VIA   -    M      A01X+136500Y+081750X0300Y         S1      
327m2523            U6    -AB14       A01X+135628Y+083144X0160Y         S1      
327m2523            R4148 -2          A01X+136500Y+080958X0198Y0197R090 S1      
327PEX1_SPARE4      PEX1  -M25        A01X+069193Y+121358X0180Y         S1      
317PEX1_SPARE4      VIA   -    MD0080PA00X+069380Y+121171X0160Y    R270 S0      
327PEX1_SPARE4      VIA   -    M      A18X+078821Y+120801X0260Y         S2      
327PEX1_SPARE4      R1314 -2          A01X+080749Y+119857X0198Y0197R090 S1      
327PEX1_SPARE4      R1303 -1          A01X+080749Y+120344X0198Y0197R090 S1      
317PEX1_SPARE4      VIA   -    MD0100PA00X+080749Y+120104X0200Y         S0      
317m2524            VIA   -    M      A01X+031284Y+009428X0200Y         S2      
017m2524            VIA   -    M      A18X+031284Y+009428X0260Y         S2      
017m2524                  -    MD0100PA00X+031284Y+009428                       
317m2524            VIA   -    MD0100PA00X+031082Y+006039X0200Y         S0      
327m2524            R1653 -2   M      A01X+029948Y+007659X0198Y0197     S1      
327m2524            R1647 -2          A01X+029628Y+008058X0198Y0197R180 S1      
327m2524            U128  -3   M      A01X+031077Y+006472X0170Y0460R180 S1      
327m2524            R1655 -2          A01X+031284Y+009188X0198Y0197R090 S1      
327m2525            J41   -A7         A01X+126325Y+008815X0150Y0500R090 S1      
327m2525            R1708 -1          A01X+131486Y+004305X0198Y0197R270 S1      
317m2525            VIA   -    M      A01X+131489Y+004545X0200Y    R270 S2      
017m2525            VIA   -    M      A18X+131489Y+004545X0260Y    R270 S2      
017m2525                  -    MD0100PA00X+131489Y+004545                       
317m2525            VIA   -    MD0100PA00X+127281Y+009062X0200Y         S0      
317m2526            VIA   -    M      A01X+149569Y+033253X0200Y         S2      
017m2526            VIA   -    M      A18X+149569Y+033253X0260Y         S2      
017m2526                  -    MD0100PA00X+149569Y+033253                       
327m2526            U142  -8          A01X+150646Y+033400X0120Y0630R270 S1      
327m2526            R1773 -2          A01X+149312Y+033170X0198Y0197     S1      
327P3V3_SSD9_SS     PU64  -7          A01X+104859Y+022506X0110Y0240     S1      
317P3V3_SSD9_SS     VIA   -    M      A01X+105272Y+023012X0200Y    R090 S2      
017P3V3_SSD9_SS     VIA   -    M      A18X+105272Y+023012X0260Y    R090 S2      
017P3V3_SSD9_SS           -    MD0100PA00X+105272Y+023012                       
327P3V3_SSD9_SS     PC566 -1          A01X+105274Y+023298X0198Y0197R090 S1      
327m2527            PEX1  -AC1        A01X+060216Y+117244X0180Y         S1      
317m2527            VIA   -    MD0080PA00X+060029Y+117057X0160Y         S0      
327m2527            R1089 -1          A01X+049536Y+068501X0198Y0197     S1      
317m2527            VIA   -    MD0100PA00X+060573Y+094114X0200Y         S0      
317m2528            VIA   -    MD0100PA00X+039488Y+033838X0200Y         S0      
327m2528            U115  -5          A01X+041689Y+034086X0070Y0340R270 S1      
327m2528            R1074 -1          A01X+105880Y+031924X0198Y0197R180 S1      
317m2528            VIA   -    MD0100PA00X+107975Y+031934X0200Y         S0      
317m2529            VIA   -           A01X+098172Y+035222X0200Y         S2      
017m2529            VIA   -           A18X+098172Y+035222X0260Y         S2      
017m2529                  -     D0100PA00X+098172Y+035222                       
327m2529            U113  -A7         A01X+100709Y+033290X0070Y0220R090 S1      
317TP_PEX1_TMS      VIA   -    MD0080PA00X+067136Y+121171X0160Y         S0      
327TP_PEX1_TMS      VIA   -           A18X+066949Y+120984X0260Y         S2      
327TP_PEX1_TMS      PEX1  -M20        A01X+067323Y+121358X0180Y         S1      
327m2530            R6304 -2          A18X+149192Y+031800X0198Y0197     S2      
317m2530            VIA   -    M      A01X+148686Y+032720X0200Y         S2      
017m2530            VIA   -    M      A18X+148686Y+032720X0260Y         S2      
017m2530                  -    MD0100PA00X+148686Y+032720                       
327m2530            R1748 -2          A01X+148312Y+032720X0198Y0197     S1      
327m2530            R1775 -1          A01X+148997Y+032720X0198Y0197     S1      
327m2530            R6303 -2   M      A18X+149147Y+032720X0198Y0197     S2      
317m2531            VIA   -    M      A01X+058851Y+151414X0200Y         S2      
017m2531            VIA   -    M      A18X+058851Y+151414X0260Y         S2      
017m2531                  -    MD0100PA00X+058851Y+151414                       
317m2531            J5    -Z10  D0122PA00X+070752Y+145272X0282Y    R180 S3      
327m2531            R1848 -1          A01X+058851Y+150969X0198Y0197R180 S1      
317m2532            VIA   -    MD0100PA00X+135785Y+083302X0180Y         S0      
327m2532            U6    -AA14       A01X+135628Y+083460X0160Y         S1      
327m2532            R4612 -1          A01X+143258Y+081850X0198Y0197R180 S1      
327m2532            R4599 -2   M      A01X+143258Y+081450X0198Y0197     S1      
327m2532            R4628 -2          A01X+143742Y+081450X0198Y0197R180 S1      
317m2532            VIA   -    M      A01X+143500Y+081450X0200Y         S2      
017m2532            VIA   -    M      A18X+143500Y+081450X0260Y         S2      
017m2532                  -    MD0100PA00X+143500Y+081450                       
317m2533            VIA   -           A01X+099303Y+035381X0200Y         S2      
017m2533            VIA   -           A18X+099303Y+035381X0260Y         S2      
017m2533                  -     D0100PA00X+099303Y+035381                       
327m2533            U113  -A6         A01X+100709Y+033487X0070Y0220R090 S1      
317TP_PEX1_TRST_L   VIA   -    MD0080PA00X+066388Y+121171X0160Y         S0      
327TP_PEX1_TRST_L   VIA   -    M      A18X+067323Y+121358X0260Y         S2      
327TP_PEX1_TRST_L   R1323 -1          A18X+068104Y+121388X0198Y0197R270 S2      
327TP_PEX1_TRST_L   PEX1  -M18        A01X+066575Y+121358X0180Y         S1      
317m2534            VIA   -    MD0100PA00X+039395Y+144746X0200Y         S0      
327m2534            R5587 -1          A01X+007094Y+158669X0198Y0197R090 S1      
317m2534            VIA   -    M      A01X+176107Y+159072X0200Y    R180 S2      
017m2534            VIA   -    M      A18X+176107Y+159072X0260Y    R180 S2      
017m2534                  -    MD0100PA00X+176107Y+159072                       
327m2534            R5602 -1          A01X+176107Y+159319X0198Y0197R090 S1      
317m2534            VIA   -    MD0100PA00X+145272Y+003405X0200Y         S0      
327m2534            R1773 -1          A01X+148997Y+033170X0198Y0197     S1      
327m2534            R1747 -2          A01X+148312Y+033170X0198Y0197     S1      
317m2534            VIA   -    MD0100PA00X+148715Y+033127X0200Y         S0      
317m2534            VIA   -    MD0100PA00X+179109Y+007730X0200Y    R180 S0      
327m2534            R5818 -1          A01X+145151Y+003039X0198Y0197     S1      
317m2534            VIA   -    MD0100PA00X+028980Y+003674X0200Y         S0      
327m2534            R5808 -1          A01X+028379Y+002716X0198Y0197     S1      
317m2534            VIA   -    MD0100PA00X+171559Y+033172X0200Y         S0      
327SSD15_CLK_EN_N   VIA   -    M      A18X+136000Y+082450X0260Y         S2      
327SSD15_CLK_EN_N   U6    -Y13        A01X+135312Y+083774X0160Y         S1      
317SSD15_CLK_EN_N   VIA   -    MD0100PA00X+135470Y+083617X0180Y         S0      
327SSD15_CLK_EN_N   R4146 -2          A18X+136000Y+081958X0198Y0197R270 S2      
327P3V3_SSD10_SS    PU66  -7          A01X+115095Y+022506X0110Y0240     S1      
317P3V3_SSD10_SS    VIA   -    M      A01X+115508Y+023012X0200Y    R090 S2      
017P3V3_SSD10_SS    VIA   -    M      A18X+115508Y+023012X0260Y    R090 S2      
017P3V3_SSD10_SS          -    MD0100PA00X+115508Y+023012                       
327P3V3_SSD10_SS    PC578 -1          A01X+115510Y+023298X0198Y0197R090 S1      
327m2535            PEX1  -AC2        A01X+060590Y+117244X0180Y         S1      
317m2535            VIA   -    MD0080PA00X+060403Y+117057X0160Y         S0      
327m2535            R1084 -1          A01X+049536Y+068901X0198Y0197     S1      
317m2535            VIA   -    MD0100PA00X+060913Y+094114X0200Y         S0      
317m2536            VIA   -    MD0100PA00X+039488Y+034178X0200Y         S0      
327m2536            U115  -4          A01X+041689Y+034244X0070Y0340R270 S1      
317m2536            VIA   -    MD0100PA00X+107975Y+032274X0200Y         S0      
327m2536            R1073 -1          A01X+105880Y+032284X0198Y0197R180 S1      
327PEX1_SPARE5      VIA   -    M      A18X+072682Y+126335X0260Y         S2      
327PEX1_SPARE5      R1302 -1          A01X+081227Y+122702X0198Y0197R135 S1      
327PEX1_SPARE5      R1313 -2          A01X+081957Y+122630X0198Y0197R135 S1      
317PEX1_SPARE5      VIA   -    MD0100PA00X+081736Y+122823X0200Y         S0      
327PEX1_SPARE5      PEX1  -L25        A01X+069193Y+121732X0180Y         S1      
317PEX1_SPARE5      VIA   -    MD0080PA00X+069380Y+121545X0160Y    R270 S0      
317m2537            VIA   -    MD0100PA00X+020864Y+006037X0200Y         S0      
327m2537            U127  -3   M      A01X+020841Y+006472X0170Y0460R180 S1      
327m2537            R1636 -2          A01X+019392Y+008058X0198Y0197R180 S1      
327m2537            R1640 -2   M      A01X+019712Y+007659X0198Y0197     S1      
317m2537            VIA   -    M      A01X+021048Y+009428X0200Y         S2      
017m2537            VIA   -    M      A18X+021048Y+009428X0260Y         S2      
017m2537                  -    MD0100PA00X+021048Y+009428                       
327m2537            R1642 -2          A01X+021048Y+009188X0198Y0197R090 S1      
327m2538            R1771 -2          A01X+182827Y+109896X0198Y0197R270 S1      
317m2538            VIA   -    MD0100PA00X+182827Y+109597X0200Y         S0      
317m2538            VIA   -    MD0100PA00X+171593Y+034097X0200Y         S0      
327m2538            U142  -7          A01X+150646Y+033656X0120Y0630R270 S1      
317m2538            VIA   -    M      A01X+150168Y+033656X0200Y         S2      
017m2538            VIA   -    M      A18X+150168Y+033656X0260Y         S2      
017m2538                  -    MD0100PA00X+150168Y+033656                       
327m2539            VIA   -           A18X+071300Y+163789X0260Y         S2      
317m2539            J5    -I10  D0122PA00X+070752Y+158067X0282Y    R180 S3      
317m2540            VIA   -    MD0100PA00X+136415Y+084562X0180Y         S0      
327m2540            U6    -U16        A01X+136257Y+084719X0160Y         S1      
317m2540            VIA   -    MD0100PA00X+093663Y+091524X0200Y         S0      
327m2540            R6187 -2          A01X+093663Y+092255X0198Y0197R270 S1      
327m2540            R4519 -2          A01X+093663Y+091266X0198Y0197R090 S1      
317m2540            VIA   -    M      A01X+104342Y+083080X0200Y         S2      
017m2540            VIA   -    M      A18X+104342Y+083080X0260Y         S2      
017m2540                  -    MD0100PA00X+104342Y+083080                       
327m2541            PEX0  -AW32       A01X+026102Y+111260X0180Y         S1      
317m2541            VIA   -    MD0080PA00X+026289Y+111447X0160Y         S0      
327m2541            R1166 -1          A01X+013984Y+098611X0198Y0197R270 S1      
327m2541            R1234 -2          A01X+013984Y+099196X0198Y0197R270 S1      
317m2541            VIA   -    MD0100PA00X+013984Y+098881X0200Y         S0      
327m2541            VIA   -    M      A18X+025016Y+105579X0260Y         S2      
327PEX1_SPARE0      VIA   -    M      A18X+080026Y+123754X0260Y         S2      
327PEX1_SPARE0      R1307 -1          A01X+080944Y+122419X0198Y0197R135 S1      
327PEX1_SPARE0      R1318 -2          A01X+081391Y+122064X0198Y0197R135 S1      
317PEX1_SPARE0      VIA   -    MD0100PA00X+081230Y+122317X0200Y         S0      
327PEX1_SPARE0      PEX1  -M26        A01X+069567Y+121358X0180Y         S1      
317PEX1_SPARE0      VIA   -    MD0080PA00X+069754Y+121545X0160Y         S0      
317m2542            VIA   -    M      A01X+020585Y+006051X0200Y         S2      
017m2542            VIA   -    M      A18X+020585Y+006051X0260Y         S2      
017m2542                  -    MD0100PA00X+020585Y+006051                       
327m2542            U127  -2   M      A01X+020585Y+006472X0170Y0460R180 S1      
327m2542            R1638 -2   M      A01X+019712Y+007259X0198Y0197     S1      
327m2542            R1635 -2          A01X+019392Y+006858X0198Y0197R180 S1      
317m2542            VIA   -    MD0100PA00X+020653Y+009435X0200Y         S0      
327m2542            R1644 -2          A01X+020653Y+009195X0198Y0197R090 S1      
327m2543            J45   -A8         A01X+172033Y+009051X0150Y0500R090 S1      
317m2543            VIA   -    M      A01X+172458Y+009065X0200Y         S2      
017m2543            VIA   -    M      A18X+172458Y+009065X0260Y         S2      
017m2543                  -    MD0100PA00X+172458Y+009065                       
327m2543            R1738 -1          A01X+176995Y+007659X0198Y0197     S1      
317m2543            VIA   -    MD0100PA00X+176755Y+007659X0200Y         S0      
327m2544            PR6616-2   M      A01X+098386Y+110462X0198Y0197R180 S1      
327m2544            R797  -1          A01X+097833Y+110466X0198Y0197R180 S1      
317m2544            VIA   -    MD0100PA00X+098073Y+110466X0200Y         S0      
327m2544            R786  -1          A01X+091435Y+110466X0198Y0197R180 S1      
317m2544            VIA   -    MD0100PA00X+091675Y+110466X0200Y         S0      
327m2544            R819  -1          A01X+037286Y+094381X0198Y0197     S1      
317m2544            VIA   -    MD0100PA00X+090886Y+101768X0200Y         S0      
317m2544            VIA   -    MD0100PA00X+045146Y+097470X0200Y         S0      
317m2544            VIA   -    M      A01X+037021Y+094381X0200Y    R180 S2      
017m2544            VIA   -    M      A18X+037021Y+094381X0260Y    R180 S2      
017m2544                  -    MD0100PA00X+037021Y+094381                       
327m2544            R775  -1          A01X+036704Y+094348X0198Y0197R180 S1      
327m2544            R1746 -2   M      A01X+182827Y+110600X0198Y0197R270 S1      
327m2544            R808  -1          A01X+182231Y+110514X0198Y0197R180 S1      
317m2544            VIA   -    MD0100PA00X+098824Y+101692X0200Y         S0      
317m2544            VIA   -    MD0100PA00X+182471Y+110614X0200Y         S0      
327m2544            R1771 -1          A01X+182827Y+110211X0198Y0197R270 S1      
327m2545            R4604 -2          A01X+143258Y+082650X0198Y0197     S1      
327m2545            R4625 -2          A01X+143742Y+082650X0198Y0197R180 S1      
317m2545            VIA   -    M      A01X+143500Y+082550X0200Y         S2      
017m2545            VIA   -    M      A18X+143500Y+082550X0260Y         S2      
017m2545                  -    MD0100PA00X+143500Y+082550                       
327m2545            U6    -T14        A01X+135628Y+085034X0160Y         S1      
317m2545            VIA   -    MD0100PA00X+135785Y+084877X0180Y         S0      
327P3V3_SSD12_SS    PU63  -7          A01X+140331Y+022506X0110Y0240     S1      
317P3V3_SSD12_SS    VIA   -    M      A01X+140744Y+023012X0200Y    R090 S2      
017P3V3_SSD12_SS    VIA   -    M      A18X+140744Y+023012X0260Y    R090 S2      
017P3V3_SSD12_SS          -    MD0100PA00X+140744Y+023012                       
327P3V3_SSD12_SS    PC555 -1          A01X+140746Y+023298X0198Y0197R090 S1      
327m2546            R1088 -1          A01X+049536Y+069301X0198Y0197     S1      
317m2546            VIA   -    MD0100PA00X+050150Y+077046X0200Y         S0      
317m2546            VIA   -    MD0080PA00X+014321Y+117057X0160Y         S0      
327m2546            PEX0  -AC1        A01X+014508Y+117244X0180Y         S1      
317m2547            VIA   -    MD0100PA00X+108035Y+033166X0200Y         S0      
317m2547            VIA   -    MD0100PA00X+048684Y+070471X0200Y    R270 S0      
327m2547            U114  -G1         A01X+051170Y+069843X0090Y         S1      
327m2547            R1071 -1          A01X+105880Y+033176X0198Y0197R180 S1      
327PEX1_SPARE3      VIA   -    M      A18X+078833Y+122106X0260Y         S2      
327PEX1_SPARE3      R1304 -1          A01X+081149Y+120344X0198Y0197R090 S1      
327PEX1_SPARE3      R1315 -2          A01X+081149Y+119857X0198Y0197R090 S1      
317PEX1_SPARE3      VIA   -    MD0100PA00X+081148Y+120104X0200Y         S0      
327PEX1_SPARE3      PEX1  -L32        A01X+071811Y+121732X0180Y         S1      
317PEX1_SPARE3      VIA   -    MD0080PA00X+071998Y+121545X0160Y    R270 S0      
327m2548            R798  -1          A01X+097833Y+110066X0198Y0197R180 S1      
317m2548            VIA   -    MD0100PA00X+098085Y+109864X0200Y         S0      
317m2548            VIA   -    MD0100PA00X+091688Y+109864X0200Y         S0      
327m2548            R787  -1          A01X+091435Y+110066X0198Y0197R180 S1      
327m2548            R776  -1          A01X+006766Y+109166X0198Y0197R180 S1      
317m2548            VIA   -    MD0100PA00X+007817Y+094926X0200Y         S0      
327m2548            R820  -1          A01X+037286Y+094781X0198Y0197     S1      
317m2548            VIA   -    MD0100PA00X+090842Y+102310X0200Y         S0      
317m2548            VIA   -    MD0100PA00X+045812Y+097470X0200Y         S0      
317m2548            VIA   -    MD0100PA00X+037021Y+094781X0200Y    R180 S0      
327m2548            PR6617-2   M      A01X+098390Y+110030X0198Y0197R180 S1      
327m2548            R809  -1          A01X+182231Y+110114X0198Y0197R180 S1      
317m2548            VIA   -    MD0100PA00X+098824Y+102002X0200Y         S0      
317m2548            VIA   -    MD0100PA00X+182471Y+110018X0200Y         S0      
317m2548            VIA   -    MD0100PA00X+171223Y+034403X0200Y         S0      
327m2548            R1745 -2          A01X+148312Y+034070X0198Y0197     S1      
327m2548            R1769 -1          A01X+148997Y+034070X0198Y0197     S1      
317m2548            VIA   -    M      A01X+148691Y+034033X0200Y         S2      
017m2548            VIA   -    M      A18X+148691Y+034033X0260Y         S2      
017m2548                  -    MD0100PA00X+148691Y+034033                       
317m2549            J5    -H10  D0122PA00X+070752Y+158579X0282Y    R180 S3      
317m2549            VIA   -    M      A01X+057581Y+153291X0200Y         S2      
017m2549            VIA   -    M      A18X+057581Y+153291X0260Y         S2      
017m2549                  -    MD0100PA00X+057581Y+153291                       
327m2549            R1847 -1          A01X+057581Y+153543X0198Y0197R090 S1      
327SMB_PEX_R_SDA    R1497 -2          A18X+085368Y+086746X0198Y0197     S2      
327SMB_PEX_R_SDA    R4888 -1          A18X+084331Y+086741X0198Y0197     S2      
317SMB_PEX_R_SDA    VIA   -    MD0100PA00X+085118Y+086746X0200Y         S0      
317SMB_PEX_R_SDA    VIA   -    MD0100PA00X+083624Y+094910X0200Y    R270 S0      
317SMB_PEX_R_SDA    VIA   -    M      A01X+086710Y+093596X0200Y         S2      
017SMB_PEX_R_SDA    VIA   -    M      A18X+086710Y+093596X0260Y         S2      
017SMB_PEX_R_SDA          -    MD0100PA00X+086710Y+093596                       
327SMB_PEX_R_SDA    R1537 -1          A01X+083642Y+095912X0198Y0197R090 S1      
327SMB_PEX_R_SDA    R1544 -1          A18X+083695Y+094587X0198Y0197R090 S2      
327SMB_PEX_R_SDA    U123  -6   M      A01X+083624Y+095290X0170Y0460R180 S1      
317m2550            VIA   -    MD0100PA00X+108035Y+032826X0200Y         S0      
317m2550            VIA   -    MD0100PA00X+048684Y+070131X0200Y    R270 S0      
327m2550            U114  -H1         A01X+051170Y+069646X0090Y         S1      
327m2550            R1072 -1          A01X+105880Y+032816X0198Y0197R180 S1      
327m2551            PEX0  -AW31       A01X+025728Y+111260X0180Y         S1      
317m2551            VIA   -    MD0080PA00X+025915Y+111447X0160Y         S0      
317m2551            VIA   -    M      A01X+013584Y+098881X0200Y         S2      
017m2551            VIA   -    M      A18X+013584Y+098881X0260Y         S2      
017m2551                  -    MD0100PA00X+013584Y+098881                       
327m2551            R1165 -1          A01X+013584Y+098611X0198Y0197R270 S1      
327m2551            R1233 -2          A01X+013584Y+099196X0198Y0197R270 S1      
327m2552            R1326 -1          A01X+058583Y+121707X0198Y0197R225 S1      
317m2552            VIA   -    MD0100PA00X+059352Y+122447X0200Y         S0      
327m2552            VIA   -    M      A18X+059703Y+122447X0260Y         S2      
317m2552            VIA   -    MD0080PA00X+065266Y+121919X0160Y         S0      
327m2552            PEX1  -L15        A01X+065453Y+121732X0180Y         S1      
327m2553            J43   -A7         A01X+151561Y+008815X0150Y0500R090 S1      
317m2553            VIA   -    M      A01X+152517Y+009062X0200Y         S2      
017m2553            VIA   -    M      A18X+152517Y+009062X0260Y         S2      
017m2553                  -    MD0100PA00X+152517Y+009062                       
327m2553            R1722 -1          A01X+156523Y+007259X0198Y0197     S1      
317m2553            VIA   -    MD0100PA00X+156283Y+007262X0200Y         S0      
327m2554            R1767 -2          A01X+149312Y+034520X0198Y0197     S1      
317m2554            VIA   -    M      A01X+150039Y+034464X0200Y         S2      
017m2554            VIA   -    M      A18X+150039Y+034464X0260Y         S2      
017m2554                  -    MD0100PA00X+150039Y+034464                       
327m2554            U142  -5          A01X+150646Y+034168X0120Y0630R270 S1      
327P3V3_SSD10_OCP   PU66  -9          A01X+114701Y+022506X0110Y0240     S1      
317P3V3_SSD10_OCP   VIA   -    M      A01X+114624Y+023056X0200Y    R090 S2      
017P3V3_SSD10_OCP   VIA   -    M      A18X+114624Y+023056X0260Y    R090 S2      
017P3V3_SSD10_OCP         -    MD0100PA00X+114624Y+023056                       
327P3V3_SSD10_OCP   PR281 -1          A01X+114686Y+023296X0198Y0197R090 S1      
317m2555            VIA   -    M      A01X+092134Y+037689X0200Y    R090 S2      
017m2555            VIA   -    M      A18X+092134Y+037689X0260Y    R090 S2      
017m2555                  -    MD0100PA00X+092134Y+037689                       
327m2555            R1007 -1          A01X+091907Y+038133X0198Y0197R090 S1      
327m2555            U112  -18         A01X+092134Y+037275X0100Y0290R180 S1      
327m2556            R1087 -1          A01X+049536Y+069701X0198Y0197     S1      
317m2556            VIA   -    MD0100PA00X+050490Y+077046X0200Y         S0      
327m2556            PEX0  -AC2        A01X+014882Y+117244X0180Y         S1      
317m2556            VIA   -    MD0080PA00X+014695Y+117057X0160Y         S0      
327PEX1_SPARE2      VIA   -    M      A18X+079497Y+123395X0260Y         S2      
327PEX1_SPARE2      R1305 -1          A01X+080661Y+122136X0198Y0197R135 S1      
327PEX1_SPARE2      R1316 -2          A01X+081108Y+121781X0198Y0197R135 S1      
317PEX1_SPARE2      VIA   -    MD0100PA00X+080903Y+121990X0200Y         S0      
327PEX1_SPARE2      PEX1  -L27        A01X+069941Y+121732X0180Y         S1      
317PEX1_SPARE2      VIA   -    MD0080PA00X+069941Y+121732X0160Y         S0      
317m2557            VIA   -    M      A01X+021439Y+008601X0200Y    R180 S2      
017m2557            VIA   -    M      A18X+021439Y+008601X0260Y    R180 S2      
017m2557                  -    MD0100PA00X+021439Y+008601                       
327m2557            U127  -5          A01X+021126Y+008185X0240Y0460R180 S1      
327m2557            R1634 -1          A01X+021439Y+008882X0198Y0197R090 S1      
327m2558            J44   -A8         A01X+161797Y+009051X0150Y0500R090 S1      
317m2558            VIA   -    M      A01X+162222Y+009065X0200Y         S2      
017m2558            VIA   -    M      A18X+162222Y+009065X0260Y         S2      
017m2558                  -    MD0100PA00X+162222Y+009065                       
327m2558            R1737 -1          A01X+166759Y+007659X0198Y0197     S1      
317m2558            VIA   -    MD0100PA00X+166519Y+007659X0200Y         S0      
317m2559            VIA   -    M      A01X+149552Y+034968X0200Y         S2      
017m2559            VIA   -    M      A18X+149552Y+034968X0260Y         S2      
017m2559                  -    MD0100PA00X+149552Y+034968                       
327m2559            U142  -4          A01X+150646Y+034424X0120Y0630R270 S1      
327m2559            R1765 -2          A01X+149312Y+034970X0198Y0197     S1      
327m2560            VIA   -           A18X+070749Y+163351X0260Y         S2      
317m2560            J5    -G9   D0122PA00X+069886Y+159169X0282Y    R180 S3      
327SMB_PEX_R_SCL    R1495 -2          A18X+085368Y+086346X0198Y0197     S2      
327SMB_PEX_R_SCL    R4887 -1          A18X+084331Y+086341X0198Y0197     S2      
317SMB_PEX_R_SCL    VIA   -    MD0100PA00X+085118Y+086346X0200Y         S0      
317SMB_PEX_R_SCL    VIA   -    MD0100PA00X+083368Y+094910X0200Y    R270 S0      
317SMB_PEX_R_SCL    VIA   -    M      A01X+087213Y+093477X0200Y         S2      
017SMB_PEX_R_SCL    VIA   -    M      A18X+087213Y+093477X0260Y         S2      
017SMB_PEX_R_SCL          -    MD0100PA00X+087213Y+093477                       
327SMB_PEX_R_SCL    R1536 -1          A01X+083242Y+095912X0198Y0197R090 S1      
327SMB_PEX_R_SCL    R1546 -1          A18X+083295Y+094587X0198Y0197R090 S2      
327SMB_PEX_R_SCL    U123  -7   M      A01X+083368Y+095290X0170Y0460R180 S1      
327m2561            R4611 -1          A01X+143258Y+083450X0198Y0197R180 S1      
327m2561            R4598 -2   M      A01X+143258Y+083050X0198Y0197     S1      
327m2561            R4624 -2          A01X+143742Y+083050X0198Y0197R180 S1      
317m2561            VIA   -    M      A01X+143498Y+083050X0200Y         S2      
017m2561            VIA   -    M      A18X+143498Y+083050X0260Y         S2      
017m2561                  -    MD0100PA00X+143498Y+083050                       
327m2561            U6    -T13        A01X+135312Y+085034X0160Y         S1      
317m2561            VIA   -    MD0100PA00X+135470Y+084877X0180Y         S0      
327m2562            PEX0  -AV32       A01X+026102Y+111634X0180Y         S1      
317m2562            VIA   -    MD0080PA00X+026289Y+111821X0160Y         S0      
327m2562            VIA   -    M      A18X+026573Y+106461X0260Y         S2      
317m2562            VIA   -    MD0100PA00X+014784Y+098881X0200Y         S0      
327m2562            R1216 -2          A01X+014784Y+099196X0198Y0197R270 S1      
327m2562            R1164 -1          A01X+014784Y+098611X0198Y0197R270 S1      
317TP_PEX1_TCK      VIA   -    MD0080PA00X+065266Y+121545X0160Y         S0      
327TP_PEX1_TCK      VIA   -           A18X+065079Y+121732X0260Y         S2      
327TP_PEX1_TCK      PEX1  -M15        A01X+065453Y+121358X0180Y         S1      
327m2563            J39   -A8         A01X+105852Y+009051X0150Y0500R090 S1      
317m2563            VIA   -    M      A01X+106277Y+009065X0200Y         S2      
017m2563            VIA   -    M      A18X+106277Y+009065X0260Y         S2      
017m2563                  -    MD0100PA00X+106277Y+009065                       
327m2563            R1696 -1          A01X+110814Y+007659X0198Y0197     S1      
317m2563            VIA   -    MD0100PA00X+110574Y+007659X0200Y         S0      
327m2564            R687  -1          A01X+037093Y+036744X0198Y0197R270 S1      
327m2564            R698  -1          A01X+037049Y+037957X0198Y0197R090 S1      
317m2564            VIA   -    MD0100PA00X+037049Y+037717X0200Y    R270 S0      
317m2564            VIA   -    MD0100PA00X+045588Y+036770X0200Y         S0      
327m2564            VIA   -    M      A18X+037049Y+037390X0260Y         S2      
327m2564            R709  -1          A01X+051677Y+060280X0198Y0197R270 S1      
317m2564            VIA   -    MD0100PA00X+051677Y+060544X0200Y    R090 S0      
327m2564            R731  -1          A01X+097386Y+060280X0198Y0197R270 S1      
317m2564            VIA   -    MD0100PA00X+097386Y+060544X0200Y    R090 S0      
327m2564            R764  -1          A18X+143044Y+060280X0198Y0197R090 S2      
327m2564            R1767 -1          A01X+148997Y+034520X0198Y0197     S1      
327m2564            R720  -1          A01X+086809Y+037692X0198Y0197R090 S1      
317m2564            VIA   -    MD0100PA00X+086809Y+037375X0200Y         S0      
327m2564            R1744 -2          A01X+148312Y+034520X0198Y0197     S1      
317m2564            VIA   -    MD0100PA00X+148636Y+034520X0200Y         S0      
317m2564            VIA   -    MD0100PA00X+143094Y+060544X0200Y    R090 S0      
327m2564            R753  -1          A01X+143094Y+060280X0198Y0197R270 S1      
317m2564            VIA   -    MD0100PA00X+128466Y+037717X0200Y         S0      
327m2564            R742  -1          A01X+128466Y+037957X0198Y0197R090 S1      
327m2565            R4669 -2          A01X+141558Y+069700X0198Y0197     S1      
327m2565            R4707 -2          A01X+142042Y+069700X0198Y0197R180 S1      
317m2565            VIA   -    M      A01X+141800Y+069600X0200Y         S2      
017m2565            VIA   -    M      A18X+141800Y+069600X0260Y         S2      
017m2565                  -    MD0100PA00X+141800Y+069600                       
317m2565            VIA   -    MD0100PA00X+137045Y+083932X0180Y         S0      
327m2565            U6    -W18        A01X+136887Y+084089X0160Y         S1      
327P3V3_SSD8_SS     PU62  -7          A01X+094689Y+021023X0110Y0240     S1      
317P3V3_SSD8_SS     VIA   -    M      A01X+095018Y+021573X0200Y    R090 S2      
017P3V3_SSD8_SS     VIA   -    M      A18X+095018Y+021573X0260Y    R090 S2      
017P3V3_SSD8_SS           -    MD0100PA00X+095018Y+021573                       
327P3V3_SSD8_SS     PC554 -1          A01X+095104Y+021816X0198Y0197R090 S1      
327PEX1_SPARE1      VIA   -    M      A18X+079199Y+122451X0260Y         S2      
327PEX1_SPARE1      R1306 -1          A01X+081549Y+120344X0198Y0197R090 S1      
327PEX1_SPARE1      R1317 -2          A01X+081549Y+119857X0198Y0197R090 S1      
317PEX1_SPARE1      VIA   -    MD0100PA00X+081546Y+120104X0200Y         S0      
327PEX1_SPARE1      PEX1  -L30        A01X+071063Y+121732X0180Y         S1      
317PEX1_SPARE1      VIA   -    MD0080PA00X+071250Y+121545X0160Y    R270 S0      
317m2566            VIA   -    MD0100PA00X+010012Y+037790X0200Y         S0      
317m2566            VIA   -    MD0100PA00X+036653Y+037717X0200Y    R270 S0      
317m2566            VIA   -    MD0100PA00X+036556Y+035430X0200Y         S0      
327m2566            R699  -1          A01X+036649Y+037957X0198Y0197R090 S1      
317m2566            VIA   -    MD0100PA00X+006368Y+060544X0200Y    R090 S0      
327m2566            R688  -1          A01X+006368Y+060280X0198Y0197R270 S1      
317m2566            VIA   -    M      A01X+045085Y+037205X0200Y         S2      
017m2566            VIA   -    M      A18X+045085Y+037205X0260Y         S2      
017m2566                  -    MD0100PA00X+045085Y+037205                       
327m2566            R710  -1          A01X+052077Y+060280X0198Y0197R270 S1      
327m2566            R732  -1          A01X+097786Y+060280X0198Y0197R270 S1      
317m2566            VIA   -    MD0100PA00X+097786Y+060544X0200Y    R090 S0      
317m2566            VIA   -    MD0100PA00X+052077Y+060544X0200Y    R090 S0      
317m2566            VIA   -    MD0100PA00X+086759Y+038500X0200Y         S0      
317m2566            VIA   -    MD0100PA00X+128070Y+037717X0200Y    R270 S0      
327m2566            R743  -1          A01X+128066Y+037957X0198Y0197R090 S1      
327m2566            R1743 -2          A01X+148312Y+034970X0198Y0197     S1      
327m2566            R1765 -1          A01X+148997Y+034970X0198Y0197     S1      
317m2566            VIA   -    MD0100PA00X+148636Y+034970X0200Y         S0      
317m2566            VIA   -    MD0100PA00X+173779Y+037717X0200Y    R270 S0      
317m2566            VIA   -    MD0100PA00X+143494Y+060544X0200Y    R090 S0      
327m2566            R754  -1          A01X+143494Y+060280X0198Y0197R270 S1      
317m2566            VIA   -    MD0100PA00X+175609Y+054295X0200Y         S0      
327m2566            R765  -1          A01X+173775Y+037957X0198Y0197R090 S1      
327m2566            R721  -1          A01X+086759Y+038742X0198Y0197R090 S1      
327m2567            C4106 -2          A01X+056796Y+153539X0198Y0197R090 S1      
317m2567            J5    -F9   D0122PA00X+069886Y+159681X0282Y    R180 S3      
317m2567            VIA   -    M      A01X+057080Y+153031X0200Y         S2      
017m2567            VIA   -    M      A18X+057080Y+153031X0260Y         S2      
017m2567                  -    MD0100PA00X+057080Y+153031                       
327m2567            R1846 -2   M      A01X+057181Y+153543X0198Y0197R270 S1      
327SMB_PEX_SDA      VIA   -    M      A18X+086321Y+086415X0260Y         S2      
317SMB_PEX_SDA      VIA   -    MD0100PA00X+088137Y+086734X0180Y    R270 S0      
327SMB_PEX_SDA      R1497 -1          A18X+085683Y+086746X0198Y0197     S2      
327SMB_PEX_SDA      U5    -K15        A01X+088294Y+086576X0160Y    R180 S1      
327m2568            U396  -1          A01X+168463Y+014265X0240Y0240     S1      
327m2568            R6119 -2          A01X+166428Y+014125X0198Y0197     S1      
317m2568            VIA   -    M      A01X+166721Y+014125X0200Y         S2      
017m2568            VIA   -    M      A18X+166721Y+014125X0260Y         S2      
017m2568                  -    MD0100PA00X+166721Y+014125                       
317m2568            VIA   -    MD0100PA00X+171225Y+024430X0200Y    R090 S0      
327m2568            R4510 -2          A01X+171225Y+024168X0198Y0197     S1      
317m2568            VIA   -    MD0100PA00X+164003Y+033555X0200Y         S0      
317m2568            VIA   -    MD0100PA00X+143877Y+037166X0200Y         S0      
317m2568            VIA   -    MD0100PA00X+135470Y+084247X0180Y         S0      
327m2568            U6    -V13        A01X+135312Y+084404X0160Y         S1      
317m2569            VIA   -    M      A01X+018344Y+017219X0200Y         S2      
017m2569            VIA   -    M      A18X+018344Y+017219X0260Y         S2      
017m2569                  -    MD0100PA00X+018344Y+017219                       
327m2569            R524  -2          A01X+018002Y+016870X0198Y0197R180 S1      
327m2569            C206  -1   M      A01X+018007Y+017300X0198Y0197R090 S1      
327m2569            U54   -13         A01X+018935Y+017734X0090Y0240R180 S1      
317m2570            VIA   -    M      A01X+018286Y+017762X0200Y         S2      
017m2570            VIA   -    M      A18X+018286Y+017762X0260Y         S2      
017m2570                  -    MD0100PA00X+018286Y+017762                       
327m2570            R525  -2          A01X+017607Y+017615X0198Y0197R090 S1      
327m2570            C206  -2   M      A01X+018007Y+017615X0198Y0197R090 S1      
327m2570            U54   -12         A01X+018680Y+017990X0090Y0240R090 S1      
317m2571            VIA   -    M      A01X+020054Y+019018X0200Y         S2      
017m2571            VIA   -    M      A18X+020054Y+019018X0260Y         S2      
017m2571                  -    MD0100PA00X+020054Y+019018                       
327m2571            U54   -4          A01X+019782Y+018580X0090Y0240R090 S1      
327m2571            R523  -2          A01X+020411Y+019266X0198Y0197R180 S1      
317SSD2_ADC_A1      VIA   -    M      A01X+030355Y+017266X0200Y         S2      
017SSD2_ADC_A1      VIA   -    M      A18X+030355Y+017266X0260Y         S2      
017SSD2_ADC_A1            -    MD0100PA00X+030355Y+017266                       
327SSD2_ADC_A1      U55   -1          A01X+030018Y+017990X0090Y0240R090 S1      
327SSD2_ADC_A1      R528  -1          A01X+030647Y+016866X0198Y0197     S1      
327SSD2_ADC_A1      R531  -1   M      A01X+030647Y+017266X0198Y0197     S1      
327m2572            VIA   -    M      A01X+118031Y+031927X0300Y    R180 S1      
327m2572            U7    -5          A01X+117171Y+032415X0220Y0680R270 S1      
327m2572            R488  -2          A01X+118401Y+032414X0198Y0197R180 S1      
327m2573            VIA   -    M      A01X+118116Y+032970X0300Y    R180 S1      
327m2573            U7    -6          A01X+117171Y+032915X0220Y0680R270 S1      
327m2573            R487  -2          A01X+118889Y+032940X0198Y0197R180 S1      
317m2574            VIA   -    MD0100PA00X+131106Y+088936X0200Y         S0      
317m2574            VIA   -    M      A01X+139687Y+095871X0200Y         S2      
017m2574            VIA   -    M      A18X+139687Y+095871X0260Y         S2      
017m2574                  -    MD0100PA00X+139687Y+095871                       
317m2574            VIA   -    MD0100PA00X+183466Y+121324X0200Y         S0      
327m2574            U6    -D1         A01X+131533Y+088814X0160Y         S1      
327m2574            R4438 -1          A18X+181783Y+121256X0198Y0197R090 S2      
317m2575            VIA   -    M      A01X+037888Y+096186X0200Y    R180 S2      
017m2575            VIA   -    M      A18X+037888Y+096186X0260Y    R180 S2      
017m2575                  -    MD0100PA00X+037888Y+096186                       
327m2575            U96   -2          A01X+038230Y+095861X0090Y0240R270 S1      
327m2575            R814  -1          A01X+037601Y+096381X0198Y0197R180 S1      
327m2575            R816  -1   M      A01X+037601Y+095981X0198Y0197R180 S1      
327BB_FRU_A2        VIA   -    M      A01X+113857Y+032915X0300Y    R180 S1      
327BB_FRU_A2        R486  -1          A01X+112058Y+032900X0198Y0197R180 S1      
327BB_FRU_A2        U7    -3          A01X+115091Y+032915X0220Y0680R270 S1      
327BB_FRU_A2        R491  -1   M      A01X+112908Y+032900X0198Y0197R180 S1      
317m2576            VIA   -    M      A01X+039725Y+096286X0200Y    R180 S2      
017m2576            VIA   -    M      A18X+039725Y+096286X0260Y    R180 S2      
017m2576                  -    MD0100PA00X+039725Y+096286                       
327m2576            U96   -12         A01X+039332Y+096058X0090Y0240R270 S1      
327m2576            R822  -2          A01X+040404Y+096433X0198Y0197R270 S1      
327m2576            C831  -2   M      A01X+040004Y+096433X0198Y0197R270 S1      
317BB_FRU_A0        VIA   -    M      A01X+114559Y+033915X0200Y         S2      
017BB_FRU_A0        VIA   -    M      A18X+114559Y+033915X0260Y         S2      
017BB_FRU_A0              -    MD0100PA00X+114559Y+033915                       
327BB_FRU_A0        R484  -1          A01X+112058Y+033900X0198Y0197R180 S1      
327BB_FRU_A0        R489  -1   M      A01X+112908Y+033900X0198Y0197R180 S1      
327BB_FRU_A0        U7    -1          A01X+115091Y+033915X0220Y0680R270 S1      
317m2577            VIA   -    M      A01X+037924Y+095664X0200Y    R180 S2      
017m2577            VIA   -    M      A18X+037924Y+095664X0260Y    R180 S2      
017m2577                  -    MD0100PA00X+037924Y+095664                       
327m2577            R817  -1          A01X+037601Y+095581X0198Y0197R180 S1      
327m2577            U96   -3          A01X+038230Y+095664X0090Y0240R270 S1      
317m2578            VIA   -    M      A01X+037893Y+096781X0200Y    R180 S2      
017m2578            VIA   -    M      A18X+037893Y+096781X0260Y    R180 S2      
017m2578                  -    MD0100PA00X+037893Y+096781                       
327m2578            U96   -1          A01X+038230Y+096058X0090Y0240R270 S1      
327m2578            R818  -1   M      A01X+037601Y+096781X0198Y0197R180 S1      
327m2578            R813  -1   M      A01X+037601Y+097181X0198Y0197R180 S1      
327m2578            R5627 -1          A01X+037286Y+093998X0198Y0197     S1      
317m2579            VIA   -    M      A01X+037993Y+094977X0200Y    R180 S2      
017m2579            VIA   -    M      A18X+037993Y+094977X0260Y    R180 S2      
017m2579                  -    MD0100PA00X+037993Y+094977                       
327m2579            R820  -2          A01X+037601Y+094781X0198Y0197     S1      
327m2579            U96   -4          A01X+038230Y+095467X0090Y0240R270 S1      
327P1V25_PEX3_R     PC278 -1          A01X+178928Y+112612X0630Y1190R270 S1      
327P1V25_PEX3_R     PC279 -1          A01X+180376Y+111959X0630Y1190R090 S1      
327P1V25_PEX3_R     PL24  -2          A01X+179310Y+114756X1160Y1460R270 S1      
327P1V25_PEX3_R     PC276 -1          A01X+181024Y+113441X0198Y0197     S1      
327P1V25_PEX3_R     U95   -11         A01X+180184Y+109317X0090Y0240R090 S1      
327P1V25_PEX3_R     C827  -1          A01X+179535Y+109606X0198Y0197R090 S1      
327P1V25_PEX3_R     R804  -2          A01X+177944Y+110095X1150Y1380R090 S1      
327P1V25_PEX3_R     PC999 -1          A18X+180819Y+114891X0400Y0500     S2      
317P1V25_PEX3_R     VIA   -    MD0100PA00X+180954Y+114491X0200Y    R270 S0      
317P1V25_PEX3_R     VIA   -    MD0100PA00X+180704Y+114491X0200Y    R270 S0      
327P1V25_PEX3_R     VIA   -           A18X+179792Y+114833X0260Y         S2      
327P1V25_PEX3_R     PC1001-1          A18X+178336Y+115182X0400Y0500R180 S2      
327P1V25_PEX3_R     PC1000-1          A18X+178336Y+114382X0400Y0500R180 S2      
317P1V25_PEX3_R     VIA   -    MD0100PA00X+178430Y+114782X0200Y    R180 S0      
317P1V25_PEX3_R     VIA   -    MD0100PA00X+178180Y+114782X0200Y    R180 S0      
327P1V25_PEX3_R     PC273 -1          A18X+180819Y+112859X0400Y0500     S2      
327P1V25_PEX3_R     PC998 -1          A18X+180819Y+114091X0400Y0500     S2      
327P1V25_PEX3_R     VIA   -           A18X+179699Y+113456X0260Y         S2      
327P1V25_PEX3_R     PC272 -1          A18X+178336Y+113512X0400Y0500R180 S2      
327P1V25_PEX3_R     PC274 -1          A18X+180819Y+111959X0400Y0500     S2      
327P1V25_PEX3_R     PC275 -1          A18X+178336Y+112612X0400Y0500R180 S2      
317P1V25_PEX3_R     VIA   -    MD0100PA00X+180954Y+113691X0200Y    R270 S0      
317P1V25_PEX3_R     VIA   -    MD0100PA00X+180704Y+113691X0200Y    R270 S0      
317P1V25_PEX3_R     VIA   -    MD0100PA00X+180723Y+113336X0200Y         S0      
317P1V25_PEX3_R     VIA   -    MD0100PA00X+180453Y+113336X0200Y         S0      
317P1V25_PEX3_R     VIA   -    MD0100PA00X+179322Y+113082X0200Y         S0      
317P1V25_PEX3_R     VIA   -    MD0100PA00X+178437Y+113982X0200Y         S0      
317P1V25_PEX3_R     VIA   -    MD0100PA00X+178532Y+113082X0200Y         S0      
317P1V25_PEX3_R     VIA   -    MD0100PA00X+178792Y+113082X0200Y         S0      
317P1V25_PEX3_R     VIA   -    MD0100PA00X+178187Y+113982X0200Y         S0      
317P1V25_PEX3_R     VIA   -    MD0100PA00X+179052Y+113082X0200Y         S0      
317P1V25_PEX3_R     VIA   -    MD0100PA00X+179322Y+112112X0200Y         S0      
317P1V25_PEX3_R     VIA   -    MD0100PA00X+180660Y+112433X0200Y         S0      
317P1V25_PEX3_R     VIA   -    MD0100PA00X+180390Y+112433X0200Y         S0      
317P1V25_PEX3_R     VIA   -    MD0100PA00X+180130Y+112433X0200Y         S0      
317P1V25_PEX3_R     VIA   -    MD0100PA00X+179870Y+112433X0200Y         S0      
317P1V25_PEX3_R     VIA   -    MD0100PA00X+179831Y+111459X0200Y         S0      
317P1V25_PEX3_R     VIA   -    MD0100PA00X+180091Y+111459X0200Y         S0      
317P1V25_PEX3_R     VIA   -    MD0100PA00X+180351Y+111459X0200Y         S0      
317P1V25_PEX3_R     VIA   -    MD0100PA00X+180621Y+111459X0200Y         S0      
317P1V25_PEX3_R     VIA   -    MD0100PA00X+177537Y+111104X0200Y    R090 S0      
317P1V25_PEX3_R     VIA   -    MD0100PA00X+177797Y+111104X0200Y    R090 S0      
317P1V25_PEX3_R     VIA   -    MD0100PA00X+178317Y+111104X0200Y    R090 S0      
317P1V25_PEX3_R     VIA   -    MD0100PA00X+178057Y+111104X0200Y    R090 S0      
317P1V25_PEX3_R     VIA   -    MD0100PA00X+179052Y+112112X0200Y         S0      
317P1V25_PEX3_R     VIA   -    MD0100PA00X+178792Y+112112X0200Y         S0      
317P1V25_PEX3_R     VIA   -    MD0100PA00X+178532Y+112112X0200Y         S0      
317P1V25_PEX3_R     VIA   -    MD0100PA00X+177546Y+110841X0200Y    R090 S0      
317P1V25_PEX3_R     VIA   -    MD0100PA00X+177806Y+110841X0200Y    R090 S0      
317P1V25_PEX3_R     VIA   -    MD0100PA00X+178326Y+110841X0200Y    R090 S0      
317P1V25_PEX3_R     VIA   -    MD0100PA00X+178066Y+110841X0200Y    R090 S0      
317P1V25_PEX3_R     VIA   -    M      A01X+181035Y+108225X0200Y         S2      
017P1V25_PEX3_R     VIA   -    M      A18X+181035Y+108225X0260Y         S2      
017P1V25_PEX3_R           -    MD0100PA00X+181035Y+108225                       
327P1V25_PEX3_R     R810  -1          A01X+180795Y+108225X0198Y0197R180 S1      
317m2580            VIA   -    M      A01X+039667Y+096829X0200Y    R180 S2      
017m2580            VIA   -    M      A18X+039667Y+096829X0260Y    R180 S2      
017m2580                  -    MD0100PA00X+039667Y+096829                       
327m2580            U96   -13         A01X+039076Y+096314X0090Y0240     S1      
327m2580            R821  -2          A01X+040010Y+097178X0198Y0197     S1      
327m2580            C831  -1   M      A01X+040004Y+096748X0198Y0197R270 S1      
317BB_FRU_A1        VIA   -    M      A01X+113783Y+033623X0200Y         S2      
017BB_FRU_A1        VIA   -    M      A18X+113783Y+033623X0260Y         S2      
017BB_FRU_A1              -    MD0100PA00X+113783Y+033623                       
327BB_FRU_A1        R485  -1          A01X+112058Y+033400X0198Y0197R180 S1      
327BB_FRU_A1        U7    -2          A01X+115091Y+033415X0220Y0680R270 S1      
327BB_FRU_A1        R490  -1   M      A01X+112908Y+033400X0198Y0197R180 S1      
327m2581            U90   -1          A01X+090491Y+109072X0090Y0240R090 S1      
317m2581            VIA   -    M      A01X+090828Y+108348X0200Y         S2      
017m2581            VIA   -    M      A18X+090828Y+108348X0260Y         S2      
017m2581                  -    MD0100PA00X+090828Y+108348                       
327m2581            R780  -1          A01X+091120Y+107666X0198Y0197     S1      
327m2581            R784  -1   M      A01X+091120Y+108066X0198Y0197     S1      
317m2582            VIA   -    M      A01X+181676Y+110114X0200Y         S2      
017m2582            VIA   -    M      A18X+181676Y+110114X0260Y         S2      
017m2582                  -    MD0100PA00X+181676Y+110114                       
327m2582            R809  -2          A01X+181916Y+110114X0198Y0197R180 S1      
327m2582            U95   -4          A01X+181287Y+109711X0090Y0240R090 S1      
327P12V_SSD0_R      PU30  -1          A01X+008326Y+021907X0110Y0240R270 S1      
327P12V_SSD0_R      PU30  -2          A01X+008326Y+021710X0110Y0240R270 S1      
327P12V_SSD0_R      PU30  -3          A01X+008326Y+021513X0110Y0240R270 S1      
327P12V_SSD0_R      PU30  -4          A01X+008326Y+021317X0110Y0240R270 S1      
327P12V_SSD0_R      PU30  -5          A01X+008326Y+021120X0110Y0240R270 S1      
327P12V_SSD0_R      PU76  -6_7        A01X+007953Y+027354X0295Y0354R090 S1      
327P12V_SSD0_R      PC643 -1          A01X+007024Y+027416X0400Y0500R270 S1      
327P12V_SSD0_R      PD86  -C          A01X+005962Y+027104X0670Y0990     S1      
317P12V_SSD0_R      VIA   -    MD0100PA00X+007226Y+027003X0200Y         S0      
317P12V_SSD0_R      VIA   -    MD0100PA00X+006976Y+027003X0200Y         S0      
317P12V_SSD0_R      VIA   -    MD0100PA00X+006976Y+026753X0200Y         S0      
317P12V_SSD0_R      VIA   -    MD0100PA00X+007226Y+026753X0200Y         S0      
317P12V_SSD0_R      VIA   -    MD0100PA00X+006696Y+027003X0200Y         S0      
317P12V_SSD0_R      VIA   -    MD0100PA00X+006696Y+026753X0200Y         S0      
317P12V_SSD0_R      VIA   -    MD0100PA00X+000897Y+025487X0200Y         S0      
317P12V_SSD0_R      VIA   -    MD0100PA00X+005806Y+026418X0200Y         S0      
327P12V_SSD0_R      R5842 -1          A01X+000974Y+025237X0198Y0197     S1      
317P12V_SSD0_R      VIA   -    MD0100PA00X+006056Y+026418X0200Y         S0      
317P12V_SSD0_R      VIA   -    MD0100PA00X+008376Y+016870X0200Y         S0      
327P12V_SSD0_R      R513  -1          A01X+008081Y+016870X0198Y0197R180 S1      
327P12V_SSD0_R      PC356 -1          A01X+007688Y+021661X0198Y0197R090 S1      
327P12V_SSD0_R      PC357 -1          A01X+007066Y+021554X0400Y0500R270 S1      
327P12V_SSD0_R      PD22  -C          A01X+005985Y+021175X0670Y0990     S1      
327P12V_SSD0_R      C202  -1          A01X+007794Y+018426X0198Y0197R090 S1      
327P12V_SSD0_R      R506  -2          A01X+006294Y+018919X1150Y1380R090 S1      
327P12V_SSD0_R      U51   -11         A01X+008443Y+018187X0090Y0240R090 S1      
317P12V_SSD0_R      VIA   -    MD0100PA00X+008052Y+021563X0200Y    R090 S0      
317P12V_SSD0_R      VIA   -    MD0100PA00X+006519Y+021571X0200Y    R090 S0      
317P12V_SSD0_R      VIA   -    MD0100PA00X+008052Y+021313X0200Y    R090 S0      
317P12V_SSD0_R      VIA   -    MD0100PA00X+007682Y+021136X0200Y    R090 S0      
317P12V_SSD0_R      VIA   -    MD0100PA00X+007682Y+021386X0200Y    R090 S0      
317P12V_SSD0_R      VIA   -    MD0100PA00X+007176Y+021170X0200Y         S0      
317P12V_SSD0_R      VIA   -    M      A01X+007206Y+020870X0200Y         S2      
017P12V_SSD0_R      VIA   -    M      A18X+007206Y+020870X0260Y         S2      
017P12V_SSD0_R            -    MD0100PA00X+007206Y+020870                       
317P12V_SSD0_R      VIA   -    MD0100PA00X+005473Y+021048X0200Y    R090 S0      
317P12V_SSD0_R      VIA   -    MD0100PA00X+005473Y+020798X0200Y    R090 S0      
317P12V_SSD0_R      VIA   -    MD0100PA00X+005473Y+021548X0200Y    R090 S0      
317P12V_SSD0_R      VIA   -    MD0100PA00X+005473Y+021298X0200Y    R090 S0      
317P12V_SSD0_R      VIA   -    MD0100PA00X+006519Y+020821X0200Y    R090 S0      
317P12V_SSD0_R      VIA   -    MD0100PA00X+006519Y+021321X0200Y    R090 S0      
317P12V_SSD0_R      VIA   -    MD0100PA00X+006519Y+021071X0200Y    R090 S0      
317P12V_SSD0_R      VIA   -    MD0100PA00X+006926Y+020870X0200Y         S0      
317P12V_SSD0_R      VIA   -    MD0100PA00X+006926Y+021170X0200Y         S0      
317P12V_SSD0_R      VIA   -    MD0100PA00X+007278Y+018422X0200Y         S0      
317P12V_SSD0_R      VIA   -    MD0100PA00X+007540Y+018401X0200Y         S0      
317P12V_SSD0_R      VIA   -    MD0100PA00X+007858Y+018101X0200Y         S0      
317P12V_SSD0_R      VIA   -    MD0100PA00X+007579Y+018137X0200Y         S0      
317P12V_SSD0_R      VIA   -    MD0100PA00X+007258Y+018143X0200Y         S0      
327m2583            U94   -5          A01X+096633Y+109918X0090Y0240R180 S1      
317m2583            VIA   -    M      A01X+096633Y+110433X0200Y         S2      
017m2583            VIA   -    M      A18X+096633Y+110433X0260Y         S2      
017m2583                  -    MD0100PA00X+096633Y+110433                       
327m2583            R797  -2          A01X+097518Y+110466X0198Y0197R180 S1      
327m2584            U90   -5          A01X+090235Y+109918X0090Y0240R180 S1      
317m2584            VIA   -    M      A01X+090235Y+110433X0200Y         S2      
017m2584            VIA   -    M      A18X+090235Y+110433X0260Y         S2      
017m2584                  -    MD0100PA00X+090235Y+110433                       
327m2584            R786  -2          A01X+091120Y+110466X0198Y0197R180 S1      
327m2585            U87   -13         A01X+004975Y+107915X0090Y0240R180 S1      
327m2585            C627  -1          A01X+004551Y+107493X0198Y0197R135 S1      
327m2585            R777  -2          A01X+005015Y+107276X0198Y0197R180 S1      
317m2585            VIA   -           A01X+004731Y+107223X0200Y         S2      
017m2585            VIA   -           A18X+004731Y+107223X0260Y         S2      
017m2585                  -     D0100PA00X+004731Y+107223                       
317m2586            VIA   -    M      A01X+181624Y+108397X0200Y         S2      
017m2586            VIA   -    M      A18X+181624Y+108397X0260Y         S2      
017m2586                  -    MD0100PA00X+181624Y+108397                       
327m2586            R802  -1          A01X+181916Y+107714X0198Y0197     S1      
327m2586            R806  -1   M      A01X+181916Y+108114X0198Y0197     S1      
327m2586            U95   -1          A01X+181287Y+109120X0090Y0240R090 S1      
327m2587            U94   -12         A01X+095786Y+109072X0090Y0240R090 S1      
327m2587            R800  -2          A01X+094897Y+108738X0198Y0197     S1      
327m2587            C633  -2          A01X+095395Y+108616X0198Y0197R135 S1      
317m2587            VIA   -           A01X+095184Y+108807X0200Y         S2      
017m2587            VIA   -           A18X+095184Y+108807X0260Y         S2      
017m2587                  -     D0100PA00X+095184Y+108807                       
327m2588            U94   -13         A01X+096042Y+108816X0090Y0240R180 S1      
327m2588            C633  -1          A01X+095618Y+108393X0198Y0197R135 S1      
327m2588            R799  -2          A01X+096082Y+108176X0198Y0197R180 S1      
317m2588            VIA   -           A01X+095798Y+108123X0200Y         S2      
017m2588            VIA   -           A18X+095798Y+108123X0260Y         S2      
017m2588                  -     D0100PA00X+095798Y+108123                       
327m2589            U90   -4          A01X+090491Y+109662X0090Y0240R090 S1      
317m2589            VIA   -    M      A01X+090880Y+110066X0200Y         S2      
017m2589            VIA   -    M      A18X+090880Y+110066X0260Y         S2      
017m2589                  -    MD0100PA00X+090880Y+110066                       
327m2589            R787  -2          A01X+091120Y+110066X0198Y0197R180 S1      
317m2590            VIA   -    M      A01X+181676Y+109414X0200Y         S2      
017m2590            VIA   -    M      A18X+181676Y+109414X0260Y         S2      
017m2590                  -    MD0100PA00X+181676Y+109414                       
327m2590            U95   -3          A01X+181287Y+109514X0090Y0240R090 S1      
327m2590            R805  -1          A01X+181916Y+109314X0198Y0197     S1      
317m2591            VIA   -    M      A01X+006211Y+109166X0200Y         S2      
017m2591            VIA   -    M      A18X+006211Y+109166X0260Y         S2      
017m2591                  -    MD0100PA00X+006211Y+109166                       
327m2591            R776  -2          A01X+006451Y+109166X0198Y0197R180 S1      
327m2591            U87   -4          A01X+005822Y+108762X0090Y0240R090 S1      
317m2592            VIA   -    M      A01X+006211Y+107966X0200Y         S2      
017m2592            VIA   -    M      A18X+006211Y+107966X0260Y         S2      
017m2592                  -    MD0100PA00X+006211Y+107966                       
327m2592            U87   -2          A01X+005822Y+108368X0090Y0240R090 S1      
327m2592            R769  -1          A01X+006451Y+107566X0198Y0197     S1      
327m2592            R774  -1   M      A01X+006451Y+107966X0198Y0197     S1      
327m2593            U90   -13         A01X+089644Y+108816X0090Y0240R180 S1      
327m2593            C630  -1          A01X+089220Y+108393X0198Y0197R135 S1      
327m2593            R788  -2          A01X+089684Y+108176X0198Y0197R180 S1      
317m2593            VIA   -           A01X+089400Y+108123X0200Y         S2      
017m2593            VIA   -           A18X+089400Y+108123X0260Y         S2      
017m2593                  -     D0100PA00X+089400Y+108123                       
317m2594            VIA   -    M      A01X+181676Y+108914X0200Y         S2      
017m2594            VIA   -    M      A18X+181676Y+108914X0260Y         S2      
017m2594                  -    MD0100PA00X+181676Y+108914                       
327m2594            R803  -1          A01X+181916Y+108514X0198Y0197     S1      
327m2594            R807  -1   M      A01X+181916Y+108914X0198Y0197     S1      
327m2594            U95   -2          A01X+181287Y+109317X0090Y0240R090 S1      
327m2595            R778  -2          A01X+003830Y+107837X0198Y0197     S1      
327m2595            C627  -2          A01X+004329Y+107716X0198Y0197R135 S1      
327m2595            U87   -12         A01X+004720Y+108171X0090Y0240R090 S1      
317m2595            VIA   -           A01X+004117Y+107906X0200Y         S2      
017m2595            VIA   -           A18X+004117Y+107906X0260Y         S2      
017m2595                  -     D0100PA00X+004117Y+107906                       
317m2596            VIA   -    MD0100PA00X+148011Y+094350X0200Y         S0      
327m2596            R6408 -2          A01X+146978Y+093954X0198Y0197     S1      
317m2596            VIA   -    M      A01X+048306Y+066265X0200Y    R270 S2      
017m2596            VIA   -    M      A18X+048306Y+066265X0260Y    R270 S2      
017m2596                  -    MD0100PA00X+048306Y+066265                       
327m2596            R3107 -1          A18X+129642Y+089180X0198Y0197R180 S2      
317m2596            VIA   -    MD0100PA00X+129687Y+089499X0200Y         S0      
317m2596            VIA   -    MD0100PA00X+047945Y+082859X0200Y         S0      
317m2596            VIA   -    MD0100PA00X+128140Y+094026X0200Y         S0      
327m2596            Q124  -G          A18X+127605Y+094026X0240Y0320R090 S2      
327m2596            R4430 -2          A01X+045355Y+064259X0198Y0197     S1      
327m2597            R811  -2          A01X+179295Y+108786X0198Y0197     S1      
327m2597            U95   -12         A01X+180184Y+109120X0090Y0240R090 S1      
327m2597            C828  -2          A01X+179793Y+108665X0198Y0197R135 S1      
317m2597            VIA   -           A01X+179582Y+108855X0200Y         S2      
017m2597            VIA   -           A18X+179582Y+108855X0260Y         S2      
017m2597                  -     D0100PA00X+179582Y+108855                       
327m2598            U90   -2          A01X+090491Y+109268X0090Y0240R090 S1      
317m2598            VIA   -    M      A01X+090880Y+108866X0200Y         S2      
017m2598            VIA   -    M      A18X+090880Y+108866X0260Y         S2      
017m2598                  -    MD0100PA00X+090880Y+108866                       
327m2598            R782  -1          A01X+091120Y+108466X0198Y0197     S1      
327m2598            R785  -1   M      A01X+091120Y+108866X0198Y0197     S1      
327m2599            U90   -3          A01X+090491Y+109465X0090Y0240R090 S1      
317m2599            VIA   -    M      A01X+090880Y+109366X0200Y         S2      
017m2599            VIA   -    M      A18X+090880Y+109366X0260Y         S2      
017m2599                  -    MD0100PA00X+090880Y+109366                       
327m2599            R783  -1          A01X+091120Y+109266X0198Y0197     S1      
327m2600            U94   -2          A01X+096889Y+109268X0090Y0240R090 S1      
317m2600            VIA   -    M      A01X+097278Y+108866X0200Y         S2      
017m2600            VIA   -    M      A18X+097278Y+108866X0260Y         S2      
017m2600                  -    MD0100PA00X+097278Y+108866                       
327m2600            R791  -1          A01X+097518Y+108466X0198Y0197     S1      
327m2600            R796  -1   M      A01X+097518Y+108866X0198Y0197     S1      
327m2601            U94   -1          A01X+096889Y+109072X0090Y0240R090 S1      
317m2601            VIA   -    M      A01X+097226Y+108348X0200Y         S2      
017m2601            VIA   -    M      A18X+097226Y+108348X0260Y         S2      
017m2601                  -    MD0100PA00X+097226Y+108348                       
327m2601            R793  -1          A01X+097518Y+107666X0198Y0197     S1      
327m2601            R794  -1   M      A01X+097518Y+108066X0198Y0197     S1      
317m2602            VIA   -    M      A01X+006211Y+108466X0200Y         S2      
017m2602            VIA   -    M      A18X+006211Y+108466X0260Y         S2      
017m2602                  -    MD0100PA00X+006211Y+108466                       
327m2602            R772  -1          A01X+006451Y+108366X0198Y0197     S1      
327m2602            U87   -3          A01X+005822Y+108565X0090Y0240R090 S1      
327m2603            R775  -2          A01X+036389Y+094348X0198Y0197R180 S1      
317m2603            VIA   -    M      A01X+008059Y+094608X0200Y         S2      
017m2603            VIA   -    M      A18X+008059Y+094608X0260Y         S2      
017m2603                  -    MD0100PA00X+008059Y+094608                       
317m2603            VIA   -    MD0100PA00X+036389Y+094686X0200Y         S0      
327m2603            U87   -5          A01X+005566Y+109018X0090Y0240R180 S1      
317m2604            VIA   -    M      A01X+006159Y+107448X0200Y         S2      
017m2604            VIA   -    M      A18X+006159Y+107448X0260Y         S2      
017m2604                  -    MD0100PA00X+006159Y+107448                       
327m2604            U87   -1          A01X+005822Y+108171X0090Y0240R090 S1      
327m2604            R771  -1          A01X+006451Y+106766X0198Y0197     S1      
327m2604            R773  -1   M      A01X+006451Y+107166X0198Y0197     S1      
317m2605            VIA   -    M      A01X+173775Y+038512X0200Y    R270 S2      
017m2605            VIA   -    M      A18X+173775Y+038512X0260Y    R270 S2      
017m2605                  -    MD0100PA00X+173775Y+038512                       
327m2605            R765  -2          A01X+173775Y+038272X0198Y0197R090 S1      
327m2605            U86   -4          A01X+173371Y+038901X0090Y0240     S1      
327m2606            U90   -12         A01X+089388Y+109072X0090Y0240R090 S1      
327m2606            C630  -2          A01X+088998Y+108616X0198Y0197R135 S1      
327m2606            R789  -2          A01X+088500Y+108738X0198Y0197     S1      
317m2606            VIA   -           A01X+088786Y+108807X0200Y         S2      
017m2606            VIA   -           A18X+088786Y+108807X0260Y         S2      
017m2606                  -     D0100PA00X+088786Y+108807                       
317m2607            VIA   -    M      A01X+143512Y+059080X0200Y    R090 S2      
017m2607            VIA   -    M      A18X+143512Y+059080X0260Y    R090 S2      
017m2607                  -    MD0100PA00X+143512Y+059080                       
327m2607            R753  -2          A01X+143094Y+059965X0198Y0197R270 S1      
327m2607            U85   -5          A01X+143925Y+059080X0090Y0240R270 S1      
327m2608            U94   -3          A01X+096889Y+109465X0090Y0240R090 S1      
317m2608            VIA   -    M      A01X+097278Y+109366X0200Y         S2      
017m2608            VIA   -    M      A18X+097278Y+109366X0260Y         S2      
017m2608                  -    MD0100PA00X+097278Y+109366                       
327m2608            R795  -1          A01X+097518Y+109266X0198Y0197     S1      
317m2609            VIA   -    M      A01X+098669Y+059609X0200Y    R090 S2      
017m2609            VIA   -    M      A18X+098669Y+059609X0260Y    R090 S2      
017m2609                  -    MD0100PA00X+098669Y+059609                       
327m2609            R728  -1          A01X+098586Y+059965X0198Y0197R090 S1      
327m2609            U83   -3          A01X+098669Y+059336X0090Y0240R180 S1      
327m2610            U95   -13         A01X+180440Y+108864X0090Y0240R180 S1      
327m2610            C828  -1          A01X+180016Y+108442X0198Y0197R135 S1      
327m2610            R810  -2          A01X+180480Y+108225X0198Y0197R180 S1      
317m2610            VIA   -           A01X+180196Y+108172X0200Y         S2      
017m2610            VIA   -           A18X+180196Y+108172X0260Y         S2      
017m2610                  -     D0100PA00X+180196Y+108172                       
317NIC6_ADC_A1      VIA   -    M      A01X+145494Y+059673X0200Y    R090 S2      
017NIC6_ADC_A1      VIA   -    M      A18X+145494Y+059673X0260Y    R090 S2      
017NIC6_ADC_A1            -    MD0100PA00X+145494Y+059673                       
327NIC6_ADC_A1      U85   -1          A01X+144771Y+059336X0090Y0240R180 S1      
327NIC6_ADC_A1      R747  -1          A01X+145894Y+059965X0198Y0197R090 S1      
327NIC6_ADC_A1      R751  -1   M      A01X+145494Y+059965X0198Y0197R090 S1      
317m2611            VIA   -    M      A01X+097786Y+059713X0200Y    R090 S2      
017m2611            VIA   -    M      A18X+097786Y+059713X0260Y    R090 S2      
017m2611                  -    MD0100PA00X+097786Y+059713                       
327m2611            U83   -4          A01X+098472Y+059336X0090Y0240R180 S1      
327m2611            R732  -2          A01X+097786Y+059965X0198Y0197R270 S1      
317m2612            VIA   -    M      A01X+099833Y+057899X0200Y    R090 S2      
017m2612            VIA   -    M      A18X+099833Y+057899X0260Y    R090 S2      
017m2612                  -    MD0100PA00X+099833Y+057899                       
327m2612            U83   -13         A01X+099318Y+058490X0090Y0240R270 S1      
327m2612            R733  -2          A01X+100182Y+057556X0198Y0197R270 S1      
327m2612            C615  -1   M      A01X+099752Y+057561X0198Y0197R180 S1      
317NIC4_ADC_A1      VIA   -    M      A01X+099786Y+059673X0200Y    R090 S2      
017NIC4_ADC_A1      VIA   -    M      A18X+099786Y+059673X0260Y    R090 S2      
017NIC4_ADC_A1            -    MD0100PA00X+099786Y+059673                       
327NIC4_ADC_A1      U83   -1          A01X+099062Y+059336X0090Y0240R180 S1      
327NIC4_ADC_A1      R725  -1          A01X+100186Y+059965X0198Y0197R090 S1      
327NIC4_ADC_A1      R729  -1   M      A01X+099786Y+059965X0198Y0197R090 S1      
327NIC6_ADC_A0      R752  -1          A01X+144694Y+059965X0198Y0197R090 S1      
327NIC6_ADC_A0      U85   -2          A01X+144574Y+059336X0090Y0240R180 S1      
327NIC6_ADC_A0      R749  -1   M      A01X+145094Y+059965X0198Y0197R090 S1      
317NIC6_ADC_A0      VIA   -    M      A01X+144899Y+059678X0200Y    R090 S2      
017NIC6_ADC_A0      VIA   -    M      A18X+144899Y+059678X0260Y    R090 S2      
017NIC6_ADC_A0            -    MD0100PA00X+144899Y+059678                       
327NIC6_ADC_A0      R5624 -1          A18X+144511Y+060108X0198Y0197     S2      
317m2613            VIA   -    M      A01X+173075Y+038512X0200Y    R270 S2      
017m2613            VIA   -    M      A18X+173075Y+038512X0260Y    R270 S2      
017m2613                  -    MD0100PA00X+173075Y+038512                       
327m2613            R761  -1          A01X+172975Y+038272X0198Y0197R270 S1      
327m2613            U86   -3          A01X+173174Y+038901X0090Y0240     S1      
317m2614            VIA   -    MD0100PA00X+129426Y+090560X0200Y         S0      
317m2614            VIA   -    M      A01X+050979Y+088193X0200Y         S2      
017m2614            VIA   -    M      A18X+050979Y+088193X0260Y         S2      
017m2614                  -    MD0100PA00X+050979Y+088193                       
317m2614            VIA   -    MD0100PA00X+004843Y+091643X0200Y         S0      
317m2614            VIA   -    MD0100PA00X+006824Y+121205X0200Y         S0      
327m2614            U6    -D2         A01X+131848Y+088814X0160Y         S1      
327m2614            R4435 -1          A18X+006401Y+122265X0198Y0197R090 S2      
317NIC5_ADC_A0      VIA   -    M      A01X+126866Y+038512X0200Y    R270 S2      
017NIC5_ADC_A0      VIA   -    M      A18X+126866Y+038512X0260Y    R270 S2      
017NIC5_ADC_A0            -    MD0100PA00X+126866Y+038512                       
327NIC5_ADC_A0      U84   -2          A01X+127268Y+038901X0090Y0240     S1      
327NIC5_ADC_A0      R737  -1          A01X+126466Y+038272X0198Y0197R270 S1      
327NIC5_ADC_A0      R739  -1   M      A01X+126866Y+038272X0198Y0197R270 S1      
327m2615            U86   -12         A01X+172780Y+040004X0090Y0240     S1      
327m2615            C624  -2          A01X+172325Y+040395X0198Y0197R045 S1      
327m2615            R767  -2          A01X+172446Y+040893X0198Y0197R270 S1      
317m2615            VIA   -           A01X+172515Y+040606X0200Y    R270 S2      
017m2615            VIA   -           A18X+172515Y+040606X0260Y    R270 S2      
017m2615                  -     D0100PA00X+172515Y+040606                       
327P1V25_PEX0_R     PC217 -1          A01X+002864Y+111663X0630Y1190R270 S1      
327P1V25_PEX0_R     PC218 -1          A01X+004362Y+111010X0630Y1190R090 S1      
317P1V25_PEX0_R     VIA   -    MD0100PA00X+002371Y+113870X0200Y         S0      
317P1V25_PEX0_R     VIA   -    MD0100PA00X+002121Y+113870X0200Y         S0      
317P1V25_PEX0_R     VIA   -    MD0100PA00X+005105Y+113369X0200Y         S0      
317P1V25_PEX0_R     VIA   -    MD0100PA00X+004855Y+113369X0200Y         S0      
327P1V25_PEX0_R     PC989 -1          A18X+004970Y+112969X0400Y0500     S2      
327P1V25_PEX0_R     PC988 -1          A18X+004970Y+113769X0400Y0500     S2      
327P1V25_PEX0_R     PC987 -1          A18X+002277Y+114270X0400Y0500R180 S2      
327P1V25_PEX0_R     PC986 -1          A18X+002277Y+113470X0400Y0500R180 S2      
327P1V25_PEX0_R     PC213 -1          A18X+004954Y+111010X0400Y0500     S2      
327P1V25_PEX0_R     PC212 -1          A18X+004954Y+111910X0400Y0500     S2      
327P1V25_PEX0_R     PC215 -1          A18X+002271Y+111663X0400Y0500R180 S2      
327P1V25_PEX0_R     PC214 -1          A18X+002271Y+112563X0400Y0500R180 S2      
327P1V25_PEX0_R     PC216 -1          A01X+005159Y+112492X0198Y0197     S1      
327P1V25_PEX0_R     PL18  -2          A01X+003796Y+113807X1160Y1460R270 S1      
327P1V25_PEX0_R     U87   -11         A01X+004720Y+108368X0090Y0240R090 S1      
327P1V25_PEX0_R     C626  -1          A01X+004070Y+108657X0198Y0197R090 S1      
327P1V25_PEX0_R     R770  -2          A01X+002479Y+109138X1150Y1380R090 S1      
317P1V25_PEX0_R     VIA   -    MD0100PA00X+002197Y+113033X0200Y    R180 S0      
317P1V25_PEX0_R     VIA   -    MD0100PA00X+002467Y+113033X0200Y         S0      
317P1V25_PEX0_R     VIA   -    MD0100PA00X+003966Y+111480X0200Y         S0      
317P1V25_PEX0_R     VIA   -    MD0100PA00X+004226Y+111480X0200Y         S0      
317P1V25_PEX0_R     VIA   -    MD0100PA00X+004486Y+111480X0200Y         S0      
317P1V25_PEX0_R     VIA   -    MD0100PA00X+004756Y+111480X0200Y         S0      
317P1V25_PEX0_R     VIA   -    MD0100PA00X+004858Y+112387X0200Y         S0      
317P1V25_PEX0_R     VIA   -    MD0100PA00X+003257Y+112133X0200Y         S0      
317P1V25_PEX0_R     VIA   -    MD0100PA00X+002987Y+112133X0200Y         S0      
317P1V25_PEX0_R     VIA   -    MD0100PA00X+002727Y+112133X0200Y         S0      
317P1V25_PEX0_R     VIA   -    MD0100PA00X+002467Y+112133X0200Y         S0      
317P1V25_PEX0_R     VIA   -    MD0100PA00X+002467Y+111163X0200Y         S0      
317P1V25_PEX0_R     VIA   -    MD0100PA00X+002727Y+111163X0200Y         S0      
317P1V25_PEX0_R     VIA   -    MD0100PA00X+002987Y+111163X0200Y         S0      
317P1V25_PEX0_R     VIA   -    MD0100PA00X+003257Y+111163X0200Y         S0      
317P1V25_PEX0_R     VIA   -    MD0100PA00X+004756Y+110510X0200Y         S0      
317P1V25_PEX0_R     VIA   -    MD0100PA00X+004486Y+110510X0200Y         S0      
317P1V25_PEX0_R     VIA   -    MD0100PA00X+004226Y+110510X0200Y         S0      
317P1V25_PEX0_R     VIA   -    MD0100PA00X+003966Y+110510X0200Y         S0      
317P1V25_PEX0_R     VIA   -    MD0100PA00X+002132Y+110134X0200Y    R090 S0      
317P1V25_PEX0_R     VIA   -    MD0100PA00X+002652Y+110134X0200Y    R090 S0      
317P1V25_PEX0_R     VIA   -    MD0100PA00X+002912Y+110134X0200Y    R090 S0      
317P1V25_PEX0_R     VIA   -    MD0100PA00X+002392Y+110134X0200Y    R090 S0      
317P1V25_PEX0_R     VIA   -    MD0100PA00X+002392Y+109877X0200Y    R090 S0      
317P1V25_PEX0_R     VIA   -    MD0100PA00X+002912Y+109877X0200Y    R090 S0      
317P1V25_PEX0_R     VIA   -    MD0100PA00X+002652Y+109877X0200Y    R090 S0      
317P1V25_PEX0_R     VIA   -    MD0100PA00X+002132Y+109877X0200Y    R090 S0      
317P1V25_PEX0_R     VIA   -    M      A01X+005570Y+107276X0200Y         S2      
017P1V25_PEX0_R     VIA   -    M      A18X+005570Y+107276X0260Y         S2      
017P1V25_PEX0_R           -    MD0100PA00X+005570Y+107276                       
327P1V25_PEX0_R     R777  -1          A01X+005330Y+107276X0198Y0197R180 S1      
317NIC7_ADC_A0      VIA   -    MD0100PA00X+174175Y+037717X0200Y    R270 S0      
317NIC7_ADC_A0      VIA   -    M      A01X+172575Y+038512X0200Y    R270 S2      
017NIC7_ADC_A0      VIA   -    M      A18X+172575Y+038512X0260Y    R270 S2      
017NIC7_ADC_A0            -    MD0100PA00X+172575Y+038512                       
327NIC7_ADC_A0      R760  -1          A01X+172175Y+038272X0198Y0197R270 S1      
327NIC7_ADC_A0      R763  -1   M      A01X+172575Y+038272X0198Y0197R270 S1      
327NIC7_ADC_A0      U86   -2          A01X+172977Y+038901X0090Y0240     S1      
327NIC7_ADC_A0      R5623 -1          A01X+174175Y+037957X0198Y0197R090 S1      
327P3V3_SCALED      R479  -2          A01X+095278Y+083021X0198Y0197R270 S1      
327P3V3_SCALED      C196  -1   M      A01X+094894Y+083018X0198Y0197R090 S1      
327P3V3_SCALED      R480  -1   M      A01X+094504Y+083018X0198Y0197R090 S1      
327P3V3_SCALED      VIA   -    M      A01X+093882Y+083686X0300Y         S1      
327P3V3_SCALED      U5    -C2         A01X+092389Y+084372X0160Y    R180 S1      
317m2616            VIA   -    M      A01X+128433Y+039157X0200Y    R270 S2      
017m2616            VIA   -    M      A18X+128433Y+039157X0260Y    R270 S2      
017m2616                  -    MD0100PA00X+128433Y+039157                       
327m2616            U84   -5          A01X+127918Y+039157X0090Y0240R090 S1      
327m2616            R742  -2          A01X+128466Y+038272X0198Y0197R090 S1      
327P5V_AUX_SCALED   U5    -B1         A01X+092704Y+084057X0160Y    R180 S1      
317P5V_AUX_SCALED   VIA   -    M      A01X+094010Y+083070X0200Y         S2      
017P5V_AUX_SCALED   VIA   -    M      A18X+094010Y+083070X0260Y         S2      
017P5V_AUX_SCALED         -    MD0100PA00X+094010Y+083070                       
327P5V_AUX_SCALED   R473  -2          A01X+095034Y+082643X0198Y0197R090 S1      
327P5V_AUX_SCALED   R476  -1   M      A01X+093764Y+082663X0198Y0197R270 S1      
327P5V_AUX_SCALED   C193  -1   M      A01X+094154Y+082663X0198Y0197R270 S1      
317NIC4_ADC_A0      VIA   -    M      A01X+099191Y+059678X0200Y    R090 S2      
017NIC4_ADC_A0      VIA   -    M      A18X+099191Y+059678X0260Y    R090 S2      
017NIC4_ADC_A0            -    MD0100PA00X+099191Y+059678                       
327NIC4_ADC_A0      R730  -1          A01X+098986Y+059965X0198Y0197R090 S1      
327NIC4_ADC_A0      R726  -1   M      A01X+099386Y+059965X0198Y0197R090 S1      
327NIC4_ADC_A0      U83   -2          A01X+098866Y+059336X0090Y0240R180 S1      
327m2617            R474  -2          A01X+095448Y+084666X0198Y0197R180 S1      
327m2617            R477  -1   M      A01X+095072Y+084664X0198Y0197R180 S1      
327m2617            VIA   -    M      A01X+093886Y+084458X0300Y         S1      
327m2617            U5    -C1         A01X+092704Y+084372X0160Y    R180 S1      
327m2617            C194  -1   M      A01X+094374Y+084458X0198Y0197R090 S1      
317NIC7_ADC_A1      VIA   -    M      A01X+172057Y+038564X0200Y    R270 S2      
017NIC7_ADC_A1      VIA   -    M      A18X+172057Y+038564X0260Y    R270 S2      
017NIC7_ADC_A1            -    MD0100PA00X+172057Y+038564                       
327NIC7_ADC_A1      R759  -1          A01X+171375Y+038272X0198Y0197R270 S1      
327NIC7_ADC_A1      U86   -1          A01X+172780Y+038901X0090Y0240     S1      
327NIC7_ADC_A1      R762  -1   M      A01X+171775Y+038272X0198Y0197R270 S1      
327P1V25_PEX2_R     PC258 -1          A01X+093930Y+112564X0630Y1190R270 S1      
327P1V25_PEX2_R     PC259 -1          A01X+095429Y+111910X0630Y1190R090 S1      
327P1V25_PEX2_R     U94   -11         A01X+095786Y+109268X0090Y0240R090 S1      
327P1V25_PEX2_R     R799  -1          A01X+096397Y+108176X0198Y0197R180 S1      
317P1V25_PEX2_R     VIA   -    M      A01X+096637Y+108176X0200Y         S2      
017P1V25_PEX2_R     VIA   -    M      A18X+096637Y+108176X0260Y         S2      
017P1V25_PEX2_R           -    MD0100PA00X+096637Y+108176                       
327P1V25_PEX2_R     PL22  -2          A01X+094912Y+114707X1160Y1460R270 S1      
327P1V25_PEX2_R     VIA   -           A18X+095394Y+114784X0260Y         S2      
317P1V25_PEX2_R     VIA   -    MD0100PA00X+095952Y+114517X0200Y         S0      
317P1V25_PEX2_R     VIA   -    MD0100PA00X+093534Y+113934X0200Y         S0      
317P1V25_PEX2_R     VIA   -    MD0100PA00X+093200Y+114771X0200Y         S0      
317P1V25_PEX2_R     VIA   -    MD0100PA00X+093450Y+114771X0200Y         S0      
327P1V25_PEX2_R     PC997 -1          A18X+093356Y+114371X0400Y0500R180 S2      
327P1V25_PEX2_R     PC996 -1          A18X+093356Y+115171X0400Y0500R180 S2      
327P1V25_PEX2_R     PC995 -1          A18X+096068Y+114917X0400Y0500     S2      
327P1V25_PEX2_R     PC994 -1          A18X+096068Y+114117X0400Y0500     S2      
317P1V25_PEX2_R     VIA   -    MD0100PA00X+096202Y+114517X0200Y         S0      
327P1V25_PEX2_R     VIA   -           A18X+095301Y+113408X0260Y         S2      
327P1V25_PEX2_R     PC252 -1          A18X+096021Y+112810X0400Y0500     S2      
327P1V25_PEX2_R     PC254 -1          A18X+093338Y+113464X0400Y0500R180 S2      
327P1V25_PEX2_R     PC253 -1          A18X+096021Y+111910X0400Y0500     S2      
327P1V25_PEX2_R     PC255 -1          A18X+093338Y+112564X0400Y0500R180 S2      
327P1V25_PEX2_R     PC256 -1          A01X+096226Y+113393X0198Y0197     S1      
317P1V25_PEX2_R     VIA   -    MD0100PA00X+096226Y+113643X0200Y    R270 S0      
317P1V25_PEX2_R     VIA   -    MD0100PA00X+095925Y+113287X0200Y         S0      
317P1V25_PEX2_R     VIA   -    MD0100PA00X+095655Y+113287X0200Y         S0      
317P1V25_PEX2_R     VIA   -    MD0100PA00X+093534Y+113034X0200Y         S0      
317P1V25_PEX2_R     VIA   -    MD0100PA00X+093264Y+113934X0200Y    R180 S0      
317P1V25_PEX2_R     VIA   -    MD0100PA00X+094324Y+113034X0200Y         S0      
317P1V25_PEX2_R     VIA   -    MD0100PA00X+094054Y+113034X0200Y         S0      
317P1V25_PEX2_R     VIA   -    MD0100PA00X+093794Y+113034X0200Y         S0      
317P1V25_PEX2_R     VIA   -    MD0100PA00X+095823Y+112380X0200Y         S0      
317P1V25_PEX2_R     VIA   -    MD0100PA00X+095293Y+111410X0200Y         S0      
317P1V25_PEX2_R     VIA   -    MD0100PA00X+095823Y+111410X0200Y         S0      
317P1V25_PEX2_R     VIA   -    MD0100PA00X+095553Y+111410X0200Y         S0      
317P1V25_PEX2_R     VIA   -    MD0100PA00X+095553Y+112380X0200Y         S0      
317P1V25_PEX2_R     VIA   -    MD0100PA00X+095293Y+112380X0200Y         S0      
317P1V25_PEX2_R     VIA   -    MD0100PA00X+095033Y+112380X0200Y         S0      
317P1V25_PEX2_R     VIA   -    MD0100PA00X+095033Y+111410X0200Y         S0      
317P1V25_PEX2_R     VIA   -    MD0100PA00X+093534Y+112064X0200Y         S0      
317P1V25_PEX2_R     VIA   -    MD0100PA00X+093794Y+112064X0200Y         S0      
317P1V25_PEX2_R     VIA   -    MD0100PA00X+094054Y+112064X0200Y         S0      
317P1V25_PEX2_R     VIA   -    MD0100PA00X+094324Y+112064X0200Y         S0      
327P1V25_PEX2_R     C632  -1          A01X+095137Y+109557X0198Y0197R090 S1      
327P1V25_PEX2_R     R792  -2          A01X+093538Y+110011X1150Y1380R090 S1      
327m2618            R744  -2          A01X+126176Y+039708X0198Y0197R090 S1      
327m2618            U84   -13         A01X+126816Y+039748X0090Y0240R090 S1      
327m2618            C618  -1          A01X+126393Y+040172X0198Y0197R045 S1      
317m2618            VIA   -           A01X+126123Y+039992X0200Y    R270 S2      
017m2618            VIA   -           A18X+126123Y+039992X0260Y    R270 S2      
017m2618                  -     D0100PA00X+126123Y+039992                       
317m2619            VIA   -    M      A01X+099291Y+057840X0200Y    R090 S2      
017m2619            VIA   -    M      A18X+099291Y+057840X0260Y    R090 S2      
017m2619                  -    MD0100PA00X+099291Y+057840                       
327m2619            U83   -12         A01X+099062Y+058234X0090Y0240R180 S1      
327m2619            R734  -2          A01X+099437Y+057161X0198Y0197R180 S1      
327m2619            C615  -2   M      A01X+099437Y+057561X0198Y0197R180 S1      
327m2620            VIA   -    M      A18X+092507Y+084203X0260Y         S2      
327m2620            C195  -1   M      A18X+092576Y+083753X0198Y0197R090 S2      
327m2620            R475  -2          A18X+093512Y+083753X0198Y0197R270 S2      
327m2620            R478  -1   M      A18X+093112Y+083753X0198Y0197R090 S2      
317m2620            VIA   -    MD0100PA00X+092231Y+084529X0180Y         S0      
327m2620            U5    -D3         A01X+092074Y+084687X0160Y    R180 S1      
317m2621            VIA   -    M      A01X+092496Y+099432X0200Y         S2      
017m2621            VIA   -    M      A18X+092496Y+099432X0260Y         S2      
017m2621                  -    MD0100PA00X+092496Y+099432                       
317m2621            VIA   -    MD0100PA00X+104530Y+087235X0200Y         S0      
317m2621            VIA   -    MD0100PA00X+097817Y+122127X0200Y         S0      
327m2621            R4437 -1          A18X+097167Y+123163X0198Y0197R090 S2      
317m2621            VIA   -    MD0100PA00X+132950Y+087711X0180Y         S0      
327m2621            U6    -H6         A01X+133108Y+087554X0160Y         S1      
317NIC5_ADC_A1      VIA   -    M      A01X+126348Y+038564X0200Y    R270 S2      
017NIC5_ADC_A1      VIA   -    M      A18X+126348Y+038564X0260Y    R270 S2      
017NIC5_ADC_A1            -    MD0100PA00X+126348Y+038564                       
327NIC5_ADC_A1      R736  -1          A01X+125666Y+038272X0198Y0197R270 S1      
327NIC5_ADC_A1      R741  -1   M      A01X+126066Y+038272X0198Y0197R270 S1      
327NIC5_ADC_A1      U84   -1          A01X+127072Y+038901X0090Y0240     S1      
327m2622            U86   -13         A01X+172524Y+039748X0090Y0240R090 S1      
327m2622            R766  -2          A01X+171885Y+039708X0198Y0197R090 S1      
327m2622            C624  -1          A01X+172102Y+040172X0198Y0197R045 S1      
317m2622            VIA   -           A01X+171832Y+039992X0200Y    R270 S2      
017m2622            VIA   -           A18X+171832Y+039992X0260Y    R270 S2      
017m2622                  -     D0100PA00X+171832Y+039992                       
327m2623            U84   -12         A01X+127072Y+040004X0090Y0240     S1      
327m2623            C618  -2          A01X+126616Y+040395X0198Y0197R045 S1      
327m2623            R745  -2          A01X+126738Y+040893X0198Y0197R270 S1      
317m2623            VIA   -           A01X+126807Y+040606X0200Y    R270 S2      
017m2623            VIA   -           A18X+126807Y+040606X0260Y    R270 S2      
017m2623                  -     D0100PA00X+126807Y+040606                       
317NIC0_ADC_A0      VIA   -    M      A01X+007773Y+059678X0200Y    R090 S2      
017NIC0_ADC_A0      VIA   -    M      A18X+007773Y+059678X0260Y    R090 S2      
017NIC0_ADC_A0            -    MD0100PA00X+007773Y+059678                       
327NIC0_ADC_A0      R686  -1          A01X+007568Y+059965X0198Y0197R090 S1      
327NIC0_ADC_A0      R683  -1   M      A01X+007968Y+059965X0198Y0197R090 S1      
327NIC0_ADC_A0      U79   -2          A01X+007448Y+059336X0090Y0240R180 S1      
317m2624            VIA   -    M      A01X+128066Y+038512X0200Y    R270 S2      
017m2624            VIA   -    M      A18X+128066Y+038512X0260Y    R270 S2      
017m2624                  -    MD0100PA00X+128066Y+038512                       
327m2624            R743  -2          A01X+128066Y+038272X0198Y0197R090 S1      
327m2624            U84   -4          A01X+127662Y+038901X0090Y0240     S1      
317NIC3_ADC_A1      VIA   -    M      A01X+085409Y+039300X0200Y         S2      
017NIC3_ADC_A1      VIA   -    M      A18X+085409Y+039300X0260Y         S2      
017NIC3_ADC_A1            -    MD0100PA00X+085409Y+039300                       
327NIC3_ADC_A1      R718  -1   M      A01X+085409Y+039058X0198Y0197R270 S1      
327NIC3_ADC_A1      R714  -1          A01X+085409Y+038008X0198Y0197R270 S1      
327NIC3_ADC_A1      U82   -1          A01X+085730Y+039701X0090Y0240     S1      
317m2625            VIA   -    M      A01X+144999Y+057840X0200Y    R090 S2      
017m2625            VIA   -    M      A18X+144999Y+057840X0260Y    R090 S2      
017m2625                  -    MD0100PA00X+144999Y+057840                       
327m2625            U85   -12         A01X+144771Y+058234X0090Y0240R180 S1      
327m2625            R756  -2          A01X+145146Y+057161X0198Y0197R180 S1      
327m2625            C621  -2   M      A01X+145146Y+057561X0198Y0197R180 S1      
317m2626            VIA   -    M      A01X+145542Y+057899X0200Y    R090 S2      
017m2626            VIA   -    M      A18X+145542Y+057899X0260Y    R090 S2      
017m2626                  -    MD0100PA00X+145542Y+057899                       
327m2626            U85   -13         A01X+145027Y+058490X0090Y0240R270 S1      
327m2626            C621  -1   M      A01X+145461Y+057561X0198Y0197R180 S1      
327m2626            R755  -2          A01X+145891Y+057556X0198Y0197R270 S1      
317m2627            VIA   -    M      A01X+008416Y+057899X0200Y    R090 S2      
017m2627            VIA   -    M      A18X+008416Y+057899X0260Y    R090 S2      
017m2627                  -    MD0100PA00X+008416Y+057899                       
327m2627            U79   -13         A01X+007901Y+058490X0090Y0240R270 S1      
327m2627            C411  -1   M      A01X+008335Y+057561X0198Y0197R180 S1      
327m2627            R689  -2          A01X+008765Y+057556X0198Y0197R270 S1      
317m2628            VIA   -    M      A01X+097803Y+059080X0200Y    R090 S2      
017m2628            VIA   -    M      A18X+097803Y+059080X0260Y    R090 S2      
017m2628                  -    MD0100PA00X+097803Y+059080                       
327m2628            R731  -2          A01X+097386Y+059965X0198Y0197R270 S1      
327m2628            U83   -5          A01X+098216Y+059080X0090Y0240R270 S1      
327m2629            U80   -12         A01X+035654Y+040004X0090Y0240     S1      
327m2629            C414  -2          A01X+035199Y+040395X0198Y0197R045 S1      
327m2629            R701  -2          A01X+035320Y+040893X0198Y0197R270 S1      
317m2629            VIA   -           A01X+035389Y+040606X0200Y    R270 S2      
017m2629            VIA   -           A18X+035389Y+040606X0260Y    R270 S2      
017m2629                  -     D0100PA00X+035389Y+040606                       
317m2630            VIA   -    M      A01X+127366Y+038512X0200Y    R270 S2      
017m2630            VIA   -    M      A18X+127366Y+038512X0260Y    R270 S2      
017m2630                  -    MD0100PA00X+127366Y+038512                       
327m2630            R740  -1          A01X+127266Y+038272X0198Y0197R270 S1      
327m2630            U84   -3          A01X+127465Y+038901X0090Y0240     S1      
317m2631            VIA   -    M      A01X+054124Y+057899X0200Y    R090 S2      
017m2631            VIA   -    M      A18X+054124Y+057899X0260Y    R090 S2      
017m2631                  -    MD0100PA00X+054124Y+057899                       
327m2631            U81   -13         A01X+053610Y+058490X0090Y0240R270 S1      
327m2631            R711  -2          A01X+054474Y+057556X0198Y0197R270 S1      
327m2631            C417  -1   M      A01X+054044Y+057561X0198Y0197R180 S1      
317m2632            VIA   -    M      A01X+144378Y+059609X0200Y    R090 S2      
017m2632            VIA   -    M      A18X+144378Y+059609X0260Y    R090 S2      
017m2632                  -    MD0100PA00X+144378Y+059609                       
327m2632            R750  -1          A01X+144294Y+059965X0198Y0197R090 S1      
327m2632            U85   -3          A01X+144378Y+059336X0090Y0240R180 S1      
327P12V_NIC5_R      PU25  -1          A01X+130348Y+039554X0110Y0240R180 S1      
327P12V_NIC5_R      PU25  -2          A01X+130151Y+039554X0110Y0240R180 S1      
327P12V_NIC5_R      PU25  -3          A01X+129954Y+039554X0110Y0240R180 S1      
327P12V_NIC5_R      PU25  -4          A01X+129757Y+039554X0110Y0240R180 S1      
327P12V_NIC5_R      PU25  -5          A01X+129560Y+039554X0110Y0240R180 S1      
327P12V_NIC5_R      PU104 -13         A01X+133233Y+044601X0100Y0320R090 S1      
327P12V_NIC5_R      PU104 -14         A01X+133233Y+044404X0100Y0320R090 S1      
327P12V_NIC5_R      PR7025-1          A01X+131534Y+044546X0198Y0197R090 S1      
327P12V_NIC5_R      PU104 -15         A01X+133233Y+044207X0100Y0320R090 S1      
327P12V_NIC5_R      PU104 -16         A01X+133233Y+044010X0100Y0320R090 S1      
327P12V_NIC5_R      PU104 -17         A01X+133233Y+043813X0100Y0320R090 S1      
327P12V_NIC5_R      PU104 -18         A01X+133233Y+043616X0100Y0320R090 S1      
327P12V_NIC5_R      PU104 -19         A01X+133233Y+043420X0100Y0320R090 S1      
327P12V_NIC5_R      PU104 -20         A01X+133233Y+043223X0100Y0320R090 S1      
327P12V_NIC5_R      PC807 -1          A01X+132602Y+043241X0198Y0197R270 S1      
327P12V_NIC5_R      PD95  -C          A01X+130475Y+043746X0670Y0990     S1      
327P12V_NIC5_R      PC804 -1          A01X+129409Y+044100X0400Y0500R270 S1      
327P12V_NIC5_R      PC805 -1          A01X+128609Y+044100X0400Y0500R270 S1      
327P12V_NIC5_R      PC323 -1          A01X+127622Y+043440X0400Y0500R270 S1      
327P12V_NIC5_R      PD11  -C          A01X+129616Y+041895X0670Y0990R270 S1      
327P12V_NIC5_R      R738  -2          A01X+127938Y+042244X1150Y1380     S1      
327P12V_NIC5_R      PC322 -1          A01X+130101Y+040192X0198Y0197     S1      
327P12V_NIC5_R      PC806 -1          A01X+129994Y+040814X0400Y0500R180 S1      
327P12V_NIC5_R      C617  -1          A01X+127557Y+040653X0198Y0197     S1      
327P12V_NIC5_R      U84   -11         A01X+127268Y+040004X0090Y0240     S1      
317P12V_NIC5_R      VIA   -    MD0100PA00X+132630Y+044372X0200Y    R270 S0      
317P12V_NIC5_R      VIA   -    MD0100PA00X+132910Y+044372X0200Y    R270 S0      
317P12V_NIC5_R      VIA   -    MD0100PA00X+130975Y+044389X0200Y    R270 S0      
317P12V_NIC5_R      VIA   -    MD0100PA00X+129976Y+044389X0200Y    R270 S0      
317P12V_NIC5_R      VIA   -    MD0100PA00X+132630Y+044092X0200Y    R270 S0      
317P12V_NIC5_R      VIA   -    MD0100PA00X+132910Y+044092X0200Y    R270 S0      
317P12V_NIC5_R      VIA   -    MD0100PA00X+132630Y+043812X0200Y    R270 S0      
317P12V_NIC5_R      VIA   -    MD0100PA00X+132630Y+043532X0200Y    R270 S0      
317P12V_NIC5_R      VIA   -    MD0100PA00X+132910Y+043812X0200Y    R270 S0      
317P12V_NIC5_R      VIA   -    MD0100PA00X+132910Y+043532X0200Y    R270 S0      
317P12V_NIC5_R      VIA   -    MD0100PA00X+130975Y+044109X0200Y    R270 S0      
317P12V_NIC5_R      VIA   -    MD0100PA00X+130975Y+043829X0200Y    R270 S0      
317P12V_NIC5_R      VIA   -    MD0100PA00X+129009Y+043932X0200Y    R270 S0      
317P12V_NIC5_R      VIA   -    MD0100PA00X+129009Y+044212X0200Y    R270 S0      
317P12V_NIC5_R      VIA   -    MD0100PA00X+129976Y+044109X0200Y    R270 S0      
317P12V_NIC5_R      VIA   -    MD0100PA00X+129976Y+043829X0200Y    R270 S0      
317P12V_NIC5_R      VIA   -    MD0100PA00X+127183Y+042669X0200Y         S0      
317P12V_NIC5_R      VIA   -    MD0100PA00X+128209Y+043932X0200Y    R270 S0      
317P12V_NIC5_R      VIA   -    MD0100PA00X+128209Y+044212X0200Y    R270 S0      
317P12V_NIC5_R      VIA   -    MD0100PA00X+127222Y+043552X0200Y    R270 S0      
317P12V_NIC5_R      VIA   -    MD0100PA00X+127222Y+043272X0200Y    R270 S0      
317P12V_NIC5_R      VIA   -    MD0100PA00X+129738Y+042407X0200Y         S0      
317P12V_NIC5_R      VIA   -    MD0100PA00X+129988Y+042407X0200Y         S0      
317P12V_NIC5_R      VIA   -    MD0100PA00X+129488Y+042407X0200Y         S0      
317P12V_NIC5_R      VIA   -    MD0100PA00X+129238Y+042407X0200Y         S0      
317P12V_NIC5_R      VIA   -    MD0100PA00X+129762Y+041361X0200Y         S0      
317P12V_NIC5_R      VIA   -    MD0100PA00X+130012Y+041361X0200Y         S0      
317P12V_NIC5_R      VIA   -    MD0100PA00X+129512Y+041361X0200Y         S0      
317P12V_NIC5_R      VIA   -    MD0100PA00X+129262Y+041361X0200Y         S0      
317P12V_NIC5_R      VIA   -    MD0100PA00X+127183Y+042409X0200Y         S0      
317P12V_NIC5_R      VIA   -    MD0100PA00X+127183Y+041889X0200Y         S0      
317P12V_NIC5_R      VIA   -    MD0100PA00X+127183Y+042149X0200Y         S0      
317P12V_NIC5_R      VIA   -    MD0100PA00X+127183Y+041629X0200Y         S0      
317P12V_NIC5_R      VIA   -    MD0100PA00X+127183Y+041109X0200Y         S0      
317P12V_NIC5_R      VIA   -    MD0100PA00X+127183Y+041369X0200Y         S0      
317P12V_NIC5_R      VIA   -    MD0100PA00X+129754Y+039828X0200Y         S0      
317P12V_NIC5_R      VIA   -    MD0100PA00X+130004Y+039828X0200Y         S0      
317P12V_NIC5_R      VIA   -    MD0100PA00X+129826Y+040198X0200Y         S0      
317P12V_NIC5_R      VIA   -    MD0100PA00X+129576Y+040198X0200Y         S0      
317P12V_NIC5_R      VIA   -    MD0100PA00X+129610Y+040704X0200Y    R270 S0      
317P12V_NIC5_R      VIA   -    M      A01X+129310Y+040674X0200Y    R270 S2      
017P12V_NIC5_R      VIA   -    M      A18X+129310Y+040674X0260Y    R270 S2      
017P12V_NIC5_R            -    MD0100PA00X+129310Y+040674                       
317P12V_NIC5_R      VIA   -    MD0100PA00X+129610Y+040954X0200Y    R270 S0      
317P12V_NIC5_R      VIA   -    MD0100PA00X+129310Y+040954X0200Y    R270 S0      
317P12V_NIC5_R      VIA   -    MD0100PA00X+127183Y+040849X0200Y         S0      
317P12V_NIC5_R      VIA   -    MD0100PA00X+127183Y+040589X0200Y    R270 S0      
317P12V_NIC5_R      VIA   -    MD0100PA00X+127242Y+040330X0200Y    R270 S0      
317P12V_NIC5_R      VIA   -    MD0100PA00X+126176Y+039153X0200Y    R270 S0      
327P12V_NIC5_R      R744  -1          A01X+126176Y+039393X0198Y0197R090 S1      
327P12V_NIC5_R      PR7026-2          A01X+133227Y+046310X0198Y0197R180 S1      
317m2633            VIA   -    M      A01X+006368Y+059713X0200Y    R090 S2      
017m2633            VIA   -    M      A18X+006368Y+059713X0260Y    R090 S2      
017m2633                  -    MD0100PA00X+006368Y+059713                       
327m2633            U79   -4          A01X+007055Y+059336X0090Y0240R180 S1      
327m2633            R688  -2          A01X+006368Y+059965X0198Y0197R270 S1      
317m2634            VIA   -    M      A01X+052094Y+059080X0200Y    R090 S2      
017m2634            VIA   -    M      A18X+052094Y+059080X0260Y    R090 S2      
017m2634                  -    MD0100PA00X+052094Y+059080                       
327m2634            R709  -2          A01X+051677Y+059965X0198Y0197R270 S1      
327m2634            U81   -5          A01X+052507Y+059080X0090Y0240R270 S1      
317m2635            VIA   -    M      A01X+007252Y+059609X0200Y    R090 S2      
017m2635            VIA   -    M      A18X+007252Y+059609X0260Y    R090 S2      
017m2635                  -    MD0100PA00X+007252Y+059609                       
327m2635            R684  -1          A01X+007168Y+059965X0198Y0197R090 S1      
327m2635            U79   -3          A01X+007252Y+059336X0090Y0240R180 S1      
317m2636            VIA   -    M      A01X+007873Y+057840X0200Y    R090 S2      
017m2636            VIA   -    M      A18X+007873Y+057840X0260Y    R090 S2      
017m2636                  -    MD0100PA00X+007873Y+057840                       
327m2636            U79   -12         A01X+007645Y+058234X0090Y0240R180 S1      
327m2636            R690  -2          A01X+008020Y+057161X0198Y0197R180 S1      
327m2636            C411  -2   M      A01X+008020Y+057561X0198Y0197R180 S1      
317NIC0_ADC_A1      VIA   -    M      A01X+008368Y+059673X0200Y    R090 S2      
017NIC0_ADC_A1      VIA   -    M      A18X+008368Y+059673X0260Y    R090 S2      
017NIC0_ADC_A1            -    MD0100PA00X+008368Y+059673                       
327NIC0_ADC_A1      R681  -1          A01X+008768Y+059965X0198Y0197R090 S1      
327NIC0_ADC_A1      R685  -1   M      A01X+008368Y+059965X0198Y0197R090 S1      
327NIC0_ADC_A1      U79   -1          A01X+007645Y+059336X0090Y0240R180 S1      
317m2637            VIA   -    M      A01X+052960Y+059609X0200Y    R090 S2      
017m2637            VIA   -    M      A18X+052960Y+059609X0260Y    R090 S2      
017m2637                  -    MD0100PA00X+052960Y+059609                       
327m2637            R706  -1          A01X+052877Y+059965X0198Y0197R090 S1      
327m2637            U81   -3          A01X+052960Y+059336X0090Y0240R180 S1      
317m2638            VIA   -    M      A01X+086759Y+039300X0200Y         S2      
017m2638            VIA   -    M      A18X+086759Y+039300X0260Y         S2      
017m2638                  -    MD0100PA00X+086759Y+039300                       
327m2638            U82   -4          A01X+086320Y+039701X0090Y0240     S1      
327m2638            R721  -2          A01X+086759Y+039058X0198Y0197R090 S1      
317NIC1_ADC_A0      VIA   -    M      A01X+035449Y+038512X0200Y    R270 S2      
017NIC1_ADC_A0      VIA   -    M      A18X+035449Y+038512X0260Y    R270 S2      
017NIC1_ADC_A0            -    MD0100PA00X+035449Y+038512                       
327NIC1_ADC_A0      R694  -1          A01X+035049Y+038272X0198Y0197R270 S1      
327NIC1_ADC_A0      R697  -1   M      A01X+035449Y+038272X0198Y0197R270 S1      
327NIC1_ADC_A0      U80   -2          A01X+035851Y+038901X0090Y0240     S1      
327P12V_NIC4_R      PU23  -1          A01X+096431Y+053452X0110Y0240R090 S1      
327P12V_NIC4_R      PU23  -2          A01X+096431Y+053649X0110Y0240R090 S1      
327P12V_NIC4_R      PU23  -3          A01X+096431Y+053846X0110Y0240R090 S1      
327P12V_NIC4_R      PU23  -4          A01X+096431Y+054042X0110Y0240R090 S1      
327P12V_NIC4_R      PU23  -5          A01X+096431Y+054239X0110Y0240R090 S1      
327P12V_NIC4_R      PC803 -1          A01X+097129Y+060831X0198Y0197     S1      
327P12V_NIC4_R      PU103 -16         A01X+096336Y+061380X0100Y0320R180 S1      
327P12V_NIC4_R      PU103 -17         A01X+096533Y+061380X0100Y0320R180 S1      
327P12V_NIC4_R      PU103 -18         A01X+096730Y+061380X0100Y0320R180 S1      
327P12V_NIC4_R      PU103 -19         A01X+096927Y+061380X0100Y0320R180 S1      
327P12V_NIC4_R      PU103 -20         A01X+097124Y+061380X0100Y0320R180 S1      
327P12V_NIC4_R      PU103 -13         A01X+095746Y+061380X0100Y0320R180 S1      
327P12V_NIC4_R      PU103 -14         A01X+095943Y+061380X0100Y0320R180 S1      
327P12V_NIC4_R      PU103 -15         A01X+096140Y+061380X0100Y0320R180 S1      
327P12V_NIC4_R      PR7020-1          A01X+095785Y+059739X0198Y0197R180 S1      
327P12V_NIC4_R      C422  -1          A01X+098627Y+057584X0198Y0197R180 S1      
327P12V_NIC4_R      U83   -11         A01X+098866Y+058234X0090Y0240R180 S1      
327P12V_NIC4_R      PD94  -C          A01X+096201Y+058611X0670Y0990R090 S1      
327P12V_NIC4_R      PC802 -1          A01X+095913Y+057519X0400Y0500     S1      
327P12V_NIC4_R      PC801 -1          A01X+095913Y+055919X0400Y0500     S1      
327P12V_NIC4_R      PC800 -1          A01X+095913Y+056719X0400Y0500     S1      
327P12V_NIC4_R      R727  -2          A01X+098133Y+056085X1150Y1380R180 S1      
327P12V_NIC4_R      PD7   -C          A01X+098772Y+054184X0670Y0990R180 S1      
327P12V_NIC4_R      PC309 -1          A01X+097069Y+053698X0198Y0197R270 S1      
327P12V_NIC4_R      PC310 -1          A01X+097691Y+053806X0400Y0500R090 S1      
317P12V_NIC4_R      VIA   -    MD0100PA00X+096814Y+060776X0200Y         S0      
317P12V_NIC4_R      VIA   -    MD0100PA00X+096534Y+061056X0200Y         S0      
317P12V_NIC4_R      VIA   -    MD0100PA00X+096534Y+060776X0200Y         S0      
317P12V_NIC4_R      VIA   -    MD0100PA00X+096814Y+061056X0200Y         S0      
317P12V_NIC4_R      VIA   -    MD0100PA00X+096254Y+061056X0200Y         S0      
317P12V_NIC4_R      VIA   -    MD0100PA00X+095974Y+061056X0200Y         S0      
317P12V_NIC4_R      VIA   -    MD0100PA00X+095974Y+060776X0200Y         S0      
317P12V_NIC4_R      VIA   -    MD0100PA00X+096254Y+060776X0200Y         S0      
317P12V_NIC4_R      VIA   -    MD0100PA00X+096517Y+059122X0200Y         S0      
317P12V_NIC4_R      VIA   -    MD0100PA00X+096237Y+059122X0200Y         S0      
317P12V_NIC4_R      VIA   -    MD0100PA00X+095957Y+059122X0200Y         S0      
317P12V_NIC4_R      VIA   -    MD0100PA00X+098651Y+057330X0200Y    R090 S0      
317P12V_NIC4_R      VIA   -    MD0100PA00X+098916Y+057369X0200Y    R090 S0      
317P12V_NIC4_R      VIA   -    MD0100PA00X+098951Y+057648X0200Y    R090 S0      
327P12V_NIC4_R      R733  -1          A01X+100182Y+057871X0198Y0197R270 S1      
317P12V_NIC4_R      VIA   -    MD0100PA00X+100182Y+058166X0200Y    R090 S0      
317P12V_NIC4_R      VIA   -    MD0100PA00X+096517Y+058122X0200Y         S0      
317P12V_NIC4_R      VIA   -    MD0100PA00X+096237Y+058122X0200Y         S0      
317P12V_NIC4_R      VIA   -    MD0100PA00X+095957Y+058122X0200Y         S0      
317P12V_NIC4_R      VIA   -    MD0100PA00X+098910Y+057048X0200Y    R090 S0      
317P12V_NIC4_R      VIA   -    MD0100PA00X+098630Y+057069X0200Y    R090 S0      
317P12V_NIC4_R      VIA   -    MD0100PA00X+095802Y+057119X0200Y         S0      
317P12V_NIC4_R      VIA   -    MD0100PA00X+096082Y+057119X0200Y         S0      
317P12V_NIC4_R      VIA   -    MD0100PA00X+096082Y+056319X0200Y         S0      
317P12V_NIC4_R      VIA   -    MD0100PA00X+095802Y+056319X0200Y         S0      
317P12V_NIC4_R      VIA   -    MD0100PA00X+098238Y+054038X0200Y    R270 S0      
317P12V_NIC4_R      VIA   -    MD0100PA00X+098238Y+054538X0200Y    R270 S0      
317P12V_NIC4_R      VIA   -    MD0100PA00X+098238Y+054288X0200Y    R270 S0      
317P12V_NIC4_R      VIA   -    MD0100PA00X+098489Y+054837X0200Y         S0      
317P12V_NIC4_R      VIA   -    MD0100PA00X+098239Y+054837X0200Y         S0      
317P12V_NIC4_R      VIA   -    MD0100PA00X+098739Y+054837X0200Y         S0      
317P12V_NIC4_R      VIA   -    M      A01X+097830Y+054490X0200Y    R180 S2      
017P12V_NIC4_R      VIA   -    M      A18X+097830Y+054490X0260Y    R180 S2      
017P12V_NIC4_R            -    MD0100PA00X+097830Y+054490                       
317P12V_NIC4_R      VIA   -    MD0100PA00X+097550Y+054490X0200Y    R180 S0      
317P12V_NIC4_R      VIA   -    MD0100PA00X+096704Y+054046X0200Y    R270 S0      
317P12V_NIC4_R      VIA   -    MD0100PA00X+097580Y+054190X0200Y    R180 S0      
317P12V_NIC4_R      VIA   -    MD0100PA00X+097830Y+054190X0200Y    R180 S0      
317P12V_NIC4_R      VIA   -    MD0100PA00X+097074Y+054223X0200Y    R270 S0      
317P12V_NIC4_R      VIA   -    MD0100PA00X+096082Y+055519X0200Y         S0      
317P12V_NIC4_R      VIA   -    MD0100PA00X+095802Y+055519X0200Y         S0      
317P12V_NIC4_R      VIA   -    MD0100PA00X+098238Y+053788X0200Y    R270 S0      
317P12V_NIC4_R      VIA   -    MD0100PA00X+098989Y+054837X0200Y         S0      
317P12V_NIC4_R      VIA   -    MD0100PA00X+096704Y+053766X0200Y    R270 S0      
317P12V_NIC4_R      VIA   -    MD0100PA00X+097074Y+053973X0200Y    R270 S0      
327P12V_NIC4_R      PR7021-2          A01X+094036Y+061374X0198Y0197R270 S1      
317NIC2_ADC_A1      VIA   -    M      A01X+054077Y+059673X0200Y    R090 S2      
017NIC2_ADC_A1      VIA   -    M      A18X+054077Y+059673X0260Y    R090 S2      
017NIC2_ADC_A1            -    MD0100PA00X+054077Y+059673                       
327NIC2_ADC_A1      U81   -1          A01X+053354Y+059336X0090Y0240R180 S1      
327NIC2_ADC_A1      R705  -1          A01X+054477Y+059965X0198Y0197R090 S1      
327NIC2_ADC_A1      R707  -1   M      A01X+054077Y+059965X0198Y0197R090 S1      
317m2639            VIA   -    M      A01X+086124Y+039400X0200Y         S2      
017m2639            VIA   -    M      A18X+086124Y+039400X0260Y         S2      
017m2639                  -    MD0100PA00X+086124Y+039400                       
327m2639            U82   -3          A01X+086124Y+039701X0090Y0240     S1      
327m2639            R717  -1          A01X+086309Y+039058X0198Y0197R270 S1      
327m2640            R687  -2          A01X+037093Y+036429X0198Y0197R270 S1      
317m2640            VIA   -    MD0100PA00X+005968Y+060544X0200Y    R090 S0      
317m2640            VIA   -    MD0100PA00X+037142Y+035382X0200Y         S0      
317m2640            VIA   -    MD0100PA00X+009826Y+037451X0200Y         S0      
317m2640            VIA   -    M      A01X+006386Y+059080X0200Y    R090 S2      
017m2640            VIA   -    M      A18X+006386Y+059080X0260Y    R090 S2      
017m2640                  -    MD0100PA00X+006386Y+059080                       
327m2640            U79   -5          A01X+006799Y+059080X0090Y0240R270 S1      
317P1V8_PEX_R       VIA   -    MD0100PA00X+039400Y+097178X0200Y    R180 S0      
327P1V8_PEX_R       R821  -1          A01X+039694Y+097178X0198Y0197     S1      
327P1V8_PEX_R       PC1003-1          A18X+041312Y+093078X0400Y0500R090 S2      
327P1V8_PEX_R       PC1002-1          A18X+042112Y+093078X0400Y0500R090 S2      
327P1V8_PEX_R       PC1004-1          A18X+040512Y+093078X0400Y0500R090 S2      
327P1V8_PEX_R       PC1005-1          A18X+039712Y+093078X0400Y0500R090 S2      
317P1V8_PEX_R       VIA   -    MD0100PA00X+042512Y+093219X0200Y         S0      
317P1V8_PEX_R       VIA   -    MD0100PA00X+041712Y+093219X0200Y         S0      
317P1V8_PEX_R       VIA   -    MD0100PA00X+040912Y+093219X0200Y         S0      
317P1V8_PEX_R       VIA   -    MD0100PA00X+040112Y+093219X0200Y         S0      
327P1V8_PEX_R       R815  -2          A01X+041481Y+095129X1150Y1380R270 S1      
327P1V8_PEX_R       C830  -1          A01X+039982Y+095622X0198Y0197R270 S1      
317P1V8_PEX_R       VIA   -    MD0100PA00X+039917Y+095947X0200Y    R180 S0      
317P1V8_PEX_R       VIA   -    MD0100PA00X+040197Y+095911X0200Y    R180 S0      
317P1V8_PEX_R       VIA   -    MD0100PA00X+040235Y+095646X0200Y    R180 S0      
317P1V8_PEX_R       VIA   -    MD0100PA00X+040497Y+095626X0200Y    R180 S0      
317P1V8_PEX_R       VIA   -    M      A01X+040518Y+095905X0200Y    R180 S2      
017P1V8_PEX_R       VIA   -    M      A18X+040518Y+095905X0260Y    R180 S2      
017P1V8_PEX_R             -    MD0100PA00X+040518Y+095905                       
327P1V8_PEX_R       U96   -11         A01X+039332Y+095861X0090Y0240R270 S1      
327P1V8_PEX_R       PC290 -1          A01X+039161Y+093308X0198Y0197R090 S1      
317P1V8_PEX_R       VIA   -    MD0100PA00X+039161Y+093068X0200Y    R180 S0      
327P1V8_PEX_R       PC1006-1          A01X+043964Y+092185X0950Y1110R270 S1      
327P1V8_PEX_R       PC293 -1          A01X+041312Y+093078X0400Y0500R270 S1      
327P1V8_PEX_R       PC292 -1          A01X+042112Y+093078X0400Y0500R270 S1      
317P1V8_PEX_R       VIA   -    MD0100PA00X+042512Y+092969X0200Y         S0      
317P1V8_PEX_R       VIA   -    MD0100PA00X+041712Y+092969X0200Y         S0      
327P1V8_PEX_R       PC291 -1          A01X+040512Y+093078X0400Y0500R270 S1      
327P1V8_PEX_R       PC294 -1          A01X+039712Y+093078X0400Y0500R270 S1      
327P1V8_PEX_R       PL26  -2          A01X+041275Y+092172X0848Y1300R090 S1      
317P1V8_PEX_R       VIA   -    MD0100PA00X+040912Y+092969X0200Y         S0      
317P1V8_PEX_R       VIA   -    MD0100PA00X+040112Y+092969X0200Y         S0      
327P1V8_PEX_R       PJ17  -2          A01X+038963Y+088176X0280Y0320     S1      
317m2641            VIA   -    M      A01X+037016Y+039157X0200Y    R270 S2      
017m2641            VIA   -    M      A18X+037016Y+039157X0260Y    R270 S2      
017m2641                  -    MD0100PA00X+037016Y+039157                       
327m2641            R698  -2          A01X+037049Y+038272X0198Y0197R090 S1      
327m2641            U80   -5          A01X+036501Y+039157X0090Y0240R090 S1      
327P12V_NIC0_R      PU22  -1          A01X+005014Y+053452X0110Y0240R090 S1      
327P12V_NIC0_R      PU22  -3          A01X+005014Y+053846X0110Y0240R090 S1      
327P12V_NIC0_R      PU22  -4          A01X+005014Y+054042X0110Y0240R090 S1      
327P12V_NIC0_R      PU22  -5          A01X+005014Y+054239X0110Y0240R090 S1      
327P12V_NIC0_R      PU22  -2          A01X+005014Y+053649X0110Y0240R090 S1      
327P12V_NIC0_R      PU71  -18         A01X+005313Y+061380X0100Y0320R180 S1      
327P12V_NIC0_R      PU71  -19         A01X+005510Y+061380X0100Y0320R180 S1      
327P12V_NIC0_R      PU71  -20         A01X+005707Y+061380X0100Y0320R180 S1      
327P12V_NIC0_R      PC603 -1          A01X+005712Y+060831X0198Y0197     S1      
327P12V_NIC0_R      PU71  -13         A01X+004329Y+061380X0100Y0320R180 S1      
327P12V_NIC0_R      PU71  -14         A01X+004526Y+061380X0100Y0320R180 S1      
327P12V_NIC0_R      PU71  -15         A01X+004722Y+061380X0100Y0320R180 S1      
327P12V_NIC0_R      PU71  -16         A01X+004919Y+061380X0100Y0320R180 S1      
327P12V_NIC0_R      PU71  -17         A01X+005116Y+061380X0100Y0320R180 S1      
327P12V_NIC0_R      PR6861-1          A01X+004367Y+059739X0198Y0197R180 S1      
327P12V_NIC0_R      C410  -1          A01X+007209Y+057584X0198Y0197R180 S1      
327P12V_NIC0_R      U79   -11         A01X+007448Y+058234X0090Y0240R180 S1      
327P12V_NIC0_R      PD78  -C          A01X+004783Y+058611X0670Y0990R090 S1      
327P12V_NIC0_R      PC600 -1          A01X+004496Y+057519X0400Y0500     S1      
327P12V_NIC0_R      PC602 -1          A01X+004496Y+056719X0400Y0500     S1      
327P12V_NIC0_R      PC601 -1          A01X+004496Y+055919X0400Y0500     S1      
327P12V_NIC0_R      R682  -2          A01X+006716Y+056085X1150Y1380R180 S1      
327P12V_NIC0_R      PD6   -C          A01X+007354Y+054184X0670Y0990R180 S1      
327P12V_NIC0_R      PC308 -1          A01X+005651Y+053698X0198Y0197R270 S1      
327P12V_NIC0_R      PC311 -1          A01X+006273Y+053806X0400Y0500R090 S1      
317P12V_NIC0_R      VIA   -    MD0100PA00X+008679Y+058166X0200Y    R090 S0      
327P12V_NIC0_R      R689  -1          A01X+008765Y+057871X0198Y0197R270 S1      
317P12V_NIC0_R      VIA   -    MD0100PA00X+005397Y+061056X0200Y         S0      
317P12V_NIC0_R      VIA   -    MD0100PA00X+005397Y+060776X0200Y         S0      
317P12V_NIC0_R      VIA   -    MD0100PA00X+005117Y+061056X0200Y         S0      
317P12V_NIC0_R      VIA   -    MD0100PA00X+004837Y+061056X0200Y         S0      
317P12V_NIC0_R      VIA   -    MD0100PA00X+004557Y+061056X0200Y         S0      
317P12V_NIC0_R      VIA   -    MD0100PA00X+004557Y+060776X0200Y         S0      
317P12V_NIC0_R      VIA   -    MD0100PA00X+004837Y+060776X0200Y         S0      
317P12V_NIC0_R      VIA   -    MD0100PA00X+005117Y+060776X0200Y         S0      
317P12V_NIC0_R      VIA   -    MD0100PA00X+004820Y+059122X0200Y         S0      
317P12V_NIC0_R      VIA   -    MD0100PA00X+004540Y+059122X0200Y         S0      
317P12V_NIC0_R      VIA   -    MD0100PA00X+005100Y+059122X0200Y         S0      
317P12V_NIC0_R      VIA   -    MD0100PA00X+007234Y+057330X0200Y    R090 S0      
317P12V_NIC0_R      VIA   -    MD0100PA00X+007498Y+057369X0200Y    R090 S0      
317P12V_NIC0_R      VIA   -    MD0100PA00X+007534Y+057648X0200Y    R090 S0      
317P12V_NIC0_R      VIA   -    MD0100PA00X+004820Y+058122X0200Y         S0      
317P12V_NIC0_R      VIA   -    MD0100PA00X+004540Y+058122X0200Y         S0      
317P12V_NIC0_R      VIA   -    MD0100PA00X+005100Y+058122X0200Y         S0      
317P12V_NIC0_R      VIA   -    MD0100PA00X+007492Y+057048X0200Y    R090 S0      
317P12V_NIC0_R      VIA   -    MD0100PA00X+007213Y+057069X0200Y    R090 S0      
317P12V_NIC0_R      VIA   -    MD0100PA00X+004664Y+056319X0200Y         S0      
317P12V_NIC0_R      VIA   -    MD0100PA00X+004384Y+056319X0200Y         S0      
317P12V_NIC0_R      VIA   -    MD0100PA00X+004384Y+057119X0200Y         S0      
317P12V_NIC0_R      VIA   -    MD0100PA00X+004664Y+057119X0200Y         S0      
317P12V_NIC0_R      VIA   -    MD0100PA00X+007069Y+054836X0200Y         S0      
317P12V_NIC0_R      VIA   -    MD0100PA00X+006819Y+054836X0200Y         S0      
317P12V_NIC0_R      VIA   -    MD0100PA00X+007319Y+054836X0200Y         S0      
317P12V_NIC0_R      VIA   -    MD0100PA00X+006163Y+054190X0200Y    R180 S0      
317P12V_NIC0_R      VIA   -    MD0100PA00X+006413Y+054490X0200Y    R180 S0      
317P12V_NIC0_R      VIA   -    MD0100PA00X+006413Y+054190X0200Y    R180 S0      
317P12V_NIC0_R      VIA   -    MD0100PA00X+005657Y+054223X0200Y    R270 S0      
317P12V_NIC0_R      VIA   -    M      A01X+006133Y+054490X0200Y    R180 S2      
017P12V_NIC0_R      VIA   -    M      A18X+006133Y+054490X0260Y    R180 S2      
017P12V_NIC0_R            -    MD0100PA00X+006133Y+054490                       
317P12V_NIC0_R      VIA   -    MD0100PA00X+006820Y+054038X0200Y    R270 S0      
317P12V_NIC0_R      VIA   -    MD0100PA00X+006820Y+054538X0200Y    R270 S0      
317P12V_NIC0_R      VIA   -    MD0100PA00X+006820Y+054288X0200Y    R270 S0      
317P12V_NIC0_R      VIA   -    MD0100PA00X+004384Y+055519X0200Y         S0      
317P12V_NIC0_R      VIA   -    MD0100PA00X+005287Y+054046X0200Y    R270 S0      
317P12V_NIC0_R      VIA   -    MD0100PA00X+004664Y+055519X0200Y         S0      
317P12V_NIC0_R      VIA   -    MD0100PA00X+007569Y+054836X0200Y         S0      
317P12V_NIC0_R      VIA   -    MD0100PA00X+005657Y+053973X0200Y    R270 S0      
317P12V_NIC0_R      VIA   -    MD0100PA00X+006820Y+053788X0200Y    R270 S0      
317P12V_NIC0_R      VIA   -    MD0100PA00X+005287Y+053796X0200Y    R270 S0      
327P12V_NIC0_R      PR6862-2          A01X+002619Y+061374X0198Y0197R270 S1      
317NIC3_ADC_A0      VIA   -    M      A01X+086059Y+038300X0200Y         S2      
017NIC3_ADC_A0      VIA   -    M      A18X+086059Y+038300X0260Y         S2      
017NIC3_ADC_A0            -    MD0100PA00X+086059Y+038300                       
327NIC3_ADC_A0      R719  -1   M      A01X+085859Y+039058X0198Y0197R270 S1      
327NIC3_ADC_A0      U82   -2          A01X+085927Y+039701X0090Y0240     S1      
327NIC3_ADC_A0      R715  -1          A01X+085859Y+038008X0198Y0197R270 S1      
327NIC3_ADC_A0      R5621 -1          A18X+086182Y+038824X0198Y0197R180 S2      
317m2642            VIA   -    M      A01X+036649Y+038512X0200Y    R270 S2      
017m2642            VIA   -    M      A18X+036649Y+038512X0260Y    R270 S2      
017m2642                  -    MD0100PA00X+036649Y+038512                       
327m2642            U80   -4          A01X+036245Y+038901X0090Y0240     S1      
327m2642            R699  -2          A01X+036649Y+038272X0198Y0197R090 S1      
317m2643            VIA   -    M      A01X+155412Y+017762X0200Y         S2      
017m2643            VIA   -    M      A18X+155412Y+017762X0260Y         S2      
017m2643                  -    MD0100PA00X+155412Y+017762                       
327m2643            R657  -2          A01X+154733Y+017615X0198Y0197R090 S1      
327m2643            C338  -2   M      A01X+155133Y+017615X0198Y0197R090 S1      
327m2643            U76   -12         A01X+155806Y+017990X0090Y0240R090 S1      
317m2644            VIA   -    M      A01X+053582Y+057840X0200Y    R090 S2      
017m2644            VIA   -    M      A18X+053582Y+057840X0260Y    R090 S2      
017m2644                  -    MD0100PA00X+053582Y+057840                       
327m2644            U81   -12         A01X+053354Y+058234X0090Y0240R180 S1      
327m2644            R712  -2          A01X+053729Y+057161X0198Y0197R180 S1      
327m2644            C417  -2   M      A01X+053729Y+057561X0198Y0197R180 S1      
317SSD13_ADC_A0     VIA   -           A01X+157238Y+017856X0200Y         S2      
017SSD13_ADC_A0     VIA   -           A18X+157238Y+017856X0260Y         S2      
017SSD13_ADC_A0           -     D0100PA00X+157238Y+017856                       
327SSD13_ADC_A0     U76   -2          A01X+156908Y+018187X0090Y0240R090 S1      
327SSD13_ADC_A0     R650  -1          A01X+157537Y+017666X0198Y0197     S1      
327SSD13_ADC_A0     R652  -1   M      A01X+157537Y+018066X0198Y0197     S1      
317m2645            VIA   -    M      A01X+084959Y+041139X0200Y    R270 S2      
017m2645            VIA   -    M      A18X+084959Y+041139X0260Y    R270 S2      
017m2645                  -    MD0100PA00X+084959Y+041139                       
327m2645            R722  -2          A01X+084610Y+041481X0198Y0197R090 S1      
327m2645            C420  -1   M      A01X+085040Y+041476X0198Y0197     S1      
327m2645            U82   -13         A01X+085474Y+040548X0090Y0240R090 S1      
317m2646            VIA   -    MD0100PA00X+033925Y+113813X0200Y         S0      
327m2646            R3947 -1          A01X+034175Y+113713X0198Y0197R090 S1      
317m2646            VIA   -    MD0100PA00X+124600Y+101480X0200Y         S0      
317m2646            VIA   -    MD0100PA00X+125342Y+113813X0200Y         S0      
327m2646            R3984 -1          A01X+125592Y+113713X0198Y0197R090 S1      
327m2646            U6    -E2         A01X+131848Y+088499X0160Y         S1      
317m2646            VIA   -    MD0100PA00X+130822Y+088925X0200Y         S0      
317m2646            VIA   -    MD0100PA00X+038346Y+086054X0200Y    R180 S0      
317m2646            VIA   -    MD0100PA00X+038796Y+081370X0200Y         S0      
317m2646            VIA   -    MD0100PA00X+073300Y+081600X0200Y         S0      
327m2646            R4439 -1          A01X+039883Y+086054X0198Y0197     S1      
317m2646            VIA   -    MD0100PA00X+171051Y+113813X0200Y         S0      
317m2646            VIA   -    MD0100PA00X+175185Y+099130X0200Y         S0      
327m2646            R4003 -1          A01X+171301Y+113713X0198Y0197R090 S1      
327m2646            R6161 -1          A01X+084042Y+096227X0198Y0197R270 S1      
317m2646            VIA   -    MD0100PA00X+078860Y+100692X0200Y         S0      
317m2646            VIA   -    M      A01X+079634Y+113813X0200Y         S2      
017m2646            VIA   -    M      A18X+079634Y+113813X0260Y         S2      
017m2646                  -    MD0100PA00X+079634Y+113813                       
327m2646            R3948 -1          A01X+079884Y+113713X0198Y0197R090 S1      
327P12V_NIC7_R      PU29  -1          A01X+176056Y+039554X0110Y0240R180 S1      
327P12V_NIC7_R      PU29  -2          A01X+175860Y+039554X0110Y0240R180 S1      
327P12V_NIC7_R      PU29  -3          A01X+175663Y+039554X0110Y0240R180 S1      
327P12V_NIC7_R      PU29  -4          A01X+175466Y+039554X0110Y0240R180 S1      
327P12V_NIC7_R      PU29  -5          A01X+175269Y+039554X0110Y0240R180 S1      
327P12V_NIC7_R      PU106 -13         A01X+178942Y+044601X0100Y0320R090 S1      
327P12V_NIC7_R      PU106 -14         A01X+178942Y+044404X0100Y0320R090 S1      
327P12V_NIC7_R      PR7049-1          A01X+177242Y+044546X0198Y0197R090 S1      
327P12V_NIC7_R      PR7050-2          A01X+178936Y+046310X0198Y0197R180 S1      
327P12V_NIC7_R      PU106 -15         A01X+178942Y+044207X0100Y0320R090 S1      
327P12V_NIC7_R      PU106 -16         A01X+178942Y+044010X0100Y0320R090 S1      
327P12V_NIC7_R      PU106 -17         A01X+178942Y+043813X0100Y0320R090 S1      
327P12V_NIC7_R      PU106 -18         A01X+178942Y+043616X0100Y0320R090 S1      
327P12V_NIC7_R      PU106 -19         A01X+178942Y+043420X0100Y0320R090 S1      
327P12V_NIC7_R      PU106 -20         A01X+178942Y+043223X0100Y0320R090 S1      
327P12V_NIC7_R      PC827 -1          A01X+178311Y+043241X0198Y0197R270 S1      
327P12V_NIC7_R      PD99  -C          A01X+176184Y+043746X0670Y0990     S1      
327P12V_NIC7_R      PC826 -1          A01X+175118Y+044100X0400Y0500R270 S1      
327P12V_NIC7_R      PC824 -1          A01X+173330Y+043440X0400Y0500R270 S1      
327P12V_NIC7_R      PC347 -1          A01X+174318Y+044100X0400Y0500R270 S1      
327P12V_NIC7_R      PD19  -C          A01X+175324Y+041895X0670Y0990R270 S1      
327P12V_NIC7_R      R758  -2          A01X+173646Y+042244X1150Y1380     S1      
327P12V_NIC7_R      PC346 -1          A01X+175810Y+040192X0198Y0197     S1      
327P12V_NIC7_R      PC825 -1          A01X+175703Y+040814X0400Y0500R180 S1      
327P12V_NIC7_R      C623  -1          A01X+173266Y+040653X0198Y0197     S1      
327P12V_NIC7_R      U86   -11         A01X+172977Y+040004X0090Y0240     S1      
317P12V_NIC7_R      VIA   -    MD0100PA00X+178338Y+044372X0200Y    R270 S0      
317P12V_NIC7_R      VIA   -    MD0100PA00X+178618Y+044372X0200Y    R270 S0      
317P12V_NIC7_R      VIA   -    MD0100PA00X+176684Y+044389X0200Y    R270 S0      
317P12V_NIC7_R      VIA   -    MD0100PA00X+175684Y+044389X0200Y    R270 S0      
317P12V_NIC7_R      VIA   -    MD0100PA00X+178338Y+044092X0200Y    R270 S0      
317P12V_NIC7_R      VIA   -    MD0100PA00X+178618Y+044092X0200Y    R270 S0      
317P12V_NIC7_R      VIA   -    MD0100PA00X+178338Y+043812X0200Y    R270 S0      
317P12V_NIC7_R      VIA   -    MD0100PA00X+178338Y+043532X0200Y    R270 S0      
317P12V_NIC7_R      VIA   -    MD0100PA00X+178618Y+043812X0200Y    R270 S0      
317P12V_NIC7_R      VIA   -    MD0100PA00X+178618Y+043532X0200Y    R270 S0      
317P12V_NIC7_R      VIA   -    MD0100PA00X+176684Y+044109X0200Y    R270 S0      
317P12V_NIC7_R      VIA   -    MD0100PA00X+176684Y+043829X0200Y    R270 S0      
317P12V_NIC7_R      VIA   -    MD0100PA00X+174718Y+044212X0200Y    R270 S0      
317P12V_NIC7_R      VIA   -    MD0100PA00X+175684Y+044109X0200Y    R270 S0      
317P12V_NIC7_R      VIA   -    MD0100PA00X+174718Y+043932X0200Y    R270 S0      
317P12V_NIC7_R      VIA   -    MD0100PA00X+175684Y+043829X0200Y    R270 S0      
317P12V_NIC7_R      VIA   -    MD0100PA00X+173918Y+044212X0200Y    R270 S0      
317P12V_NIC7_R      VIA   -    MD0100PA00X+172892Y+042669X0200Y         S0      
317P12V_NIC7_R      VIA   -    MD0100PA00X+173918Y+043932X0200Y    R270 S0      
317P12V_NIC7_R      VIA   -    MD0100PA00X+172930Y+043552X0200Y    R270 S0      
317P12V_NIC7_R      VIA   -    MD0100PA00X+172930Y+043272X0200Y    R270 S0      
317P12V_NIC7_R      VIA   -    MD0100PA00X+175470Y+041361X0200Y         S0      
317P12V_NIC7_R      VIA   -    MD0100PA00X+175720Y+041361X0200Y         S0      
317P12V_NIC7_R      VIA   -    MD0100PA00X+175220Y+041361X0200Y         S0      
317P12V_NIC7_R      VIA   -    MD0100PA00X+174970Y+041361X0200Y         S0      
317P12V_NIC7_R      VIA   -    MD0100PA00X+175447Y+042407X0200Y         S0      
317P12V_NIC7_R      VIA   -    MD0100PA00X+175697Y+042407X0200Y         S0      
317P12V_NIC7_R      VIA   -    MD0100PA00X+175197Y+042407X0200Y         S0      
317P12V_NIC7_R      VIA   -    MD0100PA00X+174947Y+042407X0200Y         S0      
317P12V_NIC7_R      VIA   -    MD0100PA00X+172892Y+042409X0200Y         S0      
317P12V_NIC7_R      VIA   -    MD0100PA00X+172892Y+041889X0200Y         S0      
317P12V_NIC7_R      VIA   -    MD0100PA00X+172892Y+042149X0200Y         S0      
317P12V_NIC7_R      VIA   -    MD0100PA00X+172892Y+041629X0200Y         S0      
317P12V_NIC7_R      VIA   -    MD0100PA00X+172892Y+041109X0200Y         S0      
317P12V_NIC7_R      VIA   -    MD0100PA00X+172892Y+041369X0200Y         S0      
317P12V_NIC7_R      VIA   -    MD0100PA00X+175462Y+039828X0200Y         S0      
317P12V_NIC7_R      VIA   -    MD0100PA00X+175712Y+039828X0200Y         S0      
317P12V_NIC7_R      VIA   -    MD0100PA00X+175535Y+040198X0200Y         S0      
317P12V_NIC7_R      VIA   -    MD0100PA00X+175285Y+040198X0200Y         S0      
317P12V_NIC7_R      VIA   -    MD0100PA00X+175319Y+040704X0200Y    R270 S0      
317P12V_NIC7_R      VIA   -    M      A01X+175019Y+040674X0200Y    R270 S2      
017P12V_NIC7_R      VIA   -    M      A18X+175019Y+040674X0260Y    R270 S2      
017P12V_NIC7_R            -    MD0100PA00X+175019Y+040674                       
317P12V_NIC7_R      VIA   -    MD0100PA00X+175319Y+040954X0200Y    R270 S0      
317P12V_NIC7_R      VIA   -    MD0100PA00X+175019Y+040954X0200Y    R270 S0      
317P12V_NIC7_R      VIA   -    MD0100PA00X+172892Y+040849X0200Y         S0      
317P12V_NIC7_R      VIA   -    MD0100PA00X+172892Y+040589X0200Y    R270 S0      
317P12V_NIC7_R      VIA   -    MD0100PA00X+172951Y+040330X0200Y    R270 S0      
317P12V_NIC7_R      VIA   -    MD0100PA00X+171885Y+039153X0200Y    R270 S0      
327P12V_NIC7_R      R766  -1          A01X+171885Y+039393X0198Y0197R090 S1      
317m2647            VIA   -    M      A01X+166888Y+019249X0200Y         S2      
017m2647            VIA   -    M      A18X+166888Y+019249X0260Y         S2      
017m2647                  -    MD0100PA00X+166888Y+019249                       
327m2647            U77   -5          A01X+166888Y+018836X0090Y0240R180 S1      
327m2647            R665  -2          A01X+167356Y+019662X0198Y0197     S1      
317m2647            VIA   -    MD0100PA00X+166935Y+017152X0200Y         S0      
327m2647            R5906 -2          A01X+166935Y+016871X0198Y0197R180 S1      
317m2648            VIA   -    M      A01X+155470Y+017219X0200Y         S2      
017m2648            VIA   -    M      A18X+155470Y+017219X0260Y         S2      
017m2648                  -    MD0100PA00X+155470Y+017219                       
327m2648            R656  -2          A01X+155128Y+016870X0198Y0197R180 S1      
327m2648            C338  -1   M      A01X+155133Y+017300X0198Y0197R090 S1      
327m2648            U76   -13         A01X+156061Y+017734X0090Y0240R180 S1      
327m2649            U80   -13         A01X+035398Y+039748X0090Y0240R090 S1      
327m2649            R700  -2          A01X+034759Y+039708X0198Y0197R090 S1      
327m2649            C414  -1          A01X+034976Y+040172X0198Y0197R045 S1      
317m2649            VIA   -           A01X+034706Y+039992X0200Y    R270 S2      
017m2649            VIA   -           A18X+034706Y+039992X0260Y    R270 S2      
017m2649                  -     D0100PA00X+034706Y+039992                       
317m2650            VIA   -    M      A01X+165707Y+017219X0200Y         S2      
017m2650            VIA   -    M      A18X+165707Y+017219X0260Y         S2      
017m2650                  -    MD0100PA00X+165707Y+017219                       
327m2650            R667  -2          A01X+165364Y+016870X0198Y0197R180 S1      
327m2650            C405  -1   M      A01X+165370Y+017300X0198Y0197R090 S1      
327m2650            U77   -13         A01X+166298Y+017734X0090Y0240R180 S1      
317NIC1_ADC_A1      VIA   -    M      A01X+034931Y+038564X0200Y    R270 S2      
017NIC1_ADC_A1      VIA   -    M      A18X+034931Y+038564X0260Y    R270 S2      
017NIC1_ADC_A1            -    MD0100PA00X+034931Y+038564                       
327NIC1_ADC_A1      R692  -1          A01X+034249Y+038272X0198Y0197R270 S1      
327NIC1_ADC_A1      U80   -1          A01X+035654Y+038901X0090Y0240     S1      
327NIC1_ADC_A1      R696  -1   M      A01X+034649Y+038272X0198Y0197R270 S1      
317m2651            VIA   -    M      A01X+167416Y+019018X0200Y         S2      
017m2651            VIA   -    M      A18X+167416Y+019018X0260Y         S2      
017m2651                  -    MD0100PA00X+167416Y+019018                       
327m2651            U77   -4          A01X+167144Y+018580X0090Y0240R090 S1      
327m2651            R5907 -2          A01X+167773Y+019666X0198Y0197R180 S1      
327m2651            R666  -2   M      A01X+167773Y+019266X0198Y0197R180 S1      
317m2652            VIA   -    M      A01X+085502Y+041197X0200Y    R270 S2      
017m2652            VIA   -    M      A18X+085502Y+041197X0260Y    R270 S2      
017m2652                  -    MD0100PA00X+085502Y+041197                       
327m2652            R723  -2          A01X+085355Y+041876X0198Y0197     S1      
327m2652            C420  -2   M      A01X+085355Y+041476X0198Y0197     S1      
327m2652            U82   -12         A01X+085730Y+040804X0090Y0240     S1      
327P12V_SSD13_R     PU41  -1          A01X+155688Y+021907X0110Y0240R270 S1      
327P12V_SSD13_R     PU41  -2          A01X+155688Y+021710X0110Y0240R270 S1      
327P12V_SSD13_R     PU41  -3          A01X+155688Y+021513X0110Y0240R270 S1      
327P12V_SSD13_R     PU41  -4          A01X+155688Y+021317X0110Y0240R270 S1      
327P12V_SSD13_R     PU41  -5          A01X+155688Y+021120X0110Y0240R270 S1      
327P12V_SSD13_R     PU116 -6_7        A01X+155315Y+027354X0295Y0354R090 S1      
327P12V_SSD13_R     PC886 -1          A01X+154386Y+027416X0400Y0500R270 S1      
327P12V_SSD13_R     PD119 -C          A01X+153324Y+027104X0670Y0990     S1      
317P12V_SSD13_R     VIA   -    MD0100PA00X+154588Y+026753X0200Y         S0      
317P12V_SSD13_R     VIA   -    MD0100PA00X+154058Y+026753X0200Y         S0      
317P12V_SSD13_R     VIA   -    MD0100PA00X+154338Y+026753X0200Y         S0      
317P12V_SSD13_R     VIA   -    MD0100PA00X+154058Y+027003X0200Y         S0      
317P12V_SSD13_R     VIA   -    MD0100PA00X+154338Y+027003X0200Y         S0      
317P12V_SSD13_R     VIA   -    MD0100PA00X+154588Y+027003X0200Y         S0      
317P12V_SSD13_R     VIA   -    MD0100PA00X+153168Y+026418X0200Y         S0      
317P12V_SSD13_R     VIA   -    MD0100PA00X+153418Y+026418X0200Y         S0      
317P12V_SSD13_R     VIA   -    MD0100PA00X+148059Y+024837X0200Y         S0      
327P12V_SSD13_R     R6019 -1          A01X+148337Y+024837X0198Y0197     S1      
317P12V_SSD13_R     VIA   -    MD0100PA00X+155738Y+016870X0200Y         S0      
327P12V_SSD13_R     R656  -1          A01X+155443Y+016870X0198Y0197R180 S1      
327P12V_SSD13_R     PC418 -1          A01X+155050Y+021661X0198Y0197R090 S1      
327P12V_SSD13_R     PC419 -1          A01X+154428Y+021554X0400Y0500R270 S1      
327P12V_SSD13_R     PD43  -C          A01X+153347Y+021175X0670Y0990     S1      
327P12V_SSD13_R     C337  -1          A01X+155156Y+018426X0198Y0197R090 S1      
327P12V_SSD13_R     R649  -2          A01X+153657Y+018919X1150Y1380R090 S1      
327P12V_SSD13_R     U76   -11         A01X+155806Y+018187X0090Y0240R090 S1      
317P12V_SSD13_R     VIA   -    MD0100PA00X+155414Y+021563X0200Y    R090 S0      
317P12V_SSD13_R     VIA   -    MD0100PA00X+153881Y+021571X0200Y    R090 S0      
317P12V_SSD13_R     VIA   -    MD0100PA00X+155044Y+021386X0200Y    R090 S0      
317P12V_SSD13_R     VIA   -    MD0100PA00X+155044Y+021136X0200Y    R090 S0      
317P12V_SSD13_R     VIA   -    MD0100PA00X+155414Y+021313X0200Y    R090 S0      
317P12V_SSD13_R     VIA   -    MD0100PA00X+153881Y+020821X0200Y    R090 S0      
317P12V_SSD13_R     VIA   -    M      A01X+154568Y+020870X0200Y         S2      
017P12V_SSD13_R     VIA   -    M      A18X+154568Y+020870X0260Y         S2      
017P12V_SSD13_R           -    MD0100PA00X+154568Y+020870                       
317P12V_SSD13_R     VIA   -    MD0100PA00X+154288Y+020870X0200Y         S0      
317P12V_SSD13_R     VIA   -    MD0100PA00X+154538Y+021170X0200Y         S0      
317P12V_SSD13_R     VIA   -    MD0100PA00X+154288Y+021170X0200Y         S0      
317P12V_SSD13_R     VIA   -    MD0100PA00X+153881Y+021071X0200Y    R090 S0      
317P12V_SSD13_R     VIA   -    MD0100PA00X+153881Y+021321X0200Y    R090 S0      
317P12V_SSD13_R     VIA   -    MD0100PA00X+152836Y+020798X0200Y    R090 S0      
317P12V_SSD13_R     VIA   -    MD0100PA00X+152836Y+021298X0200Y    R090 S0      
317P12V_SSD13_R     VIA   -    MD0100PA00X+152836Y+021548X0200Y    R090 S0      
317P12V_SSD13_R     VIA   -    MD0100PA00X+152836Y+021048X0200Y    R090 S0      
317P12V_SSD13_R     VIA   -    MD0100PA00X+154902Y+018401X0200Y         S0      
317P12V_SSD13_R     VIA   -    MD0100PA00X+154640Y+018422X0200Y         S0      
317P12V_SSD13_R     VIA   -    MD0100PA00X+154941Y+018137X0200Y         S0      
317P12V_SSD13_R     VIA   -    MD0100PA00X+155220Y+018101X0200Y         S0      
317P12V_SSD13_R     VIA   -    MD0100PA00X+154620Y+018143X0200Y         S0      
317m2653            VIA   -    M      A01X+035949Y+038512X0200Y    R270 S2      
017m2653            VIA   -    M      A18X+035949Y+038512X0260Y    R270 S2      
017m2653                  -    MD0100PA00X+035949Y+038512                       
327m2653            R695  -1          A01X+035849Y+038272X0198Y0197R270 S1      
327m2653            U80   -3          A01X+036048Y+038901X0090Y0240     S1      
327P12V_SSD15_R     PU45  -1          A01X+176160Y+021907X0110Y0240R270 S1      
327P12V_SSD15_R     PU45  -2          A01X+176160Y+021710X0110Y0240R270 S1      
327P12V_SSD15_R     PU45  -3          A01X+176160Y+021513X0110Y0240R270 S1      
327P12V_SSD15_R     PU45  -4          A01X+176160Y+021317X0110Y0240R270 S1      
327P12V_SSD15_R     PU45  -5          A01X+176160Y+021120X0110Y0240R270 S1      
327P12V_SSD15_R     PC443 -1          A01X+174858Y+027416X0400Y0500R270 S1      
327P12V_SSD15_R     PU118 -6_7        A01X+175788Y+027354X0295Y0354R090 S1      
327P12V_SSD15_R     PD51  -C          A01X+173796Y+027104X0670Y0990     S1      
317P12V_SSD15_R     VIA   -    MD0100PA00X+175060Y+027003X0200Y         S0      
317P12V_SSD15_R     VIA   -    MD0100PA00X+174810Y+027003X0200Y         S0      
317P12V_SSD15_R     VIA   -    MD0100PA00X+174530Y+027003X0200Y         S0      
317P12V_SSD15_R     VIA   -    MD0100PA00X+174810Y+026753X0200Y         S0      
317P12V_SSD15_R     VIA   -    MD0100PA00X+174530Y+026753X0200Y         S0      
317P12V_SSD15_R     VIA   -    MD0100PA00X+175060Y+026753X0200Y         S0      
317P12V_SSD15_R     VIA   -    MD0100PA00X+173891Y+026418X0200Y         S0      
317P12V_SSD15_R     VIA   -    MD0100PA00X+173641Y+026418X0200Y         S0      
317P12V_SSD15_R     VIA   -    MD0100PA00X+168531Y+024837X0200Y         S0      
327P12V_SSD15_R     R6029 -1          A01X+168809Y+024837X0198Y0197     S1      
317P12V_SSD15_R     VIA   -    MD0100PA00X+176210Y+016870X0200Y         S0      
327P12V_SSD15_R     R678  -1          A01X+175916Y+016870X0198Y0197R180 S1      
327P12V_SSD15_R     PC442 -1          A01X+175522Y+021661X0198Y0197R090 S1      
327P12V_SSD15_R     PC894 -1          A01X+174900Y+021554X0400Y0500R270 S1      
327P12V_SSD15_R     PD123 -C          A01X+173819Y+021175X0670Y0990     S1      
327P12V_SSD15_R     C407  -1          A01X+175628Y+018426X0198Y0197R090 S1      
327P12V_SSD15_R     R670  -2          A01X+174129Y+018919X1150Y1380R090 S1      
327P12V_SSD15_R     U78   -11         A01X+176278Y+018187X0090Y0240R090 S1      
317P12V_SSD15_R     VIA   -    MD0100PA00X+175887Y+021563X0200Y    R090 S0      
317P12V_SSD15_R     VIA   -    MD0100PA00X+174354Y+021571X0200Y    R090 S0      
317P12V_SSD15_R     VIA   -    MD0100PA00X+175887Y+021313X0200Y    R090 S0      
317P12V_SSD15_R     VIA   -    MD0100PA00X+174354Y+021071X0200Y    R090 S0      
317P12V_SSD15_R     VIA   -    MD0100PA00X+174354Y+021321X0200Y    R090 S0      
317P12V_SSD15_R     VIA   -    MD0100PA00X+174354Y+020821X0200Y    R090 S0      
317P12V_SSD15_R     VIA   -    M      A01X+175041Y+020870X0200Y         S2      
017P12V_SSD15_R     VIA   -    M      A18X+175041Y+020870X0260Y         S2      
017P12V_SSD15_R           -    MD0100PA00X+175041Y+020870                       
317P12V_SSD15_R     VIA   -    MD0100PA00X+174761Y+020870X0200Y         S0      
317P12V_SSD15_R     VIA   -    MD0100PA00X+175011Y+021170X0200Y         S0      
317P12V_SSD15_R     VIA   -    MD0100PA00X+175516Y+021386X0200Y    R090 S0      
317P12V_SSD15_R     VIA   -    MD0100PA00X+175516Y+021136X0200Y    R090 S0      
317P12V_SSD15_R     VIA   -    MD0100PA00X+174761Y+021170X0200Y         S0      
317P12V_SSD15_R     VIA   -    MD0100PA00X+173308Y+021298X0200Y    R090 S0      
317P12V_SSD15_R     VIA   -    MD0100PA00X+173308Y+021548X0200Y    R090 S0      
317P12V_SSD15_R     VIA   -    MD0100PA00X+173308Y+021048X0200Y    R090 S0      
317P12V_SSD15_R     VIA   -    MD0100PA00X+173308Y+020798X0200Y    R090 S0      
317P12V_SSD15_R     VIA   -    MD0100PA00X+175375Y+018401X0200Y         S0      
317P12V_SSD15_R     VIA   -    MD0100PA00X+175113Y+018422X0200Y         S0      
317P12V_SSD15_R     VIA   -    MD0100PA00X+175413Y+018137X0200Y         S0      
317P12V_SSD15_R     VIA   -    MD0100PA00X+175092Y+018143X0200Y         S0      
317P12V_SSD15_R     VIA   -    MD0100PA00X+175693Y+018101X0200Y         S0      
327NIC2_ADC_A0      R708  -1          A01X+053277Y+059965X0198Y0197R090 S1      
327NIC2_ADC_A0      R703  -1   M      A01X+053677Y+059965X0198Y0197R090 S1      
327NIC2_ADC_A0      U81   -2          A01X+053157Y+059336X0090Y0240R180 S1      
317NIC2_ADC_A0      VIA   -    M      A01X+053482Y+059678X0200Y    R090 S2      
017NIC2_ADC_A0      VIA   -    M      A18X+053482Y+059678X0260Y    R090 S2      
017NIC2_ADC_A0            -    MD0100PA00X+053482Y+059678                       
327NIC2_ADC_A0      R5622 -1          A18X+052906Y+060079X0198Y0197     S2      
317m2654            VIA   -    M      A01X+082799Y+087411X0200Y    R270 S2      
017m2654            VIA   -    M      A18X+082799Y+087411X0260Y    R270 S2      
017m2654                  -    MD0100PA00X+082799Y+087411                       
327m2654            U302  -1          A01X+082680Y+087850X0160Y0360     S1      
327m2654            R2740 -1          A01X+082888Y+087044X0198Y0197R270 S1      
317m2655            VIA   -    M      A01X+146416Y+019249X0200Y         S2      
017m2655            VIA   -    M      A18X+146416Y+019249X0260Y         S2      
017m2655                  -    MD0100PA00X+146416Y+019249                       
327m2655            U75   -5          A01X+146416Y+018836X0090Y0240R180 S1      
327m2655            R643  -2          A01X+147301Y+019666X0198Y0197R180 S1      
317m2655            VIA   -    MD0100PA00X+146463Y+017152X0200Y         S0      
327m2655            R5904 -2          A01X+146463Y+016871X0198Y0197R180 S1      
317m2656            VIA   -    M      A01X+156652Y+019249X0200Y         S2      
017m2656            VIA   -    M      A18X+156652Y+019249X0260Y         S2      
017m2656                  -    MD0100PA00X+156652Y+019249                       
327m2656            R654  -2          A01X+157537Y+019666X0198Y0197R180 S1      
327m2656            U76   -5          A01X+156652Y+018836X0090Y0240R180 S1      
317m2656            VIA   -    MD0100PA00X+156699Y+017152X0200Y         S0      
327m2656            R5905 -2          A01X+156699Y+016871X0198Y0197R180 S1      
317m2657            VIA   -    M      A01X+145234Y+017219X0200Y         S2      
017m2657            VIA   -    M      A18X+145234Y+017219X0260Y         S2      
017m2657                  -    MD0100PA00X+145234Y+017219                       
327m2657            R645  -2          A01X+144892Y+016870X0198Y0197R180 S1      
327m2657            C335  -1   M      A01X+144897Y+017300X0198Y0197R090 S1      
327m2657            U75   -13         A01X+145825Y+017734X0090Y0240R180 S1      
317m2658            VIA   -    M      A01X+083319Y+087356X0200Y    R270 S2      
017m2658            VIA   -    M      A18X+083319Y+087356X0260Y    R270 S2      
017m2658                  -    MD0100PA00X+083319Y+087356                       
327m2658            U302  -2          A01X+082936Y+087850X0160Y0360     S1      
327m2658            R2739 -1          A01X+083288Y+087044X0198Y0197R270 S1      
327P12V_SSD14_R     PU43  -1          A01X+165924Y+021907X0110Y0240R270 S1      
327P12V_SSD14_R     PU43  -2          A01X+165924Y+021710X0110Y0240R270 S1      
327P12V_SSD14_R     PU43  -3          A01X+165924Y+021513X0110Y0240R270 S1      
327P12V_SSD14_R     PU43  -4          A01X+165924Y+021317X0110Y0240R270 S1      
327P12V_SSD14_R     PU43  -5          A01X+165924Y+021120X0110Y0240R270 S1      
327P12V_SSD14_R     PU117 -6_7        A01X+165551Y+027354X0295Y0354R090 S1      
327P12V_SSD14_R     PC431 -1          A01X+164622Y+027416X0400Y0500R270 S1      
327P12V_SSD14_R     PD47  -C          A01X+163560Y+027104X0670Y0990     S1      
317P12V_SSD14_R     VIA   -    MD0100PA00X+164824Y+027003X0200Y         S0      
317P12V_SSD14_R     VIA   -    MD0100PA00X+164574Y+027003X0200Y         S0      
317P12V_SSD14_R     VIA   -    MD0100PA00X+164574Y+026753X0200Y         S0      
317P12V_SSD14_R     VIA   -    MD0100PA00X+164824Y+026753X0200Y         S0      
317P12V_SSD14_R     VIA   -    MD0100PA00X+164294Y+027003X0200Y         S0      
317P12V_SSD14_R     VIA   -    MD0100PA00X+164294Y+026753X0200Y         S0      
317P12V_SSD14_R     VIA   -    MD0100PA00X+163655Y+026418X0200Y         S0      
317P12V_SSD14_R     VIA   -    MD0100PA00X+163405Y+026418X0200Y         S0      
317P12V_SSD14_R     VIA   -    MD0100PA00X+158295Y+024837X0200Y         S0      
327P12V_SSD14_R     R6028 -1          A01X+158573Y+024837X0198Y0197     S1      
317P12V_SSD14_R     VIA   -    MD0100PA00X+165974Y+016870X0200Y         S0      
327P12V_SSD14_R     R667  -1          A01X+165679Y+016870X0198Y0197R180 S1      
327P12V_SSD14_R     PC430 -1          A01X+165286Y+021661X0198Y0197R090 S1      
327P12V_SSD14_R     PC892 -1          A01X+164664Y+021554X0400Y0500R270 S1      
327P12V_SSD14_R     PD122 -C          A01X+163583Y+021175X0670Y0990     S1      
327P12V_SSD14_R     C404  -1          A01X+165392Y+018426X0198Y0197R090 S1      
327P12V_SSD14_R     R661  -2          A01X+163893Y+018919X1150Y1380R090 S1      
327P12V_SSD14_R     U77   -11         A01X+166042Y+018187X0090Y0240R090 S1      
317P12V_SSD14_R     VIA   -    MD0100PA00X+165651Y+021563X0200Y    R090 S0      
317P12V_SSD14_R     VIA   -    MD0100PA00X+164117Y+021571X0200Y    R090 S0      
317P12V_SSD14_R     VIA   -    MD0100PA00X+164524Y+021170X0200Y         S0      
317P12V_SSD14_R     VIA   -    MD0100PA00X+165280Y+021386X0200Y    R090 S0      
317P12V_SSD14_R     VIA   -    MD0100PA00X+165280Y+021136X0200Y    R090 S0      
317P12V_SSD14_R     VIA   -    MD0100PA00X+165651Y+021313X0200Y    R090 S0      
317P12V_SSD14_R     VIA   -    M      A01X+164804Y+020870X0200Y         S2      
017P12V_SSD14_R     VIA   -    M      A18X+164804Y+020870X0260Y         S2      
017P12V_SSD14_R           -    MD0100PA00X+164804Y+020870                       
317P12V_SSD14_R     VIA   -    MD0100PA00X+164524Y+020870X0200Y         S0      
317P12V_SSD14_R     VIA   -    MD0100PA00X+164774Y+021170X0200Y         S0      
317P12V_SSD14_R     VIA   -    MD0100PA00X+163072Y+020798X0200Y    R090 S0      
317P12V_SSD14_R     VIA   -    MD0100PA00X+163072Y+021298X0200Y    R090 S0      
317P12V_SSD14_R     VIA   -    MD0100PA00X+163072Y+021548X0200Y    R090 S0      
317P12V_SSD14_R     VIA   -    MD0100PA00X+163072Y+021048X0200Y    R090 S0      
317P12V_SSD14_R     VIA   -    MD0100PA00X+164117Y+020821X0200Y    R090 S0      
317P12V_SSD14_R     VIA   -    MD0100PA00X+164117Y+021071X0200Y    R090 S0      
317P12V_SSD14_R     VIA   -    MD0100PA00X+164117Y+021321X0200Y    R090 S0      
317P12V_SSD14_R     VIA   -    MD0100PA00X+164877Y+018422X0200Y         S0      
317P12V_SSD14_R     VIA   -    MD0100PA00X+165138Y+018401X0200Y         S0      
317P12V_SSD14_R     VIA   -    MD0100PA00X+165177Y+018137X0200Y         S0      
317P12V_SSD14_R     VIA   -    MD0100PA00X+164856Y+018143X0200Y         S0      
317P12V_SSD14_R     VIA   -    MD0100PA00X+165456Y+018101X0200Y         S0      
317m2659            VIA   -    M      A01X+177700Y+018383X0200Y         S2      
017m2659            VIA   -    M      A18X+177700Y+018383X0260Y         S2      
017m2659                  -    MD0100PA00X+177700Y+018383                       
327m2659            R674  -1          A01X+178009Y+018466X0198Y0197     S1      
327m2659            U78   -3          A01X+177380Y+018383X0090Y0240R090 S1      
317m2660            VIA   -    M      A01X+083535Y+089135X0200Y    R270 S2      
017m2660            VIA   -    M      A18X+083535Y+089135X0260Y    R270 S2      
017m2660                  -    MD0100PA00X+083535Y+089135                       
327m2660            U302  -4          A01X+083192Y+088717X0160Y0360     S1      
327m2660            R2742 -2          A01X+083264Y+089301X0198Y0197R270 S1      
317m2661            VIA   -    M      A01X+177652Y+019018X0200Y         S2      
017m2661            VIA   -    M      A18X+177652Y+019018X0260Y         S2      
017m2661                  -    MD0100PA00X+177652Y+019018                       
327m2661            R677  -2          A01X+178009Y+019266X0198Y0197R180 S1      
327m2661            U78   -4          A01X+177380Y+018580X0090Y0240R090 S1      
327P12V_SSD12_R     PU39  -1          A01X+145452Y+021907X0110Y0240R270 S1      
327P12V_SSD12_R     PU39  -2          A01X+145452Y+021710X0110Y0240R270 S1      
327P12V_SSD12_R     PU39  -3          A01X+145452Y+021513X0110Y0240R270 S1      
327P12V_SSD12_R     PU39  -4          A01X+145452Y+021317X0110Y0240R270 S1      
327P12V_SSD12_R     PU39  -5          A01X+145452Y+021120X0110Y0240R270 S1      
327P12V_SSD12_R     PC883 -1          A01X+144150Y+027416X0400Y0500R270 S1      
327P12V_SSD12_R     PU115 -6_7        A01X+145079Y+027354X0295Y0354R090 S1      
327P12V_SSD12_R     PD118 -C          A01X+143088Y+027104X0670Y0990     S1      
317P12V_SSD12_R     VIA   -    MD0100PA00X+143822Y+026753X0200Y         S0      
317P12V_SSD12_R     VIA   -    MD0100PA00X+144352Y+026753X0200Y         S0      
317P12V_SSD12_R     VIA   -    MD0100PA00X+143822Y+027003X0200Y         S0      
317P12V_SSD12_R     VIA   -    MD0100PA00X+144352Y+027003X0200Y         S0      
317P12V_SSD12_R     VIA   -    MD0100PA00X+144102Y+027003X0200Y         S0      
317P12V_SSD12_R     VIA   -    MD0100PA00X+144102Y+026753X0200Y         S0      
317P12V_SSD12_R     VIA   -    MD0100PA00X+143182Y+026418X0200Y         S0      
317P12V_SSD12_R     VIA   -    MD0100PA00X+142932Y+026418X0200Y         S0      
317P12V_SSD12_R     VIA   -    MD0100PA00X+137823Y+024837X0200Y         S0      
327P12V_SSD12_R     R6018 -1          A01X+138100Y+024837X0198Y0197     S1      
317P12V_SSD12_R     VIA   -    MD0100PA00X+145502Y+016870X0200Y         S0      
327P12V_SSD12_R     R645  -1          A01X+145207Y+016870X0198Y0197R180 S1      
327P12V_SSD12_R     PC406 -1          A01X+144814Y+021661X0198Y0197R090 S1      
327P12V_SSD12_R     PC407 -1          A01X+144192Y+021554X0400Y0500R270 S1      
327P12V_SSD12_R     PD39  -C          A01X+143111Y+021175X0670Y0990     S1      
327P12V_SSD12_R     C334  -1          A01X+144920Y+018426X0198Y0197R090 S1      
327P12V_SSD12_R     R638  -2          A01X+143420Y+018919X1150Y1380R090 S1      
327P12V_SSD12_R     U75   -11         A01X+145569Y+018187X0090Y0240R090 S1      
317P12V_SSD12_R     VIA   -    MD0100PA00X+145178Y+021563X0200Y    R090 S0      
317P12V_SSD12_R     VIA   -    MD0100PA00X+143645Y+021571X0200Y    R090 S0      
317P12V_SSD12_R     VIA   -    MD0100PA00X+145178Y+021313X0200Y    R090 S0      
317P12V_SSD12_R     VIA   -    MD0100PA00X+143645Y+020821X0200Y    R090 S0      
317P12V_SSD12_R     VIA   -    M      A01X+144332Y+020870X0200Y         S2      
017P12V_SSD12_R     VIA   -    M      A18X+144332Y+020870X0260Y         S2      
017P12V_SSD12_R           -    MD0100PA00X+144332Y+020870                       
317P12V_SSD12_R     VIA   -    MD0100PA00X+144052Y+020870X0200Y         S0      
317P12V_SSD12_R     VIA   -    MD0100PA00X+144302Y+021170X0200Y         S0      
317P12V_SSD12_R     VIA   -    MD0100PA00X+144052Y+021170X0200Y         S0      
317P12V_SSD12_R     VIA   -    MD0100PA00X+143645Y+021071X0200Y    R090 S0      
317P12V_SSD12_R     VIA   -    MD0100PA00X+143645Y+021321X0200Y    R090 S0      
317P12V_SSD12_R     VIA   -    MD0100PA00X+144808Y+021386X0200Y    R090 S0      
317P12V_SSD12_R     VIA   -    MD0100PA00X+144808Y+021136X0200Y    R090 S0      
317P12V_SSD12_R     VIA   -    MD0100PA00X+142599Y+021548X0200Y    R090 S0      
317P12V_SSD12_R     VIA   -    MD0100PA00X+142599Y+021048X0200Y    R090 S0      
317P12V_SSD12_R     VIA   -    MD0100PA00X+142599Y+020798X0200Y    R090 S0      
317P12V_SSD12_R     VIA   -    MD0100PA00X+142599Y+021298X0200Y    R090 S0      
317P12V_SSD12_R     VIA   -    MD0100PA00X+144666Y+018401X0200Y         S0      
317P12V_SSD12_R     VIA   -    MD0100PA00X+144404Y+018422X0200Y         S0      
317P12V_SSD12_R     VIA   -    MD0100PA00X+144384Y+018143X0200Y         S0      
317P12V_SSD12_R     VIA   -    MD0100PA00X+144705Y+018137X0200Y         S0      
317P12V_SSD12_R     VIA   -    MD0100PA00X+144984Y+018101X0200Y         S0      
317SSD12_ADC_A0     VIA   -           A01X+147002Y+017856X0200Y         S2      
017SSD12_ADC_A0     VIA   -           A18X+147002Y+017856X0260Y         S2      
017SSD12_ADC_A0           -     D0100PA00X+147002Y+017856                       
327SSD12_ADC_A0     R639  -1          A01X+147301Y+017666X0198Y0197     S1      
327SSD12_ADC_A0     R641  -1   M      A01X+147301Y+018066X0198Y0197     S1      
327SSD12_ADC_A0     U75   -2          A01X+146672Y+018187X0090Y0240R090 S1      
317m2662            VIA   -    M      A01X+157180Y+019018X0200Y         S2      
017m2662            VIA   -    M      A18X+157180Y+019018X0260Y         S2      
017m2662                  -    MD0100PA00X+157180Y+019018                       
327m2662            R655  -2          A01X+157537Y+019266X0198Y0197R180 S1      
327m2662            U76   -4          A01X+156908Y+018580X0090Y0240R090 S1      
327P12V_NIC3_R      PU28  -1          A01X+088463Y+040888X0110Y0240R180 S1      
327P12V_NIC3_R      PU28  -2          A01X+088266Y+040888X0110Y0240R180 S1      
327P12V_NIC3_R      PU28  -3          A01X+088069Y+040888X0110Y0240R180 S1      
327P12V_NIC3_R      PU28  -4          A01X+087872Y+040888X0110Y0240R180 S1      
327P12V_NIC3_R      PU28  -5          A01X+087676Y+040888X0110Y0240R180 S1      
317P12V_NIC3_R      VIA   -    MD0100PA00X+084610Y+040872X0200Y    R270 S0      
327P12V_NIC3_R      R722  -1          A01X+084610Y+041166X0198Y0197R090 S1      
327P12V_NIC3_R      PU74  -13         A01X+091349Y+046235X0100Y0320R090 S1      
327P12V_NIC3_R      PU74  -14         A01X+091349Y+046038X0100Y0320R090 S1      
327P12V_NIC3_R      PU74  -15         A01X+091349Y+045841X0100Y0320R090 S1      
317P12V_NIC3_R      VIA   -    MD0100PA00X+090745Y+046006X0200Y    R270 S0      
317P12V_NIC3_R      VIA   -    MD0100PA00X+091025Y+046006X0200Y    R270 S0      
327P12V_NIC3_R      PR6887-1          A01X+089649Y+046180X0198Y0197R090 S1      
327P12V_NIC3_R      PR6888-2          A01X+091342Y+047944X0198Y0197R180 S1      
317P12V_NIC3_R      VIA   -    MD0100PA00X+089090Y+046023X0200Y    R270 S0      
327P12V_NIC3_R      PC621 -1          A01X+087488Y+046068X0400Y0500R270 S1      
327P12V_NIC3_R      PC345 -1          A01X+086688Y+046068X0400Y0500R270 S1      
317P12V_NIC3_R      VIA   -    MD0100PA00X+087088Y+046179X0200Y    R270 S0      
317P12V_NIC3_R      VIA   -    MD0100PA00X+088091Y+046023X0200Y    R270 S0      
327P12V_NIC3_R      PC622 -1          A01X+085888Y+046068X0400Y0500R270 S1      
317P12V_NIC3_R      VIA   -    MD0100PA00X+085488Y+046179X0200Y    R270 S0      
317P12V_NIC3_R      VIA   -    MD0100PA00X+086288Y+046179X0200Y    R270 S0      
327P12V_NIC3_R      PC627 -1          A01X+090717Y+044875X0198Y0197R270 S1      
327P12V_NIC3_R      PU74  -16         A01X+091349Y+045644X0100Y0320R090 S1      
327P12V_NIC3_R      PU74  -17         A01X+091349Y+045447X0100Y0320R090 S1      
327P12V_NIC3_R      PU74  -18         A01X+091349Y+045250X0100Y0320R090 S1      
327P12V_NIC3_R      PU74  -19         A01X+091349Y+045054X0100Y0320R090 S1      
327P12V_NIC3_R      PU74  -20         A01X+091349Y+044857X0100Y0320R090 S1      
317P12V_NIC3_R      VIA   -    MD0100PA00X+090745Y+045166X0200Y    R270 S0      
317P12V_NIC3_R      VIA   -    MD0100PA00X+091025Y+045166X0200Y    R270 S0      
317P12V_NIC3_R      VIA   -    MD0100PA00X+090745Y+045726X0200Y    R270 S0      
317P12V_NIC3_R      VIA   -    MD0100PA00X+090745Y+045446X0200Y    R270 S0      
317P12V_NIC3_R      VIA   -    MD0100PA00X+091025Y+045446X0200Y    R270 S0      
317P12V_NIC3_R      VIA   -    MD0100PA00X+091025Y+045726X0200Y    R270 S0      
327P12V_NIC3_R      PD18  -C          A01X+088580Y+045380X0670Y0990     S1      
317P12V_NIC3_R      VIA   -    MD0100PA00X+089090Y+045743X0200Y    R270 S0      
317P12V_NIC3_R      VIA   -    MD0100PA00X+089090Y+045463X0200Y    R270 S0      
317P12V_NIC3_R      VIA   -    MD0100PA00X+088091Y+045743X0200Y    R270 S0      
317P12V_NIC3_R      VIA   -    MD0100PA00X+088091Y+045463X0200Y    R270 S0      
317P12V_NIC3_R      VIA   -    MD0100PA00X+087088Y+045899X0200Y    R270 S0      
317P12V_NIC3_R      VIA   -    MD0100PA00X+085488Y+045899X0200Y    R270 S0      
317P12V_NIC3_R      VIA   -    MD0100PA00X+086288Y+045899X0200Y    R270 S0      
327P12V_NIC3_R      PD83  -C          A01X+087731Y+043229X0670Y0990R270 S1      
317P12V_NIC3_R      VIA   -    MD0100PA00X+087627Y+042695X0200Y         S0      
317P12V_NIC3_R      VIA   -    MD0100PA00X+087377Y+042695X0200Y         S0      
317P12V_NIC3_R      VIA   -    MD0100PA00X+087854Y+043741X0200Y         S0      
317P12V_NIC3_R      VIA   -    MD0100PA00X+088104Y+043741X0200Y         S0      
317P12V_NIC3_R      VIA   -    MD0100PA00X+087604Y+043741X0200Y         S0      
317P12V_NIC3_R      VIA   -    MD0100PA00X+087354Y+043741X0200Y         S0      
317P12V_NIC3_R      VIA   -    MD0100PA00X+087877Y+042695X0200Y         S0      
317P12V_NIC3_R      VIA   -    MD0100PA00X+088127Y+042695X0200Y         S0      
327P12V_NIC3_R      PC344 -1          A01X+088216Y+041526X0198Y0197     S1      
327P12V_NIC3_R      PC626 -1          A01X+088109Y+042148X0400Y0500R180 S1      
317P12V_NIC3_R      VIA   -    MD0100PA00X+087725Y+042288X0200Y    R270 S0      
317P12V_NIC3_R      VIA   -    M      A01X+087425Y+042008X0200Y    R270 S2      
017P12V_NIC3_R      VIA   -    M      A18X+087425Y+042008X0260Y    R270 S2      
017P12V_NIC3_R            -    MD0100PA00X+087425Y+042008                       
317P12V_NIC3_R      VIA   -    MD0100PA00X+087425Y+042288X0200Y    R270 S0      
317P12V_NIC3_R      VIA   -    MD0100PA00X+087869Y+041162X0200Y         S0      
317P12V_NIC3_R      VIA   -    MD0100PA00X+088119Y+041162X0200Y         S0      
317P12V_NIC3_R      VIA   -    MD0100PA00X+087942Y+041532X0200Y         S0      
317P12V_NIC3_R      VIA   -    MD0100PA00X+087692Y+041532X0200Y         S0      
317P12V_NIC3_R      VIA   -    MD0100PA00X+087725Y+042038X0200Y    R270 S0      
327P12V_NIC3_R      C419  -1          A01X+086166Y+041453X0198Y0197     S1      
327P12V_NIC3_R      R716  -2          A01X+085763Y+042936X1150Y1380     S1      
317P12V_NIC3_R      VIA   -    MD0100PA00X+086162Y+041969X0200Y    R270 S0      
317P12V_NIC3_R      VIA   -    MD0100PA00X+085877Y+041668X0200Y    R270 S0      
317P12V_NIC3_R      VIA   -    MD0100PA00X+085841Y+041389X0200Y    R270 S0      
317P12V_NIC3_R      VIA   -    MD0100PA00X+085883Y+041990X0200Y    R270 S0      
317P12V_NIC3_R      VIA   -    MD0100PA00X+086141Y+041707X0200Y    R270 S0      
327P12V_NIC3_R      U82   -11         A01X+085927Y+040804X0090Y0240     S1      
317m2663            VIA   -    M      A01X+167464Y+018383X0200Y         S2      
017m2663            VIA   -    M      A18X+167464Y+018383X0260Y         S2      
017m2663                  -    MD0100PA00X+167464Y+018383                       
327m2663            R662  -1          A01X+167773Y+018466X0198Y0197     S1      
327m2663            U77   -3          A01X+167144Y+018383X0090Y0240R090 S1      
317m2664            VIA   -    M      A01X+177124Y+019249X0200Y         S2      
017m2664            VIA   -    M      A18X+177124Y+019249X0260Y         S2      
017m2664                  -    MD0100PA00X+177124Y+019249                       
327m2664            U78   -5          A01X+177124Y+018836X0090Y0240R180 S1      
327m2664            R676  -2          A01X+178009Y+019666X0198Y0197R180 S1      
327m2664            R5909 -2   M      A01X+177592Y+019662X0198Y0197     S1      
317m2664            VIA   -    MD0100PA00X+177171Y+017152X0200Y         S0      
327m2664            R5908 -2          A01X+177171Y+016871X0198Y0197R180 S1      
317m2665            VIA   -    M      A01X+175943Y+017219X0200Y         S2      
017m2665            VIA   -    M      A18X+175943Y+017219X0260Y         S2      
017m2665                  -    MD0100PA00X+175943Y+017219                       
327m2665            R678  -2          A01X+175600Y+016870X0198Y0197R180 S1      
327m2665            C408  -1   M      A01X+175606Y+017300X0198Y0197R090 S1      
327m2665            U78   -13         A01X+176534Y+017734X0090Y0240R180 S1      
327P12V_NIC2_R      PU26  -1          A01X+050722Y+053452X0110Y0240R090 S1      
327P12V_NIC2_R      PU26  -2          A01X+050722Y+053649X0110Y0240R090 S1      
327P12V_NIC2_R      PU26  -3          A01X+050722Y+053846X0110Y0240R090 S1      
327P12V_NIC2_R      PU26  -4          A01X+050722Y+054042X0110Y0240R090 S1      
327P12V_NIC2_R      PU26  -5          A01X+050722Y+054239X0110Y0240R090 S1      
327P12V_NIC2_R      PC620 -1          A01X+051420Y+060831X0198Y0197     S1      
327P12V_NIC2_R      PU73  -17         A01X+050825Y+061380X0100Y0320R180 S1      
327P12V_NIC2_R      PU73  -18         A01X+051022Y+061380X0100Y0320R180 S1      
327P12V_NIC2_R      PU73  -19         A01X+051218Y+061380X0100Y0320R180 S1      
327P12V_NIC2_R      PU73  -20         A01X+051415Y+061380X0100Y0320R180 S1      
327P12V_NIC2_R      PU73  -13         A01X+050037Y+061380X0100Y0320R180 S1      
327P12V_NIC2_R      PU73  -14         A01X+050234Y+061380X0100Y0320R180 S1      
327P12V_NIC2_R      PU73  -15         A01X+050431Y+061380X0100Y0320R180 S1      
327P12V_NIC2_R      PU73  -16         A01X+050628Y+061380X0100Y0320R180 S1      
327P12V_NIC2_R      PR6885-1          A01X+050076Y+059739X0198Y0197R180 S1      
327P12V_NIC2_R      C416  -1          A01X+052918Y+057584X0198Y0197R180 S1      
327P12V_NIC2_R      U81   -11         A01X+053157Y+058234X0090Y0240R180 S1      
327P12V_NIC2_R      PC625 -1          A01X+050204Y+057519X0400Y0500     S1      
327P12V_NIC2_R      PD82  -C          A01X+050492Y+058611X0670Y0990R090 S1      
327P12V_NIC2_R      PC623 -1          A01X+050204Y+055919X0400Y0500     S1      
327P12V_NIC2_R      PC624 -1          A01X+050204Y+056719X0400Y0500     S1      
327P12V_NIC2_R      R704  -2          A01X+052424Y+056085X1150Y1380R180 S1      
327P12V_NIC2_R      PD14  -C          A01X+053063Y+054184X0670Y0990R180 S1      
327P12V_NIC2_R      PC332 -1          A01X+051360Y+053698X0198Y0197R270 S1      
327P12V_NIC2_R      PC333 -1          A01X+051982Y+053806X0400Y0500R090 S1      
317P12V_NIC2_R      VIA   -    MD0100PA00X+050826Y+060776X0200Y         S0      
317P12V_NIC2_R      VIA   -    MD0100PA00X+050826Y+061056X0200Y         S0      
317P12V_NIC2_R      VIA   -    MD0100PA00X+051106Y+060776X0200Y         S0      
317P12V_NIC2_R      VIA   -    MD0100PA00X+051106Y+061056X0200Y         S0      
317P12V_NIC2_R      VIA   -    MD0100PA00X+050546Y+060776X0200Y         S0      
317P12V_NIC2_R      VIA   -    MD0100PA00X+050266Y+060776X0200Y         S0      
317P12V_NIC2_R      VIA   -    MD0100PA00X+050266Y+061056X0200Y         S0      
317P12V_NIC2_R      VIA   -    MD0100PA00X+050546Y+061056X0200Y         S0      
317P12V_NIC2_R      VIA   -    MD0100PA00X+050809Y+059122X0200Y         S0      
317P12V_NIC2_R      VIA   -    MD0100PA00X+050249Y+059122X0200Y         S0      
317P12V_NIC2_R      VIA   -    MD0100PA00X+050529Y+059122X0200Y         S0      
317P12V_NIC2_R      VIA   -    MD0100PA00X+053243Y+057648X0200Y    R090 S0      
327P12V_NIC2_R      R711  -1          A01X+054474Y+057871X0198Y0197R270 S1      
317P12V_NIC2_R      VIA   -    MD0100PA00X+054474Y+058166X0200Y    R090 S0      
317P12V_NIC2_R      VIA   -    MD0100PA00X+053207Y+057369X0200Y    R090 S0      
317P12V_NIC2_R      VIA   -    MD0100PA00X+052942Y+057330X0200Y    R090 S0      
317P12V_NIC2_R      VIA   -    MD0100PA00X+050809Y+058122X0200Y         S0      
317P12V_NIC2_R      VIA   -    MD0100PA00X+050249Y+058122X0200Y         S0      
317P12V_NIC2_R      VIA   -    MD0100PA00X+050529Y+058122X0200Y         S0      
317P12V_NIC2_R      VIA   -    MD0100PA00X+052921Y+057069X0200Y    R090 S0      
317P12V_NIC2_R      VIA   -    MD0100PA00X+053201Y+057048X0200Y    R090 S0      
317P12V_NIC2_R      VIA   -    MD0100PA00X+050093Y+056319X0200Y         S0      
317P12V_NIC2_R      VIA   -    MD0100PA00X+050373Y+056319X0200Y         S0      
317P12V_NIC2_R      VIA   -    MD0100PA00X+050373Y+057119X0200Y         S0      
317P12V_NIC2_R      VIA   -    MD0100PA00X+050093Y+057119X0200Y         S0      
317P12V_NIC2_R      VIA   -    MD0100PA00X+053099Y+054834X0200Y         S0      
317P12V_NIC2_R      VIA   -    MD0100PA00X+052599Y+054834X0200Y         S0      
317P12V_NIC2_R      VIA   -    MD0100PA00X+052849Y+054834X0200Y         S0      
317P12V_NIC2_R      VIA   -    MD0100PA00X+052529Y+054288X0200Y    R270 S0      
317P12V_NIC2_R      VIA   -    MD0100PA00X+052529Y+054538X0200Y    R270 S0      
317P12V_NIC2_R      VIA   -    MD0100PA00X+052529Y+054038X0200Y    R270 S0      
317P12V_NIC2_R      VIA   -    MD0100PA00X+050996Y+054046X0200Y    R270 S0      
317P12V_NIC2_R      VIA   -    M      A01X+051842Y+054490X0200Y    R180 S2      
017P12V_NIC2_R      VIA   -    M      A18X+051842Y+054490X0260Y    R180 S2      
017P12V_NIC2_R            -    MD0100PA00X+051842Y+054490                       
317P12V_NIC2_R      VIA   -    MD0100PA00X+051366Y+054223X0200Y    R270 S0      
317P12V_NIC2_R      VIA   -    MD0100PA00X+052122Y+054190X0200Y    R180 S0      
317P12V_NIC2_R      VIA   -    MD0100PA00X+052122Y+054490X0200Y    R180 S0      
317P12V_NIC2_R      VIA   -    MD0100PA00X+051872Y+054190X0200Y    R180 S0      
317P12V_NIC2_R      VIA   -    MD0100PA00X+050093Y+055519X0200Y         S0      
317P12V_NIC2_R      VIA   -    MD0100PA00X+050373Y+055519X0200Y         S0      
317P12V_NIC2_R      VIA   -    MD0100PA00X+053349Y+054834X0200Y         S0      
317P12V_NIC2_R      VIA   -    MD0100PA00X+052529Y+053788X0200Y    R270 S0      
317P12V_NIC2_R      VIA   -    MD0100PA00X+051366Y+053973X0200Y    R270 S0      
317P12V_NIC2_R      VIA   -    MD0100PA00X+050996Y+053796X0200Y    R270 S0      
327P12V_NIC2_R      PR6886-2          A01X+048328Y+061374X0198Y0197R270 S1      
317m2666            VIA   -    M      A01X+145176Y+017762X0200Y         S2      
017m2666            VIA   -    M      A18X+145176Y+017762X0260Y         S2      
017m2666                  -    MD0100PA00X+145176Y+017762                       
327m2666            R646  -2          A01X+144497Y+017615X0198Y0197R090 S1      
327m2666            U75   -12         A01X+145569Y+017990X0090Y0240R090 S1      
327m2666            C335  -2   M      A01X+144897Y+017615X0198Y0197R090 S1      
317m2667            VIA   -    M      A01X+133030Y+074633X0200Y         S2      
017m2667            VIA   -    M      A18X+133030Y+074633X0260Y         S2      
017m2667                  -    MD0100PA00X+133030Y+074633                       
327m2667            R4239 -2          A01X+133922Y+074168X0198Y0197R180 S1      
327m2667            U324  -14         A01X+132128Y+075096X0160Y0540R270 S1      
317m2668            VIA   -    M      A01X+131416Y+019249X0200Y         S2      
017m2668            VIA   -    M      A18X+131416Y+019249X0260Y         S2      
017m2668                  -    MD0100PA00X+131416Y+019249                       
327m2668            R632  -2          A01X+132301Y+019666X0198Y0197R180 S1      
327m2668            R5903 -2   M      A01X+131883Y+019662X0198Y0197     S1      
327m2668            U74   -5          A01X+131416Y+018836X0090Y0240R180 S1      
317m2669            VIA   -    M      A01X+157228Y+018383X0200Y         S2      
017m2669            VIA   -    M      A18X+157228Y+018383X0260Y         S2      
017m2669                  -    MD0100PA00X+157228Y+018383                       
327m2669            R653  -1          A01X+157537Y+018466X0198Y0197     S1      
327m2669            U76   -3          A01X+156908Y+018383X0090Y0240R090 S1      
317m2670            VIA   -    M      A01X+131463Y+017152X0200Y         S2      
017m2670            VIA   -    M      A18X+131463Y+017152X0260Y         S2      
017m2670                  -    MD0100PA00X+131463Y+017152                       
327m2670            R5902 -2          A01X+131463Y+016871X0198Y0197R180 S1      
317m2670            VIA   -    MD0100PA00X+131943Y+019018X0200Y         S0      
327m2670            U74   -4          A01X+131672Y+018580X0090Y0240R090 S1      
327m2670            R633  -2          A01X+132301Y+019266X0198Y0197R180 S1      
317m2671            VIA   -    M      A01X+165649Y+017762X0200Y         S2      
017m2671            VIA   -    M      A18X+165649Y+017762X0260Y         S2      
017m2671                  -    MD0100PA00X+165649Y+017762                       
327m2671            R668  -2          A01X+164970Y+017615X0198Y0197R090 S1      
327m2671            C405  -2   M      A01X+165370Y+017615X0198Y0197R090 S1      
327m2671            U77   -12         A01X+166042Y+017990X0090Y0240R090 S1      
317m2672            VIA   -    M      A01X+101283Y+018383X0200Y         S2      
017m2672            VIA   -    M      A18X+101283Y+018383X0260Y         S2      
017m2672                  -    MD0100PA00X+101283Y+018383                       
327m2672            U71   -3          A01X+100963Y+018383X0090Y0240R090 S1      
327m2672            R596  -1          A01X+101592Y+018466X0198Y0197     S1      
317m2673            VIA   -    M      A01X+146991Y+018383X0200Y         S2      
017m2673            VIA   -    M      A18X+146991Y+018383X0260Y         S2      
017m2673                  -    MD0100PA00X+146991Y+018383                       
327m2673            R642  -1          A01X+147301Y+018466X0198Y0197     S1      
327m2673            U75   -3          A01X+146672Y+018383X0090Y0240R090 S1      
327P12V_NIC1_R      PU24  -1          A01X+038930Y+039554X0110Y0240R180 S1      
327P12V_NIC1_R      PU24  -2          A01X+038734Y+039554X0110Y0240R180 S1      
327P12V_NIC1_R      PU24  -3          A01X+038537Y+039554X0110Y0240R180 S1      
327P12V_NIC1_R      PU24  -4          A01X+038340Y+039554X0110Y0240R180 S1      
327P12V_NIC1_R      PU24  -5          A01X+038143Y+039554X0110Y0240R180 S1      
327P12V_NIC1_R      PU72  -13         A01X+041816Y+044601X0100Y0320R090 S1      
327P12V_NIC1_R      PU72  -14         A01X+041816Y+044404X0100Y0320R090 S1      
327P12V_NIC1_R      PR6863-1          A01X+040116Y+044546X0198Y0197R090 S1      
327P12V_NIC1_R      PR6864-2          A01X+041810Y+046310X0198Y0197R180 S1      
327P12V_NIC1_R      PC607 -1          A01X+041185Y+043241X0198Y0197R270 S1      
327P12V_NIC1_R      PU72  -15         A01X+041816Y+044207X0100Y0320R090 S1      
327P12V_NIC1_R      PU72  -16         A01X+041816Y+044010X0100Y0320R090 S1      
327P12V_NIC1_R      PU72  -17         A01X+041816Y+043813X0100Y0320R090 S1      
327P12V_NIC1_R      PU72  -18         A01X+041816Y+043616X0100Y0320R090 S1      
327P12V_NIC1_R      PU72  -19         A01X+041816Y+043420X0100Y0320R090 S1      
327P12V_NIC1_R      PU72  -20         A01X+041816Y+043223X0100Y0320R090 S1      
327P12V_NIC1_R      PC605 -1          A01X+037992Y+044100X0400Y0500R270 S1      
327P12V_NIC1_R      PD10  -C          A01X+039052Y+043746X0670Y0990     S1      
327P12V_NIC1_R      PC606 -1          A01X+037192Y+044100X0400Y0500R270 S1      
327P12V_NIC1_R      PC604 -1          A01X+036204Y+043440X0400Y0500R270 S1      
327P12V_NIC1_R      PD79  -C          A01X+038198Y+041895X0670Y0990R270 S1      
327P12V_NIC1_R      R693  -2          A01X+036520Y+042244X1150Y1380     S1      
327P12V_NIC1_R      PC321 -1          A01X+038577Y+040814X0400Y0500R180 S1      
327P12V_NIC1_R      PC320 -1          A01X+038684Y+040192X0198Y0197     S1      
327P12V_NIC1_R      C413  -1          A01X+036140Y+040653X0198Y0197     S1      
327P12V_NIC1_R      U80   -11         A01X+035851Y+040004X0090Y0240     S1      
317P12V_NIC1_R      VIA   -    MD0100PA00X+041212Y+044372X0200Y    R270 S0      
317P12V_NIC1_R      VIA   -    MD0100PA00X+041492Y+044372X0200Y    R270 S0      
317P12V_NIC1_R      VIA   -    MD0100PA00X+039558Y+044389X0200Y    R270 S0      
317P12V_NIC1_R      VIA   -    MD0100PA00X+038558Y+044389X0200Y    R270 S0      
317P12V_NIC1_R      VIA   -    MD0100PA00X+041212Y+044092X0200Y    R270 S0      
317P12V_NIC1_R      VIA   -    MD0100PA00X+041492Y+044092X0200Y    R270 S0      
317P12V_NIC1_R      VIA   -    MD0100PA00X+041212Y+043812X0200Y    R270 S0      
317P12V_NIC1_R      VIA   -    MD0100PA00X+041212Y+043532X0200Y    R270 S0      
317P12V_NIC1_R      VIA   -    MD0100PA00X+041492Y+043812X0200Y    R270 S0      
317P12V_NIC1_R      VIA   -    MD0100PA00X+041492Y+043532X0200Y    R270 S0      
317P12V_NIC1_R      VIA   -    MD0100PA00X+039558Y+044109X0200Y    R270 S0      
317P12V_NIC1_R      VIA   -    MD0100PA00X+039558Y+043829X0200Y    R270 S0      
317P12V_NIC1_R      VIA   -    MD0100PA00X+038558Y+044109X0200Y    R270 S0      
317P12V_NIC1_R      VIA   -    MD0100PA00X+038558Y+043829X0200Y    R270 S0      
317P12V_NIC1_R      VIA   -    MD0100PA00X+036792Y+044212X0200Y    R270 S0      
317P12V_NIC1_R      VIA   -    MD0100PA00X+037592Y+043932X0200Y    R270 S0      
317P12V_NIC1_R      VIA   -    MD0100PA00X+037592Y+044212X0200Y    R270 S0      
317P12V_NIC1_R      VIA   -    MD0100PA00X+036792Y+043932X0200Y    R270 S0      
317P12V_NIC1_R      VIA   -    MD0100PA00X+035804Y+043552X0200Y    R270 S0      
317P12V_NIC1_R      VIA   -    MD0100PA00X+035766Y+042669X0200Y         S0      
317P12V_NIC1_R      VIA   -    MD0100PA00X+035804Y+043272X0200Y    R270 S0      
317P12V_NIC1_R      VIA   -    MD0100PA00X+038344Y+041361X0200Y         S0      
317P12V_NIC1_R      VIA   -    MD0100PA00X+038594Y+041361X0200Y         S0      
317P12V_NIC1_R      VIA   -    MD0100PA00X+038094Y+041361X0200Y         S0      
317P12V_NIC1_R      VIA   -    MD0100PA00X+037844Y+041361X0200Y         S0      
317P12V_NIC1_R      VIA   -    MD0100PA00X+038321Y+042407X0200Y         S0      
317P12V_NIC1_R      VIA   -    MD0100PA00X+038571Y+042407X0200Y         S0      
317P12V_NIC1_R      VIA   -    MD0100PA00X+038071Y+042407X0200Y         S0      
317P12V_NIC1_R      VIA   -    MD0100PA00X+037821Y+042407X0200Y         S0      
317P12V_NIC1_R      VIA   -    MD0100PA00X+035766Y+041109X0200Y         S0      
317P12V_NIC1_R      VIA   -    MD0100PA00X+035766Y+042409X0200Y         S0      
317P12V_NIC1_R      VIA   -    MD0100PA00X+035766Y+041889X0200Y         S0      
317P12V_NIC1_R      VIA   -    MD0100PA00X+035766Y+042149X0200Y         S0      
317P12V_NIC1_R      VIA   -    MD0100PA00X+035766Y+041629X0200Y         S0      
317P12V_NIC1_R      VIA   -    MD0100PA00X+035766Y+041369X0200Y         S0      
317P12V_NIC1_R      VIA   -    MD0100PA00X+038409Y+040198X0200Y         S0      
317P12V_NIC1_R      VIA   -    MD0100PA00X+038159Y+040198X0200Y         S0      
317P12V_NIC1_R      VIA   -    MD0100PA00X+038193Y+040704X0200Y    R270 S0      
317P12V_NIC1_R      VIA   -    MD0100PA00X+038193Y+040954X0200Y    R270 S0      
317P12V_NIC1_R      VIA   -    MD0100PA00X+037893Y+040954X0200Y    R270 S0      
317P12V_NIC1_R      VIA   -    MD0100PA00X+038336Y+039828X0200Y         S0      
317P12V_NIC1_R      VIA   -    MD0100PA00X+038586Y+039828X0200Y         S0      
317P12V_NIC1_R      VIA   -    M      A01X+037893Y+040674X0200Y    R270 S2      
017P12V_NIC1_R      VIA   -    M      A18X+037893Y+040674X0260Y    R270 S2      
017P12V_NIC1_R            -    MD0100PA00X+037893Y+040674                       
317P12V_NIC1_R      VIA   -    MD0100PA00X+035825Y+040330X0200Y    R270 S0      
317P12V_NIC1_R      VIA   -    MD0100PA00X+035766Y+040849X0200Y         S0      
317P12V_NIC1_R      VIA   -    MD0100PA00X+035766Y+040589X0200Y    R270 S0      
317P12V_NIC1_R      VIA   -    MD0100PA00X+034759Y+039153X0200Y    R270 S0      
327P12V_NIC1_R      R700  -1          A01X+034759Y+039393X0198Y0197R090 S1      
317m2674            VIA   -    M      A01X+121755Y+018383X0200Y         S2      
017m2674            VIA   -    M      A18X+121755Y+018383X0260Y         S2      
017m2674                  -    MD0100PA00X+121755Y+018383                       
327m2674            R618  -1          A01X+122064Y+018466X0198Y0197     S1      
327m2674            U73   -3          A01X+121435Y+018383X0090Y0240R090 S1      
317m2675            VIA   -    M      A01X+146943Y+019018X0200Y         S2      
017m2675            VIA   -    M      A18X+146943Y+019018X0260Y         S2      
017m2675                  -    MD0100PA00X+146943Y+019018                       
327m2675            U75   -4          A01X+146672Y+018580X0090Y0240R090 S1      
327m2675            R644  -2          A01X+147301Y+019266X0198Y0197R180 S1      
327P12V_SSD8_R      PU38  -1          A01X+099743Y+021907X0110Y0240R270 S1      
327P12V_SSD8_R      PU38  -2          A01X+099743Y+021710X0110Y0240R270 S1      
327P12V_SSD8_R      PU38  -3          A01X+099743Y+021513X0110Y0240R270 S1      
327P12V_SSD8_R      PU38  -4          A01X+099743Y+021317X0110Y0240R270 S1      
327P12V_SSD8_R      PU38  -5          A01X+099743Y+021120X0110Y0240R270 S1      
317P12V_SSD8_R      VIA   -    MD0100PA00X+097336Y+026407X0200Y         S0      
317P12V_SSD8_R      VIA   -    MD0100PA00X+097086Y+026407X0200Y         S0      
317P12V_SSD8_R      VIA   -    MD0100PA00X+098113Y+026753X0200Y         S0      
317P12V_SSD8_R      VIA   -    MD0100PA00X+098643Y+026753X0200Y         S0      
317P12V_SSD8_R      VIA   -    MD0100PA00X+098393Y+026753X0200Y         S0      
317P12V_SSD8_R      VIA   -    MD0100PA00X+098113Y+027003X0200Y         S0      
317P12V_SSD8_R      VIA   -    MD0100PA00X+098393Y+027003X0200Y         S0      
317P12V_SSD8_R      VIA   -    MD0100PA00X+098643Y+027003X0200Y         S0      
327P12V_SSD8_R      PD38  -C          A01X+097379Y+027104X0670Y0990     S1      
327P12V_SSD8_R      PU111 -6_7        A01X+099370Y+027354X0295Y0354R090 S1      
327P12V_SSD8_R      PC405 -1          A01X+098441Y+027416X0400Y0500R270 S1      
327P12V_SSD8_R      R5998 -1          A01X+094572Y+023687X0198Y0197R180 S1      
317P12V_SSD8_R      VIA   -    MD0100PA00X+093340Y+024551X0200Y         S0      
327P12V_SSD8_R      R601  -1          A01X+099498Y+016870X0198Y0197R180 S1      
317P12V_SSD8_R      VIA   -    MD0100PA00X+099793Y+016870X0200Y         S0      
327P12V_SSD8_R      PC404 -1          A01X+099105Y+021661X0198Y0197R090 S1      
327P12V_SSD8_R      PC861 -1          A01X+098483Y+021554X0400Y0500R270 S1      
327P12V_SSD8_R      PD111 -C          A01X+097402Y+021175X0670Y0990     S1      
327P12V_SSD8_R      C322  -1          A01X+099211Y+018426X0198Y0197R090 S1      
327P12V_SSD8_R      R593  -2          A01X+097712Y+018919X1150Y1380R090 S1      
327P12V_SSD8_R      U71   -11         A01X+099861Y+018187X0090Y0240R090 S1      
317P12V_SSD8_R      VIA   -    MD0100PA00X+099470Y+021563X0200Y    R090 S0      
317P12V_SSD8_R      VIA   -    MD0100PA00X+097936Y+021571X0200Y    R090 S0      
317P12V_SSD8_R      VIA   -    MD0100PA00X+098343Y+021170X0200Y         S0      
317P12V_SSD8_R      VIA   -    MD0100PA00X+099099Y+021136X0200Y    R090 S0      
317P12V_SSD8_R      VIA   -    MD0100PA00X+099099Y+021386X0200Y    R090 S0      
317P12V_SSD8_R      VIA   -    MD0100PA00X+098593Y+021170X0200Y         S0      
317P12V_SSD8_R      VIA   -    MD0100PA00X+098343Y+020870X0200Y         S0      
317P12V_SSD8_R      VIA   -    M      A01X+098623Y+020870X0200Y         S2      
017P12V_SSD8_R      VIA   -    M      A18X+098623Y+020870X0260Y         S2      
017P12V_SSD8_R            -    MD0100PA00X+098623Y+020870                       
317P12V_SSD8_R      VIA   -    MD0100PA00X+097936Y+021321X0200Y    R090 S0      
317P12V_SSD8_R      VIA   -    MD0100PA00X+097936Y+021071X0200Y    R090 S0      
317P12V_SSD8_R      VIA   -    MD0100PA00X+097936Y+020821X0200Y    R090 S0      
317P12V_SSD8_R      VIA   -    MD0100PA00X+099470Y+021313X0200Y    R090 S0      
317P12V_SSD8_R      VIA   -    MD0100PA00X+096891Y+021048X0200Y    R090 S0      
317P12V_SSD8_R      VIA   -    MD0100PA00X+096891Y+021548X0200Y    R090 S0      
317P12V_SSD8_R      VIA   -    MD0100PA00X+096891Y+021298X0200Y    R090 S0      
317P12V_SSD8_R      VIA   -    MD0100PA00X+096891Y+020798X0200Y    R090 S0      
317P12V_SSD8_R      VIA   -    MD0100PA00X+098957Y+018401X0200Y         S0      
317P12V_SSD8_R      VIA   -    MD0100PA00X+098696Y+018422X0200Y         S0      
317P12V_SSD8_R      VIA   -    MD0100PA00X+099275Y+018101X0200Y         S0      
317P12V_SSD8_R      VIA   -    MD0100PA00X+098675Y+018143X0200Y         S0      
317P12V_SSD8_R      VIA   -    MD0100PA00X+098996Y+018137X0200Y         S0      
317m2676            VIA   -    M      A01X+175885Y+017762X0200Y         S2      
017m2676            VIA   -    M      A18X+175885Y+017762X0260Y         S2      
017m2676                  -    MD0100PA00X+175885Y+017762                       
327m2676            R679  -2          A01X+175206Y+017615X0198Y0197R090 S1      
327m2676            C408  -2   M      A01X+175606Y+017615X0198Y0197R090 S1      
327m2676            U78   -12         A01X+176278Y+017990X0090Y0240R090 S1      
327P12V_NIC6_R      PU27  -1          A01X+142140Y+053452X0110Y0240R090 S1      
327P12V_NIC6_R      PU27  -2          A01X+142140Y+053649X0110Y0240R090 S1      
327P12V_NIC6_R      PU27  -3          A01X+142140Y+053846X0110Y0240R090 S1      
327P12V_NIC6_R      PU27  -4          A01X+142140Y+054042X0110Y0240R090 S1      
327P12V_NIC6_R      PU27  -5          A01X+142140Y+054239X0110Y0240R090 S1      
327P12V_NIC6_R      PC820 -1          A01X+142838Y+060831X0198Y0197     S1      
327P12V_NIC6_R      PU105 -15         A01X+141848Y+061380X0100Y0320R180 S1      
327P12V_NIC6_R      PU105 -16         A01X+142045Y+061380X0100Y0320R180 S1      
327P12V_NIC6_R      PU105 -17         A01X+142242Y+061380X0100Y0320R180 S1      
327P12V_NIC6_R      PU105 -18         A01X+142439Y+061380X0100Y0320R180 S1      
327P12V_NIC6_R      PU105 -19         A01X+142636Y+061380X0100Y0320R180 S1      
327P12V_NIC6_R      PU105 -20         A01X+142833Y+061380X0100Y0320R180 S1      
327P12V_NIC6_R      PU105 -13         A01X+141455Y+061380X0100Y0320R180 S1      
327P12V_NIC6_R      PU105 -14         A01X+141652Y+061380X0100Y0320R180 S1      
327P12V_NIC6_R      PR7044-1          A01X+141493Y+059739X0198Y0197R180 S1      
327P12V_NIC6_R      C620  -1          A01X+144335Y+057584X0198Y0197R180 S1      
327P12V_NIC6_R      U85   -11         A01X+144574Y+058234X0090Y0240R180 S1      
327P12V_NIC6_R      PC822 -1          A01X+141622Y+057519X0400Y0500     S1      
327P12V_NIC6_R      PD15  -C          A01X+141909Y+058611X0670Y0990R090 S1      
327P12V_NIC6_R      PC335 -1          A01X+141622Y+055919X0400Y0500     S1      
327P12V_NIC6_R      PC823 -1          A01X+141622Y+056719X0400Y0500     S1      
327P12V_NIC6_R      R748  -2          A01X+143842Y+056085X1150Y1380R180 S1      
327P12V_NIC6_R      PD98  -C          A01X+144480Y+054184X0670Y0990R180 S1      
327P12V_NIC6_R      PC334 -1          A01X+142777Y+053698X0198Y0197R270 S1      
327P12V_NIC6_R      PC819 -1          A01X+143399Y+053806X0400Y0500R090 S1      
317P12V_NIC6_R      VIA   -    MD0100PA00X+141963Y+061056X0200Y         S0      
317P12V_NIC6_R      VIA   -    MD0100PA00X+142243Y+061056X0200Y         S0      
317P12V_NIC6_R      VIA   -    MD0100PA00X+142523Y+060776X0200Y         S0      
317P12V_NIC6_R      VIA   -    MD0100PA00X+142523Y+061056X0200Y         S0      
317P12V_NIC6_R      VIA   -    MD0100PA00X+142243Y+060776X0200Y         S0      
317P12V_NIC6_R      VIA   -    MD0100PA00X+141963Y+060776X0200Y         S0      
317P12V_NIC6_R      VIA   -    MD0100PA00X+141683Y+060776X0200Y         S0      
317P12V_NIC6_R      VIA   -    MD0100PA00X+141683Y+061056X0200Y         S0      
317P12V_NIC6_R      VIA   -    MD0100PA00X+141946Y+059122X0200Y         S0      
317P12V_NIC6_R      VIA   -    MD0100PA00X+142226Y+059122X0200Y         S0      
317P12V_NIC6_R      VIA   -    MD0100PA00X+141666Y+059122X0200Y         S0      
317P12V_NIC6_R      VIA   -    MD0100PA00X+144360Y+057330X0200Y    R090 S0      
317P12V_NIC6_R      VIA   -    MD0100PA00X+144624Y+057369X0200Y    R090 S0      
317P12V_NIC6_R      VIA   -    MD0100PA00X+144660Y+057648X0200Y    R090 S0      
317P12V_NIC6_R      VIA   -    MD0100PA00X+141946Y+058122X0200Y         S0      
317P12V_NIC6_R      VIA   -    MD0100PA00X+142226Y+058122X0200Y         S0      
317P12V_NIC6_R      VIA   -    MD0100PA00X+141666Y+058122X0200Y         S0      
317P12V_NIC6_R      VIA   -    MD0100PA00X+144618Y+057048X0200Y    R090 S0      
327P12V_NIC6_R      R755  -1          A01X+145891Y+057871X0198Y0197R270 S1      
317P12V_NIC6_R      VIA   -    MD0100PA00X+145891Y+058166X0200Y    R090 S0      
317P12V_NIC6_R      VIA   -    MD0100PA00X+144339Y+057069X0200Y    R090 S0      
317P12V_NIC6_R      VIA   -    MD0100PA00X+141790Y+057119X0200Y         S0      
317P12V_NIC6_R      VIA   -    MD0100PA00X+141790Y+056319X0200Y         S0      
317P12V_NIC6_R      VIA   -    MD0100PA00X+141510Y+057119X0200Y         S0      
317P12V_NIC6_R      VIA   -    MD0100PA00X+141510Y+056319X0200Y         S0      
317P12V_NIC6_R      VIA   -    MD0100PA00X+143946Y+054538X0200Y    R270 S0      
317P12V_NIC6_R      VIA   -    MD0100PA00X+143946Y+054288X0200Y    R270 S0      
317P12V_NIC6_R      VIA   -    MD0100PA00X+144199Y+054842X0200Y         S0      
317P12V_NIC6_R      VIA   -    MD0100PA00X+143949Y+054842X0200Y         S0      
317P12V_NIC6_R      VIA   -    MD0100PA00X+144449Y+054842X0200Y         S0      
317P12V_NIC6_R      VIA   -    MD0100PA00X+143539Y+054190X0200Y    R180 S0      
317P12V_NIC6_R      VIA   -    MD0100PA00X+143946Y+054038X0200Y    R270 S0      
317P12V_NIC6_R      VIA   -    MD0100PA00X+141790Y+055519X0200Y         S0      
317P12V_NIC6_R      VIA   -    MD0100PA00X+143289Y+054190X0200Y    R180 S0      
317P12V_NIC6_R      VIA   -    MD0100PA00X+142783Y+054223X0200Y    R270 S0      
317P12V_NIC6_R      VIA   -    M      A01X+143539Y+054490X0200Y    R180 S2      
017P12V_NIC6_R      VIA   -    M      A18X+143539Y+054490X0260Y    R180 S2      
017P12V_NIC6_R            -    MD0100PA00X+143539Y+054490                       
317P12V_NIC6_R      VIA   -    MD0100PA00X+143259Y+054490X0200Y    R180 S0      
317P12V_NIC6_R      VIA   -    MD0100PA00X+142413Y+054046X0200Y    R270 S0      
317P12V_NIC6_R      VIA   -    MD0100PA00X+141510Y+055519X0200Y         S0      
317P12V_NIC6_R      VIA   -    MD0100PA00X+143946Y+053788X0200Y    R270 S0      
317P12V_NIC6_R      VIA   -    MD0100PA00X+144699Y+054842X0200Y         S0      
317P12V_NIC6_R      VIA   -    MD0100PA00X+142783Y+053973X0200Y    R270 S0      
317P12V_NIC6_R      VIA   -    MD0100PA00X+142413Y+053766X0200Y    R270 S0      
327P12V_NIC6_R      PR7045-2          A01X+139745Y+061374X0198Y0197R270 S1      
317m2677            VIA   -    M      A01X+100707Y+019249X0200Y         S2      
017m2677            VIA   -    M      A18X+100707Y+019249X0260Y         S2      
017m2677                  -    MD0100PA00X+100707Y+019249                       
327m2677            U71   -5          A01X+100707Y+018836X0090Y0240R180 S1      
327m2677            R599  -2          A01X+101592Y+019666X0198Y0197R180 S1      
317m2678            VIA   -           A01X+083522Y+084772X0200Y         S2      
017m2678            VIA   -           A18X+083522Y+084772X0260Y         S2      
017m2678                  -     D0100PA00X+083522Y+084772                       
327m2678            U89   -1          A01X+083207Y+085928X0110Y0280R180 S1      
317m2679            VIA   -    M      A01X+131991Y+018383X0200Y         S2      
017m2679            VIA   -    M      A18X+131991Y+018383X0260Y         S2      
017m2679                  -    MD0100PA00X+131991Y+018383                       
327m2679            U74   -3          A01X+131672Y+018383X0090Y0240R090 S1      
327m2679            R629  -1          A01X+132301Y+018466X0198Y0197     S1      
317m2680            VIA   -    M      A01X+119940Y+017762X0200Y         S2      
017m2680            VIA   -    M      A18X+119940Y+017762X0260Y         S2      
017m2680                  -    MD0100PA00X+119940Y+017762                       
327m2680            R624  -2          A01X+119261Y+017615X0198Y0197R090 S1      
327m2680            C329  -2   M      A01X+119661Y+017615X0198Y0197R090 S1      
327m2680            U73   -12         A01X+120333Y+017990X0090Y0240R090 S1      
327P12V_SSD10_R     PU42  -1          A01X+120215Y+021907X0110Y0240R270 S1      
327P12V_SSD10_R     PU42  -2          A01X+120215Y+021710X0110Y0240R270 S1      
327P12V_SSD10_R     PU42  -3          A01X+120215Y+021513X0110Y0240R270 S1      
327P12V_SSD10_R     PU42  -4          A01X+120215Y+021317X0110Y0240R270 S1      
327P12V_SSD10_R     PU42  -5          A01X+120215Y+021120X0110Y0240R270 S1      
327P12V_SSD10_R     PU114 -6_7        A01X+119843Y+027354X0295Y0354R090 S1      
327P12V_SSD10_R     PD46  -C          A01X+117851Y+027104X0670Y0990     S1      
327P12V_SSD10_R     PC429 -1          A01X+118913Y+027416X0400Y0500R270 S1      
317P12V_SSD10_R     VIA   -    MD0100PA00X+119115Y+027003X0200Y         S0      
317P12V_SSD10_R     VIA   -    MD0100PA00X+119115Y+026753X0200Y         S0      
317P12V_SSD10_R     VIA   -    MD0100PA00X+118865Y+027003X0200Y         S0      
317P12V_SSD10_R     VIA   -    MD0100PA00X+118585Y+027003X0200Y         S0      
317P12V_SSD10_R     VIA   -    MD0100PA00X+118865Y+026753X0200Y         S0      
317P12V_SSD10_R     VIA   -    MD0100PA00X+118585Y+026753X0200Y         S0      
317P12V_SSD10_R     VIA   -    MD0100PA00X+117946Y+026418X0200Y         S0      
317P12V_SSD10_R     VIA   -    MD0100PA00X+117696Y+026418X0200Y         S0      
317P12V_SSD10_R     VIA   -    MD0100PA00X+112586Y+024837X0200Y         S0      
327P12V_SSD10_R     R6008 -1          A01X+112864Y+024837X0198Y0197     S1      
317P12V_SSD10_R     VIA   -    MD0100PA00X+120265Y+016870X0200Y         S0      
327P12V_SSD10_R     R623  -1          A01X+119971Y+016870X0198Y0197R180 S1      
327P12V_SSD10_R     PC428 -1          A01X+119577Y+021661X0198Y0197R090 S1      
327P12V_SSD10_R     PD114 -C          A01X+117874Y+021175X0670Y0990     S1      
327P12V_SSD10_R     PC872 -1          A01X+118956Y+021554X0400Y0500R270 S1      
327P12V_SSD10_R     C328  -1          A01X+119684Y+018426X0198Y0197R090 S1      
327P12V_SSD10_R     R615  -2          A01X+118184Y+018919X1150Y1380R090 S1      
327P12V_SSD10_R     U73   -11         A01X+120333Y+018187X0090Y0240R090 S1      
317P12V_SSD10_R     VIA   -    MD0100PA00X+119942Y+021563X0200Y    R090 S0      
317P12V_SSD10_R     VIA   -    MD0100PA00X+118409Y+021571X0200Y    R090 S0      
317P12V_SSD10_R     VIA   -    MD0100PA00X+119066Y+021170X0200Y         S0      
317P12V_SSD10_R     VIA   -    MD0100PA00X+119942Y+021313X0200Y    R090 S0      
317P12V_SSD10_R     VIA   -    MD0100PA00X+119572Y+021386X0200Y    R090 S0      
317P12V_SSD10_R     VIA   -    MD0100PA00X+119572Y+021136X0200Y    R090 S0      
317P12V_SSD10_R     VIA   -    MD0100PA00X+118816Y+020870X0200Y         S0      
317P12V_SSD10_R     VIA   -    M      A01X+119096Y+020870X0200Y         S2      
017P12V_SSD10_R     VIA   -    M      A18X+119096Y+020870X0260Y         S2      
017P12V_SSD10_R           -    MD0100PA00X+119096Y+020870                       
317P12V_SSD10_R     VIA   -    MD0100PA00X+118409Y+020821X0200Y    R090 S0      
317P12V_SSD10_R     VIA   -    MD0100PA00X+118409Y+021321X0200Y    R090 S0      
317P12V_SSD10_R     VIA   -    MD0100PA00X+118409Y+021071X0200Y    R090 S0      
317P12V_SSD10_R     VIA   -    MD0100PA00X+118816Y+021170X0200Y         S0      
317P12V_SSD10_R     VIA   -    MD0100PA00X+117363Y+021548X0200Y    R090 S0      
317P12V_SSD10_R     VIA   -    MD0100PA00X+117363Y+021298X0200Y    R090 S0      
317P12V_SSD10_R     VIA   -    MD0100PA00X+117363Y+021048X0200Y    R090 S0      
317P12V_SSD10_R     VIA   -    MD0100PA00X+117363Y+020798X0200Y    R090 S0      
317P12V_SSD10_R     VIA   -    MD0100PA00X+119168Y+018422X0200Y         S0      
317P12V_SSD10_R     VIA   -    MD0100PA00X+119430Y+018401X0200Y         S0      
317P12V_SSD10_R     VIA   -    MD0100PA00X+119748Y+018101X0200Y         S0      
317P12V_SSD10_R     VIA   -    MD0100PA00X+119147Y+018143X0200Y         S0      
317P12V_SSD10_R     VIA   -    MD0100PA00X+119468Y+018137X0200Y         S0      
317m2681            VIA   -           A01X+082354Y+085796X0200Y         S2      
017m2681            VIA   -           A18X+082354Y+085796X0260Y         S2      
017m2681                  -     D0100PA00X+082354Y+085796                       
327m2681            U88   -1          A01X+081998Y+085920X0110Y0280R180 S1      
327m2682            U71   -4          A01X+100963Y+018580X0090Y0240R090 S1      
327m2682            R5898 -2          A01X+101592Y+019266X0198Y0197R180 S1      
317m2682            VIA   -    M      A01X+101235Y+019018X0200Y         S2      
017m2682            VIA   -    M      A18X+101235Y+019018X0260Y         S2      
017m2682                  -    MD0100PA00X+101235Y+019018                       
317m2682            VIA   -    MD0100PA00X+100303Y+019230X0200Y         S0      
327m2682            R600  -2          A01X+100860Y+019662X0198Y0197R180 S1      
317BIC_UART_SEL2    VIA   -    M      A01X+082292Y+085258X0200Y         S2      
017BIC_UART_SEL2    VIA   -    M      A18X+082292Y+085258X0260Y         S2      
017BIC_UART_SEL2          -    MD0100PA00X+082292Y+085258                       
327BIC_UART_SEL2    U89   -5          A01X+082616Y+084865X0110Y0280R180 S1      
327BIC_UART_SEL2    R5918 -1          A01X+081190Y+083692X0198Y0197R180 S1      
327BIC_UART_SEL2    U88   -5   M      A01X+081407Y+084857X0110Y0280R180 S1      
327BIC_UART_SEL2    R5919 -2   M      A01X+081190Y+084092X0198Y0197     S1      
327P12V_SSD11_R     PU44  -1          A01X+130452Y+021907X0110Y0240R270 S1      
327P12V_SSD11_R     PU44  -2          A01X+130452Y+021710X0110Y0240R270 S1      
327P12V_SSD11_R     PU44  -3          A01X+130452Y+021513X0110Y0240R270 S1      
327P12V_SSD11_R     PU44  -4          A01X+130452Y+021317X0110Y0240R270 S1      
327P12V_SSD11_R     PU44  -5          A01X+130452Y+021120X0110Y0240R270 S1      
327P12V_SSD11_R     PC876 -1          A01X+129150Y+027416X0400Y0500R270 S1      
327P12V_SSD11_R     PU113 -6_7        A01X+130079Y+027354X0295Y0354R090 S1      
327P12V_SSD11_R     PD50  -C          A01X+128088Y+027104X0670Y0990     S1      
317P12V_SSD11_R     VIA   -    MD0100PA00X+129102Y+026753X0200Y         S0      
317P12V_SSD11_R     VIA   -    MD0100PA00X+129352Y+026753X0200Y         S0      
317P12V_SSD11_R     VIA   -    MD0100PA00X+128822Y+026753X0200Y         S0      
317P12V_SSD11_R     VIA   -    MD0100PA00X+128822Y+027003X0200Y         S0      
317P12V_SSD11_R     VIA   -    MD0100PA00X+129102Y+027003X0200Y         S0      
317P12V_SSD11_R     VIA   -    MD0100PA00X+129352Y+027003X0200Y         S0      
317P12V_SSD11_R     VIA   -    MD0100PA00X+127932Y+026418X0200Y         S0      
317P12V_SSD11_R     VIA   -    MD0100PA00X+128182Y+026418X0200Y         S0      
317P12V_SSD11_R     VIA   -    MD0100PA00X+122823Y+024837X0200Y         S0      
327P12V_SSD11_R     R6009 -1          A01X+123100Y+024837X0198Y0197     S1      
317P12V_SSD11_R     VIA   -    MD0100PA00X+130502Y+016870X0200Y         S0      
327P12V_SSD11_R     R634  -1          A01X+130207Y+016870X0198Y0197R180 S1      
327P12V_SSD11_R     PC440 -1          A01X+129814Y+021661X0198Y0197R090 S1      
327P12V_SSD11_R     PC441 -1          A01X+129192Y+021554X0400Y0500R270 S1      
327P12V_SSD11_R     PD115 -C          A01X+128111Y+021175X0670Y0990     S1      
327P12V_SSD11_R     C331  -1          A01X+129920Y+018426X0198Y0197R090 S1      
327P12V_SSD11_R     R626  -2          A01X+128420Y+018919X1150Y1380R090 S1      
327P12V_SSD11_R     U74   -11         A01X+130569Y+018187X0090Y0240R090 S1      
317P12V_SSD11_R     VIA   -    MD0100PA00X+130178Y+021563X0200Y    R090 S0      
317P12V_SSD11_R     VIA   -    MD0100PA00X+128645Y+021571X0200Y    R090 S0      
317P12V_SSD11_R     VIA   -    M      A01X+129332Y+020870X0200Y         S2      
017P12V_SSD11_R     VIA   -    M      A18X+129332Y+020870X0260Y         S2      
017P12V_SSD11_R           -    MD0100PA00X+129332Y+020870                       
317P12V_SSD11_R     VIA   -    MD0100PA00X+129052Y+020870X0200Y         S0      
317P12V_SSD11_R     VIA   -    MD0100PA00X+129302Y+021170X0200Y         S0      
317P12V_SSD11_R     VIA   -    MD0100PA00X+129052Y+021170X0200Y         S0      
317P12V_SSD11_R     VIA   -    MD0100PA00X+129808Y+021386X0200Y    R090 S0      
317P12V_SSD11_R     VIA   -    MD0100PA00X+129808Y+021136X0200Y    R090 S0      
317P12V_SSD11_R     VIA   -    MD0100PA00X+130178Y+021313X0200Y    R090 S0      
317P12V_SSD11_R     VIA   -    MD0100PA00X+128645Y+020821X0200Y    R090 S0      
317P12V_SSD11_R     VIA   -    MD0100PA00X+128645Y+021071X0200Y    R090 S0      
317P12V_SSD11_R     VIA   -    MD0100PA00X+128645Y+021321X0200Y    R090 S0      
317P12V_SSD11_R     VIA   -    MD0100PA00X+127599Y+020798X0200Y    R090 S0      
317P12V_SSD11_R     VIA   -    MD0100PA00X+127599Y+021048X0200Y    R090 S0      
317P12V_SSD11_R     VIA   -    MD0100PA00X+127599Y+021298X0200Y    R090 S0      
317P12V_SSD11_R     VIA   -    MD0100PA00X+127599Y+021548X0200Y    R090 S0      
317P12V_SSD11_R     VIA   -    MD0100PA00X+129666Y+018401X0200Y         S0      
317P12V_SSD11_R     VIA   -    MD0100PA00X+129404Y+018422X0200Y         S0      
317P12V_SSD11_R     VIA   -    MD0100PA00X+129704Y+018137X0200Y         S0      
317P12V_SSD11_R     VIA   -    MD0100PA00X+129383Y+018143X0200Y         S0      
317P12V_SSD11_R     VIA   -    MD0100PA00X+129984Y+018101X0200Y         S0      
317m2683            VIA   -    M      A01X+119998Y+017219X0200Y         S2      
017m2683            VIA   -    M      A18X+119998Y+017219X0260Y         S2      
017m2683                  -    MD0100PA00X+119998Y+017219                       
327m2683            R623  -2          A01X+119656Y+016870X0198Y0197R180 S1      
327m2683            U73   -13         A01X+120589Y+017734X0090Y0240R180 S1      
327m2683            C329  -1   M      A01X+119661Y+017300X0198Y0197R090 S1      
317m2684            VIA   -    M      A01X+086235Y+019018X0200Y         S2      
017m2684            VIA   -    M      A18X+086235Y+019018X0260Y         S2      
017m2684                  -    MD0100PA00X+086235Y+019018                       
327m2684            U62   -4          A01X+085963Y+018580X0090Y0240R090 S1      
327m2684            R589  -2          A01X+086592Y+019266X0198Y0197R180 S1      
317m2685            VIA   -    M      A01X+130234Y+017219X0200Y         S2      
017m2685            VIA   -    M      A18X+130234Y+017219X0260Y         S2      
017m2685                  -    MD0100PA00X+130234Y+017219                       
327m2685            R634  -2          A01X+129892Y+016870X0198Y0197R180 S1      
327m2685            U74   -13         A01X+130825Y+017734X0090Y0240R180 S1      
327m2685            C332  -1   M      A01X+129897Y+017300X0198Y0197R090 S1      
317m2686            VIA   -    M      A01X+074231Y+017762X0200Y         S2      
017m2686            VIA   -    M      A18X+074231Y+017762X0260Y         S2      
017m2686                  -    MD0100PA00X+074231Y+017762                       
327m2686            R580  -2          A01X+073552Y+017615X0198Y0197R090 S1      
327m2686            C317  -2   M      A01X+073952Y+017615X0198Y0197R090 S1      
327m2686            U61   -12         A01X+074624Y+017990X0090Y0240R090 S1      
317m2687            VIA   -    M      A01X+099468Y+017762X0200Y         S2      
017m2687            VIA   -    M      A18X+099468Y+017762X0260Y         S2      
017m2687                  -    MD0100PA00X+099468Y+017762                       
327m2687            R602  -2          A01X+098788Y+017615X0198Y0197R090 S1      
327m2687            C323  -2   M      A01X+099188Y+017615X0198Y0197R090 S1      
327m2687            U71   -12         A01X+099861Y+017990X0090Y0240R090 S1      
317SSD7_ADC_A1      VIA   -    M      A01X+086300Y+017266X0200Y         S2      
017SSD7_ADC_A1      VIA   -    M      A18X+086300Y+017266X0260Y         S2      
017SSD7_ADC_A1            -    MD0100PA00X+086300Y+017266                       
327SSD7_ADC_A1      U62   -1          A01X+085963Y+017990X0090Y0240R090 S1      
327SSD7_ADC_A1      R582  -1          A01X+086592Y+016866X0198Y0197     S1      
327SSD7_ADC_A1      R585  -1   M      A01X+086592Y+017266X0198Y0197     S1      
317m2688            VIA   -    M      A01X+121180Y+019249X0200Y         S2      
017m2688            VIA   -    M      A18X+121180Y+019249X0260Y         S2      
017m2688                  -    MD0100PA00X+121180Y+019249                       
327m2688            U73   -5          A01X+121180Y+018836X0090Y0240R180 S1      
327m2688            R621  -2          A01X+121647Y+019662X0198Y0197     S1      
317m2689            VIA   -    M      A01X+065810Y+018383X0200Y         S2      
017m2689            VIA   -    M      A18X+065810Y+018383X0260Y         S2      
017m2689                  -    MD0100PA00X+065810Y+018383                       
327m2689            U60   -3          A01X+065491Y+018383X0090Y0240R090 S1      
327m2689            R565  -1          A01X+066120Y+018466X0198Y0197     S1      
317m2690            VIA   -    M      A01X+053759Y+017762X0200Y         S2      
017m2690            VIA   -    M      A18X+053759Y+017762X0260Y         S2      
017m2690                  -    MD0100PA00X+053759Y+017762                       
327m2690            R558  -2          A01X+053080Y+017615X0198Y0197R090 S1      
327m2690            C311  -2   M      A01X+053480Y+017615X0198Y0197R090 S1      
327m2690            U59   -12         A01X+054152Y+017990X0090Y0240R090 S1      
317SSD8_ADC_A0      VIA   -           A01X+101294Y+017856X0200Y         S2      
017SSD8_ADC_A0      VIA   -           A18X+101294Y+017856X0260Y         S2      
017SSD8_ADC_A0            -     D0100PA00X+101294Y+017856                       
327SSD8_ADC_A0      U71   -2          A01X+100963Y+018187X0090Y0240R090 S1      
327SSD8_ADC_A0      R595  -1          A01X+101592Y+017666X0198Y0197     S1      
327SSD8_ADC_A0      R598  -1   M      A01X+101592Y+018066X0198Y0197     S1      
327P12V_SSD5_R      PU33  -1          A01X+064270Y+021907X0110Y0240R270 S1      
327P12V_SSD5_R      PU33  -2          A01X+064270Y+021710X0110Y0240R270 S1      
327P12V_SSD5_R      PU33  -3          A01X+064270Y+021513X0110Y0240R270 S1      
327P12V_SSD5_R      PU33  -4          A01X+064270Y+021317X0110Y0240R270 S1      
327P12V_SSD5_R      PU33  -5          A01X+064270Y+021120X0110Y0240R270 S1      
327P12V_SSD5_R      PC844 -1          A01X+062968Y+027416X0400Y0500R270 S1      
327P12V_SSD5_R      PU108 -6_7        A01X+063898Y+027354X0295Y0354R090 S1      
327P12V_SSD5_R      PD103 -C          A01X+061907Y+027104X0670Y0990     S1      
317P12V_SSD5_R      VIA   -    MD0100PA00X+063170Y+027003X0200Y         S0      
317P12V_SSD5_R      VIA   -    MD0100PA00X+062640Y+027003X0200Y         S0      
317P12V_SSD5_R      VIA   -    MD0100PA00X+062920Y+027003X0200Y         S0      
317P12V_SSD5_R      VIA   -    MD0100PA00X+063170Y+026753X0200Y         S0      
317P12V_SSD5_R      VIA   -    MD0100PA00X+062640Y+026753X0200Y         S0      
317P12V_SSD5_R      VIA   -    MD0100PA00X+062920Y+026753X0200Y         S0      
317P12V_SSD5_R      VIA   -    MD0100PA00X+062001Y+026418X0200Y         S0      
317P12V_SSD5_R      VIA   -    MD0100PA00X+061751Y+026418X0200Y         S0      
317P12V_SSD5_R      VIA   -    MD0100PA00X+056642Y+024837X0200Y         S0      
327P12V_SSD5_R      R5979 -1          A01X+056919Y+024837X0198Y0197     S1      
317P12V_SSD5_R      VIA   -    MD0100PA00X+064320Y+016870X0200Y         S0      
327P12V_SSD5_R      R568  -1          A01X+064026Y+016870X0198Y0197R180 S1      
327P12V_SSD5_R      PC370 -1          A01X+063633Y+021661X0198Y0197R090 S1      
327P12V_SSD5_R      PC371 -1          A01X+063011Y+021554X0400Y0500R270 S1      
327P12V_SSD5_R      PD27  -C          A01X+061930Y+021175X0670Y0990     S1      
327P12V_SSD5_R      C313  -1          A01X+063739Y+018426X0198Y0197R090 S1      
327P12V_SSD5_R      R562  -2          A01X+062239Y+018919X1150Y1380R090 S1      
327P12V_SSD5_R      U60   -11         A01X+064388Y+018187X0090Y0240R090 S1      
317P12V_SSD5_R      VIA   -    MD0100PA00X+063997Y+021563X0200Y    R090 S0      
317P12V_SSD5_R      VIA   -    MD0100PA00X+062464Y+021571X0200Y    R090 S0      
317P12V_SSD5_R      VIA   -    MD0100PA00X+063997Y+021313X0200Y    R090 S0      
317P12V_SSD5_R      VIA   -    MD0100PA00X+062464Y+021071X0200Y    R090 S0      
317P12V_SSD5_R      VIA   -    MD0100PA00X+062464Y+021321X0200Y    R090 S0      
317P12V_SSD5_R      VIA   -    MD0100PA00X+063121Y+021170X0200Y         S0      
317P12V_SSD5_R      VIA   -    MD0100PA00X+063627Y+021386X0200Y    R090 S0      
317P12V_SSD5_R      VIA   -    MD0100PA00X+063627Y+021136X0200Y    R090 S0      
317P12V_SSD5_R      VIA   -    MD0100PA00X+062464Y+020821X0200Y    R090 S0      
317P12V_SSD5_R      VIA   -    M      A01X+063151Y+020870X0200Y         S2      
017P12V_SSD5_R      VIA   -    M      A18X+063151Y+020870X0260Y         S2      
017P12V_SSD5_R            -    MD0100PA00X+063151Y+020870                       
317P12V_SSD5_R      VIA   -    MD0100PA00X+062871Y+020870X0200Y         S0      
317P12V_SSD5_R      VIA   -    MD0100PA00X+062871Y+021170X0200Y         S0      
317P12V_SSD5_R      VIA   -    MD0100PA00X+061418Y+020798X0200Y    R090 S0      
317P12V_SSD5_R      VIA   -    MD0100PA00X+061418Y+021298X0200Y    R090 S0      
317P12V_SSD5_R      VIA   -    MD0100PA00X+061418Y+021548X0200Y    R090 S0      
317P12V_SSD5_R      VIA   -    MD0100PA00X+061418Y+021048X0200Y    R090 S0      
317P12V_SSD5_R      VIA   -    MD0100PA00X+063485Y+018401X0200Y         S0      
317P12V_SSD5_R      VIA   -    MD0100PA00X+063223Y+018422X0200Y         S0      
317P12V_SSD5_R      VIA   -    MD0100PA00X+063803Y+018101X0200Y         S0      
317P12V_SSD5_R      VIA   -    MD0100PA00X+063524Y+018137X0200Y         S0      
317P12V_SSD5_R      VIA   -    MD0100PA00X+063202Y+018143X0200Y         S0      
317m2691            VIA   -    M      A01X+130176Y+017762X0200Y         S2      
017m2691            VIA   -    M      A18X+130176Y+017762X0260Y         S2      
017m2691                  -    MD0100PA00X+130176Y+017762                       
327m2691            R635  -2          A01X+129497Y+017615X0198Y0197R090 S1      
327m2691            C332  -2   M      A01X+129897Y+017615X0198Y0197R090 S1      
327m2691            U74   -12         A01X+130569Y+017990X0090Y0240R090 S1      
317m2692            VIA   -    M      A01X+065235Y+019249X0200Y         S2      
017m2692            VIA   -    M      A18X+065235Y+019249X0260Y         S2      
017m2692                  -    MD0100PA00X+065235Y+019249                       
327m2692            U60   -5          A01X+065235Y+018836X0090Y0240R180 S1      
327m2692            R566  -2          A01X+066120Y+019666X0198Y0197R180 S1      
317m2693            VIA   -    M      A01X+099526Y+017219X0200Y         S2      
017m2693            VIA   -    M      A18X+099526Y+017219X0260Y         S2      
017m2693                  -    MD0100PA00X+099526Y+017219                       
327m2693            U71   -13         A01X+100116Y+017734X0090Y0240R180 S1      
327m2693            C323  -1   M      A01X+099188Y+017300X0198Y0197R090 S1      
327m2693            R601  -2          A01X+099183Y+016870X0198Y0197R180 S1      
317m2694            VIA   -    M      A01X+084526Y+017219X0200Y         S2      
017m2694            VIA   -    M      A18X+084526Y+017219X0260Y         S2      
017m2694                  -    MD0100PA00X+084526Y+017219                       
327m2694            R590  -2          A01X+084183Y+016870X0198Y0197R180 S1      
327m2694            U62   -13         A01X+085116Y+017734X0090Y0240R180 S1      
327m2694            C320  -1   M      A01X+084188Y+017300X0198Y0197R090 S1      
317m2695            VIA   -    M      A01X+074289Y+017219X0200Y         S2      
017m2695            VIA   -    M      A18X+074289Y+017219X0260Y         S2      
017m2695                  -    MD0100PA00X+074289Y+017219                       
327m2695            R579  -2          A01X+073947Y+016870X0198Y0197R180 S1      
327m2695            C317  -1   M      A01X+073952Y+017300X0198Y0197R090 S1      
327m2695            U61   -13         A01X+074880Y+017734X0090Y0240R180 S1      
317m2696            VIA   -    M      A01X+055574Y+018383X0200Y         S2      
017m2696            VIA   -    M      A18X+055574Y+018383X0260Y         S2      
017m2696                  -    MD0100PA00X+055574Y+018383                       
327m2696            U59   -3          A01X+055254Y+018383X0090Y0240R090 S1      
327m2696            R552  -1          A01X+055883Y+018466X0198Y0197     S1      
317m2697            VIA   -    M      A01X+054998Y+019249X0200Y         S2      
017m2697            VIA   -    M      A18X+054998Y+019249X0260Y         S2      
017m2697                  -    MD0100PA00X+054998Y+019249                       
327m2697            R555  -2          A01X+055883Y+019666X0198Y0197R180 S1      
327m2697            U59   -5          A01X+054998Y+018836X0090Y0240R180 S1      
317SSD5_ADC_A0      VIA   -           A01X+065821Y+017856X0200Y         S2      
017SSD5_ADC_A0      VIA   -           A18X+065821Y+017856X0260Y         S2      
017SSD5_ADC_A0            -     D0100PA00X+065821Y+017856                       
327SSD5_ADC_A0      U60   -2          A01X+065491Y+018187X0090Y0240R090 S1      
327SSD5_ADC_A0      R561  -1          A01X+066120Y+017666X0198Y0197     S1      
327SSD5_ADC_A0      R564  -1   M      A01X+066120Y+018066X0198Y0197     S1      
317m2698            VIA   -    M      A01X+086283Y+018383X0200Y         S2      
017m2698            VIA   -    M      A18X+086283Y+018383X0260Y         S2      
017m2698                  -    MD0100PA00X+086283Y+018383                       
327m2698            R587  -1          A01X+086592Y+018466X0198Y0197     S1      
327m2698            U62   -3          A01X+085963Y+018383X0090Y0240R090 S1      
317m2699            VIA   -    M      A01X+084468Y+017762X0200Y         S2      
017m2699            VIA   -    M      A18X+084468Y+017762X0260Y         S2      
017m2699                  -    MD0100PA00X+084468Y+017762                       
327m2699            R591  -2          A01X+083788Y+017615X0198Y0197R090 S1      
327m2699            C320  -2   M      A01X+084188Y+017615X0198Y0197R090 S1      
327m2699            U62   -12         A01X+084861Y+017990X0090Y0240R090 S1      
327P12V_SSD7_R      PU37  -1          A01X+084743Y+021907X0110Y0240R270 S1      
327P12V_SSD7_R      PU37  -2          A01X+084743Y+021710X0110Y0240R270 S1      
327P12V_SSD7_R      PU37  -3          A01X+084743Y+021513X0110Y0240R270 S1      
327P12V_SSD7_R      PU37  -4          A01X+084743Y+021317X0110Y0240R270 S1      
327P12V_SSD7_R      PU37  -5          A01X+084743Y+021120X0110Y0240R270 S1      
327P12V_SSD7_R      PU110 -6_7        A01X+084370Y+027354X0295Y0354R090 S1      
327P12V_SSD7_R      PC395 -1          A01X+083441Y+027416X0400Y0500R270 S1      
327P12V_SSD7_R      PD35  -C          A01X+082379Y+027104X0670Y0990     S1      
317P12V_SSD7_R      VIA   -    MD0100PA00X+083643Y+027003X0200Y         S0      
317P12V_SSD7_R      VIA   -    MD0100PA00X+083393Y+027003X0200Y         S0      
317P12V_SSD7_R      VIA   -    MD0100PA00X+083393Y+026753X0200Y         S0      
317P12V_SSD7_R      VIA   -    MD0100PA00X+083643Y+026753X0200Y         S0      
317P12V_SSD7_R      VIA   -    MD0100PA00X+083113Y+027003X0200Y         S0      
317P12V_SSD7_R      VIA   -    MD0100PA00X+083113Y+026753X0200Y         S0      
317P12V_SSD7_R      VIA   -    MD0100PA00X+082474Y+026418X0200Y         S0      
317P12V_SSD7_R      VIA   -    MD0100PA00X+082224Y+026418X0200Y         S0      
317P12V_SSD7_R      VIA   -    MD0100PA00X+077114Y+024837X0200Y         S0      
327P12V_SSD7_R      R5989 -1          A01X+077392Y+024837X0198Y0197     S1      
317P12V_SSD7_R      VIA   -    MD0100PA00X+084793Y+016870X0200Y         S0      
327P12V_SSD7_R      R590  -1          A01X+084498Y+016870X0198Y0197R180 S1      
327P12V_SSD7_R      PC394 -1          A01X+084105Y+021661X0198Y0197R090 S1      
327P12V_SSD7_R      PC856 -1          A01X+083483Y+021554X0400Y0500R270 S1      
327P12V_SSD7_R      PD107 -C          A01X+082402Y+021175X0670Y0990     S1      
327P12V_SSD7_R      C319  -1          A01X+084211Y+018426X0198Y0197R090 S1      
327P12V_SSD7_R      R583  -2          A01X+082712Y+018919X1150Y1380R090 S1      
327P12V_SSD7_R      U62   -11         A01X+084861Y+018187X0090Y0240R090 S1      
317P12V_SSD7_R      VIA   -    MD0100PA00X+084470Y+021563X0200Y    R090 S0      
317P12V_SSD7_R      VIA   -    MD0100PA00X+082936Y+021571X0200Y    R090 S0      
317P12V_SSD7_R      VIA   -    MD0100PA00X+084470Y+021313X0200Y    R090 S0      
317P12V_SSD7_R      VIA   -    MD0100PA00X+083343Y+021170X0200Y         S0      
317P12V_SSD7_R      VIA   -    MD0100PA00X+084099Y+021136X0200Y    R090 S0      
317P12V_SSD7_R      VIA   -    MD0100PA00X+084099Y+021386X0200Y    R090 S0      
317P12V_SSD7_R      VIA   -    MD0100PA00X+083593Y+021170X0200Y         S0      
317P12V_SSD7_R      VIA   -    MD0100PA00X+083343Y+020870X0200Y         S0      
317P12V_SSD7_R      VIA   -    M      A01X+083623Y+020870X0200Y         S2      
017P12V_SSD7_R      VIA   -    M      A18X+083623Y+020870X0260Y         S2      
017P12V_SSD7_R            -    MD0100PA00X+083623Y+020870                       
317P12V_SSD7_R      VIA   -    MD0100PA00X+082936Y+021071X0200Y    R090 S0      
317P12V_SSD7_R      VIA   -    MD0100PA00X+082936Y+020821X0200Y    R090 S0      
317P12V_SSD7_R      VIA   -    MD0100PA00X+081891Y+021048X0200Y    R090 S0      
317P12V_SSD7_R      VIA   -    MD0100PA00X+081891Y+021548X0200Y    R090 S0      
317P12V_SSD7_R      VIA   -    MD0100PA00X+081891Y+021298X0200Y    R090 S0      
317P12V_SSD7_R      VIA   -    MD0100PA00X+081891Y+020798X0200Y    R090 S0      
317P12V_SSD7_R      VIA   -    MD0100PA00X+082936Y+021321X0200Y    R090 S0      
317P12V_SSD7_R      VIA   -    MD0100PA00X+083696Y+018422X0200Y         S0      
317P12V_SSD7_R      VIA   -    MD0100PA00X+083957Y+018401X0200Y         S0      
317P12V_SSD7_R      VIA   -    MD0100PA00X+083675Y+018143X0200Y         S0      
317P12V_SSD7_R      VIA   -    MD0100PA00X+083996Y+018137X0200Y         S0      
317P12V_SSD7_R      VIA   -    MD0100PA00X+084275Y+018101X0200Y         S0      
317SSD4_ADC_A1      VIA   -    M      A01X+055591Y+017266X0200Y         S2      
017SSD4_ADC_A1      VIA   -    M      A18X+055591Y+017266X0260Y         S2      
017SSD4_ADC_A1            -    MD0100PA00X+055591Y+017266                       
327SSD4_ADC_A1      U59   -1          A01X+055254Y+017990X0090Y0240R090 S1      
327SSD4_ADC_A1      R549  -1          A01X+055883Y+016866X0198Y0197     S1      
327SSD4_ADC_A1      R553  -1   M      A01X+055883Y+017266X0198Y0197     S1      
317SSD4_ADC_A0      VIA   -           A01X+055585Y+017856X0200Y         S2      
017SSD4_ADC_A0      VIA   -           A18X+055585Y+017856X0260Y         S2      
017SSD4_ADC_A0            -     D0100PA00X+055585Y+017856                       
327SSD4_ADC_A0      U59   -2          A01X+055254Y+018187X0090Y0240R090 S1      
327SSD4_ADC_A0      R550  -1          A01X+055883Y+017666X0198Y0197     S1      
327SSD4_ADC_A0      R554  -1   M      A01X+055883Y+018066X0198Y0197     S1      
317m2700            VIA   -    MD0100PA00X+141680Y+093684X0200Y         S0      
327m2700            R6407 -2          A01X+141814Y+093929X0198Y0197R180 S1      
317m2700            VIA   -    MD0100PA00X+127028Y+089706X0200Y         S0      
317m2700            VIA   -    M      A01X+042499Y+072829X0200Y         S2      
017m2700            VIA   -    M      A18X+042499Y+072829X0260Y         S2      
017m2700                  -    MD0100PA00X+042499Y+072829                       
327m2700            R824  -2          A01X+044658Y+064088X0198Y0197     S1      
317m2700            VIA   -    MD0100PA00X+045647Y+063830X0200Y         S0      
317m2700            VIA   -    MD0100PA00X+047240Y+083957X0200Y         S0      
317m2700            VIA   -    MD0100PA00X+011199Y+071010X0200Y         S0      
327m2700            R4429 -2          A18X+009019Y+068180X0198Y0197R180 S2      
327P12V_SSD6_R      PU35  -1          A01X+074507Y+021907X0110Y0240R270 S1      
327P12V_SSD6_R      PU35  -2          A01X+074507Y+021710X0110Y0240R270 S1      
327P12V_SSD6_R      PU35  -3          A01X+074507Y+021513X0110Y0240R270 S1      
327P12V_SSD6_R      PU35  -4          A01X+074507Y+021317X0110Y0240R270 S1      
327P12V_SSD6_R      PU35  -5          A01X+074507Y+021120X0110Y0240R270 S1      
327P12V_SSD6_R      PU109 -6_7        A01X+074134Y+027354X0295Y0354R090 S1      
327P12V_SSD6_R      PC854 -1          A01X+073205Y+027416X0400Y0500R270 S1      
327P12V_SSD6_R      PD106 -C          A01X+072143Y+027104X0670Y0990     S1      
317P12V_SSD6_R      VIA   -    MD0100PA00X+072877Y+027003X0200Y         S0      
317P12V_SSD6_R      VIA   -    MD0100PA00X+073157Y+027003X0200Y         S0      
317P12V_SSD6_R      VIA   -    MD0100PA00X+073407Y+027003X0200Y         S0      
317P12V_SSD6_R      VIA   -    MD0100PA00X+073407Y+026753X0200Y         S0      
317P12V_SSD6_R      VIA   -    MD0100PA00X+072877Y+026753X0200Y         S0      
317P12V_SSD6_R      VIA   -    MD0100PA00X+073157Y+026753X0200Y         S0      
317P12V_SSD6_R      VIA   -    MD0100PA00X+071987Y+026418X0200Y         S0      
317P12V_SSD6_R      VIA   -    MD0100PA00X+072237Y+026418X0200Y         S0      
317P12V_SSD6_R      VIA   -    MD0100PA00X+066889Y+024837X0200Y         S0      
327P12V_SSD6_R      R5988 -1          A01X+067156Y+024837X0198Y0197     S1      
317P12V_SSD6_R      VIA   -    MD0100PA00X+074557Y+016870X0200Y         S0      
327P12V_SSD6_R      R579  -1          A01X+074262Y+016870X0198Y0197R180 S1      
327P12V_SSD6_R      PC382 -1          A01X+073869Y+021661X0198Y0197R090 S1      
327P12V_SSD6_R      PD31  -C          A01X+072166Y+021175X0670Y0990     S1      
327P12V_SSD6_R      PC383 -1          A01X+073247Y+021554X0400Y0500R270 S1      
327P12V_SSD6_R      C316  -1          A01X+073975Y+018426X0198Y0197R090 S1      
327P12V_SSD6_R      R573  -2          A01X+072476Y+018919X1150Y1380R090 S1      
327P12V_SSD6_R      U61   -11         A01X+074624Y+018187X0090Y0240R090 S1      
317P12V_SSD6_R      VIA   -    MD0100PA00X+074233Y+021563X0200Y    R090 S0      
317P12V_SSD6_R      VIA   -    MD0100PA00X+072700Y+021571X0200Y    R090 S0      
317P12V_SSD6_R      VIA   -    MD0100PA00X+074233Y+021313X0200Y    R090 S0      
317P12V_SSD6_R      VIA   -    MD0100PA00X+073863Y+021136X0200Y    R090 S0      
317P12V_SSD6_R      VIA   -    MD0100PA00X+073863Y+021386X0200Y    R090 S0      
317P12V_SSD6_R      VIA   -    MD0100PA00X+072700Y+021071X0200Y    R090 S0      
317P12V_SSD6_R      VIA   -    MD0100PA00X+073107Y+021170X0200Y         S0      
317P12V_SSD6_R      VIA   -    MD0100PA00X+073357Y+021170X0200Y         S0      
317P12V_SSD6_R      VIA   -    MD0100PA00X+073107Y+020870X0200Y         S0      
317P12V_SSD6_R      VIA   -    M      A01X+073387Y+020870X0200Y         S2      
017P12V_SSD6_R      VIA   -    M      A18X+073387Y+020870X0260Y         S2      
017P12V_SSD6_R            -    MD0100PA00X+073387Y+020870                       
317P12V_SSD6_R      VIA   -    MD0100PA00X+072700Y+020821X0200Y    R090 S0      
317P12V_SSD6_R      VIA   -    MD0100PA00X+072700Y+021321X0200Y    R090 S0      
317P12V_SSD6_R      VIA   -    MD0100PA00X+071654Y+021298X0200Y    R090 S0      
317P12V_SSD6_R      VIA   -    MD0100PA00X+071654Y+020798X0200Y    R090 S0      
317P12V_SSD6_R      VIA   -    MD0100PA00X+071654Y+021048X0200Y    R090 S0      
317P12V_SSD6_R      VIA   -    MD0100PA00X+071654Y+021548X0200Y    R090 S0      
317P12V_SSD6_R      VIA   -    MD0100PA00X+073721Y+018401X0200Y         S0      
317P12V_SSD6_R      VIA   -    MD0100PA00X+073459Y+018422X0200Y         S0      
317P12V_SSD6_R      VIA   -    MD0100PA00X+073760Y+018137X0200Y         S0      
317P12V_SSD6_R      VIA   -    MD0100PA00X+074039Y+018101X0200Y         S0      
317P12V_SSD6_R      VIA   -    MD0100PA00X+073439Y+018143X0200Y         S0      
317m2701            VIA   -    M      A01X+076046Y+018383X0200Y         S2      
017m2701            VIA   -    M      A18X+076046Y+018383X0260Y         S2      
017m2701                  -    MD0100PA00X+076046Y+018383                       
327m2701            R576  -1          A01X+076356Y+018466X0198Y0197     S1      
327m2701            U61   -3          A01X+075727Y+018383X0090Y0240R090 S1      
317SSD6_ADC_A1      VIA   -    M      A01X+076064Y+017266X0200Y         S2      
017SSD6_ADC_A1      VIA   -    M      A18X+076064Y+017266X0260Y         S2      
017SSD6_ADC_A1            -    MD0100PA00X+076064Y+017266                       
327SSD6_ADC_A1      U61   -1          A01X+075727Y+017990X0090Y0240R090 S1      
327SSD6_ADC_A1      R571  -1          A01X+076356Y+016866X0198Y0197     S1      
327SSD6_ADC_A1      R574  -1   M      A01X+076356Y+017266X0198Y0197     S1      
317m2702            VIA   -    M      A01X+085707Y+019249X0200Y         S2      
017m2702            VIA   -    M      A18X+085707Y+019249X0260Y         S2      
017m2702                  -    MD0100PA00X+085707Y+019249                       
327m2702            U62   -5          A01X+085707Y+018836X0090Y0240R180 S1      
327m2702            R588  -2          A01X+086592Y+019666X0198Y0197R180 S1      
327m2702            R5897 -2   M      A01X+086175Y+019662X0198Y0197     S1      
317m2703            VIA   -    M      A01X+065762Y+019018X0200Y         S2      
017m2703            VIA   -    M      A18X+065762Y+019018X0260Y         S2      
017m2703                  -    MD0100PA00X+065762Y+019018                       
327m2703            R567  -2          A01X+066120Y+019266X0198Y0197R180 S1      
327m2703            U60   -4          A01X+065491Y+018580X0090Y0240R090 S1      
317m2704            VIA   -    M      A01X+064053Y+017219X0200Y         S2      
017m2704            VIA   -    M      A18X+064053Y+017219X0260Y         S2      
017m2704                  -    MD0100PA00X+064053Y+017219                       
327m2704            R568  -2          A01X+063711Y+016870X0198Y0197R180 S1      
327m2704            U60   -13         A01X+064644Y+017734X0090Y0240R180 S1      
327m2704            C314  -1   M      A01X+063716Y+017300X0198Y0197R090 S1      
317m2705            VIA   -    M      A01X+075998Y+019018X0200Y         S2      
017m2705            VIA   -    M      A18X+075998Y+019018X0260Y         S2      
017m2705                  -    MD0100PA00X+075998Y+019018                       
327m2705            U61   -4          A01X+075727Y+018580X0090Y0240R090 S1      
327m2705            R5896 -2          A01X+076356Y+019666X0198Y0197R180 S1      
327m2705            R578  -2   M      A01X+076356Y+019266X0198Y0197R180 S1      
327P12V_SSD4_R      PU31  -1          A01X+054034Y+021907X0110Y0240R270 S1      
327P12V_SSD4_R      PU31  -2          A01X+054034Y+021710X0110Y0240R270 S1      
327P12V_SSD4_R      PU31  -3          A01X+054034Y+021513X0110Y0240R270 S1      
327P12V_SSD4_R      PU31  -4          A01X+054034Y+021317X0110Y0240R270 S1      
327P12V_SSD4_R      PU31  -5          A01X+054034Y+021120X0110Y0240R270 S1      
327P12V_SSD4_R      PU107 -6_7        A01X+053662Y+027354X0295Y0354R090 S1      
327P12V_SSD4_R      PC841 -1          A01X+052732Y+027416X0400Y0500R270 S1      
327P12V_SSD4_R      PD102 -C          A01X+051670Y+027104X0670Y0990     S1      
317P12V_SSD4_R      VIA   -    MD0100PA00X+052934Y+026753X0200Y         S0      
317P12V_SSD4_R      VIA   -    MD0100PA00X+052684Y+026753X0200Y         S0      
317P12V_SSD4_R      VIA   -    MD0100PA00X+052934Y+027003X0200Y         S0      
317P12V_SSD4_R      VIA   -    MD0100PA00X+052684Y+027003X0200Y         S0      
317P12V_SSD4_R      VIA   -    MD0100PA00X+052404Y+026753X0200Y         S0      
317P12V_SSD4_R      VIA   -    MD0100PA00X+052404Y+027003X0200Y         S0      
317P12V_SSD4_R      VIA   -    MD0100PA00X+051765Y+026418X0200Y         S0      
317P12V_SSD4_R      VIA   -    MD0100PA00X+051515Y+026418X0200Y         S0      
317P12V_SSD4_R      VIA   -    MD0100PA00X+046405Y+024837X0200Y         S0      
327P12V_SSD4_R      R5978 -1          A01X+046683Y+024837X0198Y0197     S1      
317P12V_SSD4_R      VIA   -    MD0100PA00X+054084Y+016870X0200Y         S0      
327P12V_SSD4_R      R557  -1          A01X+053790Y+016870X0198Y0197R180 S1      
327P12V_SSD4_R      PC358 -1          A01X+053396Y+021661X0198Y0197R090 S1      
327P12V_SSD4_R      PC359 -1          A01X+052774Y+021554X0400Y0500R270 S1      
327P12V_SSD4_R      PD23  -C          A01X+051694Y+021175X0670Y0990     S1      
327P12V_SSD4_R      C310  -1          A01X+053502Y+018426X0198Y0197R090 S1      
327P12V_SSD4_R      R551  -2          A01X+052003Y+018919X1150Y1380R090 S1      
327P12V_SSD4_R      U59   -11         A01X+054152Y+018187X0090Y0240R090 S1      
317P12V_SSD4_R      VIA   -    MD0100PA00X+053761Y+021563X0200Y    R090 S0      
317P12V_SSD4_R      VIA   -    MD0100PA00X+052228Y+021571X0200Y    R090 S0      
317P12V_SSD4_R      VIA   -    MD0100PA00X+052635Y+021170X0200Y         S0      
317P12V_SSD4_R      VIA   -    M      A01X+052915Y+020870X0200Y         S2      
017P12V_SSD4_R      VIA   -    M      A18X+052915Y+020870X0260Y         S2      
017P12V_SSD4_R            -    MD0100PA00X+052915Y+020870                       
317P12V_SSD4_R      VIA   -    MD0100PA00X+052635Y+020870X0200Y         S0      
317P12V_SSD4_R      VIA   -    MD0100PA00X+053761Y+021313X0200Y    R090 S0      
317P12V_SSD4_R      VIA   -    MD0100PA00X+052885Y+021170X0200Y         S0      
317P12V_SSD4_R      VIA   -    MD0100PA00X+053391Y+021386X0200Y    R090 S0      
317P12V_SSD4_R      VIA   -    MD0100PA00X+053391Y+021136X0200Y    R090 S0      
317P12V_SSD4_R      VIA   -    MD0100PA00X+052228Y+021071X0200Y    R090 S0      
317P12V_SSD4_R      VIA   -    MD0100PA00X+052228Y+021321X0200Y    R090 S0      
317P12V_SSD4_R      VIA   -    MD0100PA00X+052228Y+020821X0200Y    R090 S0      
317P12V_SSD4_R      VIA   -    MD0100PA00X+051182Y+021298X0200Y    R090 S0      
317P12V_SSD4_R      VIA   -    MD0100PA00X+051182Y+021548X0200Y    R090 S0      
317P12V_SSD4_R      VIA   -    MD0100PA00X+051182Y+021048X0200Y    R090 S0      
317P12V_SSD4_R      VIA   -    MD0100PA00X+051182Y+020798X0200Y    R090 S0      
317P12V_SSD4_R      VIA   -    MD0100PA00X+053249Y+018401X0200Y         S0      
317P12V_SSD4_R      VIA   -    MD0100PA00X+052987Y+018422X0200Y         S0      
317P12V_SSD4_R      VIA   -    MD0100PA00X+053287Y+018137X0200Y         S0      
317P12V_SSD4_R      VIA   -    MD0100PA00X+052966Y+018143X0200Y         S0      
317P12V_SSD4_R      VIA   -    MD0100PA00X+053567Y+018101X0200Y         S0      
317m2706            VIA   -    M      A01X+040526Y+019018X0200Y         S2      
017m2706            VIA   -    M      A18X+040526Y+019018X0260Y         S2      
017m2706                  -    MD0100PA00X+040526Y+019018                       
327m2706            U56   -4          A01X+040254Y+018580X0090Y0240R090 S1      
327m2706            R545  -2          A01X+040883Y+019266X0198Y0197R180 S1      
317m2707            VIA   -    M      A01X+030290Y+019018X0200Y         S2      
017m2707            VIA   -    M      A18X+030290Y+019018X0260Y         S2      
017m2707                  -    MD0100PA00X+030290Y+019018                       
327m2707            R5894 -2          A01X+030267Y+019629X0198Y0197     S1      
327m2707            R534  -2   M      A01X+030647Y+019266X0198Y0197R180 S1      
327m2707            U55   -4          A01X+030018Y+018580X0090Y0240R090 S1      
317m2708            VIA   -    M      A01X+075471Y+019249X0200Y         S2      
017m2708            VIA   -    M      A18X+075471Y+019249X0260Y         S2      
017m2708                  -    MD0100PA00X+075471Y+019249                       
327m2708            U61   -5          A01X+075471Y+018836X0090Y0240R180 S1      
327m2708            R577  -2          A01X+075938Y+019662X0198Y0197     S1      
317m2709            VIA   -    M      A01X+009865Y+018383X0200Y         S2      
017m2709            VIA   -    M      A18X+009865Y+018383X0260Y         S2      
017m2709                  -    MD0100PA00X+009865Y+018383                       
327m2709            U51   -3          A01X+009546Y+018383X0090Y0240R090 S1      
327m2709            R509  -1          A01X+010175Y+018466X0198Y0197     S1      
317m2710            VIA   -    M      A01X+053817Y+017219X0200Y         S2      
017m2710            VIA   -    M      A18X+053817Y+017219X0260Y         S2      
017m2710                  -    MD0100PA00X+053817Y+017219                       
327m2710            R557  -2          A01X+053475Y+016870X0198Y0197R180 S1      
327m2710            U59   -13         A01X+054408Y+017734X0090Y0240R180 S1      
327m2710            C311  -1   M      A01X+053480Y+017300X0198Y0197R090 S1      
317m2711            VIA   -    M      A01X+028523Y+017762X0200Y         S2      
017m2711            VIA   -    M      A18X+028523Y+017762X0260Y         S2      
017m2711                  -    MD0100PA00X+028523Y+017762                       
327m2711            R536  -2          A01X+027844Y+017615X0198Y0197R090 S1      
327m2711            U55   -12         A01X+028916Y+017990X0090Y0240R090 S1      
327m2711            C209  -2   M      A01X+028244Y+017615X0198Y0197R090 S1      
317m2712            VIA   -    M      A01X+063995Y+017762X0200Y         S2      
017m2712            VIA   -    M      A18X+063995Y+017762X0260Y         S2      
017m2712                  -    MD0100PA00X+063995Y+017762                       
327m2712            R569  -2          A01X+063316Y+017615X0198Y0197R090 S1      
327m2712            C314  -2   M      A01X+063716Y+017615X0198Y0197R090 S1      
327m2712            U60   -12         A01X+064388Y+017990X0090Y0240R090 S1      
317m2713            VIA   -    M      A01X+039998Y+019249X0200Y         S2      
017m2713            VIA   -    M      A18X+039998Y+019249X0260Y         S2      
017m2713                  -    MD0100PA00X+039998Y+019249                       
327m2713            U56   -5          A01X+039998Y+018836X0090Y0240R180 S1      
327m2713            R544  -2          A01X+040883Y+019666X0198Y0197R180 S1      
327m2713            R5895 -2   M      A01X+040466Y+019662X0198Y0197     S1      
317SSD5_ADC_A1      VIA   -    M      A01X+065828Y+017266X0200Y         S2      
017SSD5_ADC_A1      VIA   -    M      A18X+065828Y+017266X0260Y         S2      
017SSD5_ADC_A1            -    MD0100PA00X+065828Y+017266                       
327SSD5_ADC_A1      U60   -1          A01X+065491Y+017990X0090Y0240R090 S1      
327SSD5_ADC_A1      R560  -1          A01X+066120Y+016866X0198Y0197     S1      
327SSD5_ADC_A1      R563  -1   M      A01X+066120Y+017266X0198Y0197     S1      
317m2714            VIA   -    M      A01X+055526Y+019018X0200Y         S2      
017m2714            VIA   -    M      A18X+055526Y+019018X0260Y         S2      
017m2714                  -    MD0100PA00X+055526Y+019018                       
327m2714            U59   -4          A01X+055254Y+018580X0090Y0240R090 S1      
327m2714            R556  -2          A01X+055883Y+019266X0198Y0197R180 S1      
317m2715            VIA   -    M      A01X+019526Y+019249X0200Y         S2      
017m2715            VIA   -    M      A18X+019526Y+019249X0260Y         S2      
017m2715                  -    MD0100PA00X+019526Y+019249                       
327m2715            R522  -2          A01X+020411Y+019666X0198Y0197R180 S1      
327m2715            U54   -5          A01X+019526Y+018836X0090Y0240R180 S1      
317m2716            VIA   -    M      A01X+040574Y+018383X0200Y         S2      
017m2716            VIA   -    M      A18X+040574Y+018383X0260Y         S2      
017m2716                  -    MD0100PA00X+040574Y+018383                       
327m2716            U56   -3          A01X+040254Y+018383X0090Y0240R090 S1      
327m2716            R541  -1          A01X+040883Y+018466X0198Y0197     S1      
317m2717            VIA   -    M      A01X+009817Y+019018X0200Y         S2      
017m2717            VIA   -    M      A18X+009817Y+019018X0260Y         S2      
017m2717                  -    MD0100PA00X+009817Y+019018                       
327m2717            R512  -2          A01X+010175Y+019266X0198Y0197R180 S1      
327m2717            U51   -4          A01X+009546Y+018580X0090Y0240R090 S1      
317m2718            VIA   -    M      A01X+030338Y+018383X0200Y         S2      
017m2718            VIA   -    M      A18X+030338Y+018383X0260Y         S2      
017m2718                  -    MD0100PA00X+030338Y+018383                       
327m2718            U55   -3          A01X+030018Y+018383X0090Y0240R090 S1      
327m2718            R530  -1          A01X+030647Y+018466X0198Y0197     S1      
317m2719            VIA   -    M      A01X+008108Y+017219X0200Y         S2      
017m2719            VIA   -    M      A18X+008108Y+017219X0260Y         S2      
017m2719                  -    MD0100PA00X+008108Y+017219                       
327m2719            U51   -13         A01X+008699Y+017734X0090Y0240R180 S1      
327m2719            C203  -1   M      A01X+007771Y+017300X0198Y0197R090 S1      
327m2719            R513  -2          A01X+007766Y+016870X0198Y0197R180 S1      
317SSD0_ADC_A0      VIA   -           A01X+009876Y+017856X0200Y         S2      
017SSD0_ADC_A0      VIA   -           A18X+009876Y+017856X0260Y         S2      
017SSD0_ADC_A0            -     D0100PA00X+009876Y+017856                       
327SSD0_ADC_A0      U51   -2          A01X+009546Y+018187X0090Y0240R090 S1      
327SSD0_ADC_A0      R507  -1          A01X+010175Y+017666X0198Y0197     S1      
327SSD0_ADC_A0      R508  -1   M      A01X+010175Y+018066X0198Y0197     S1      
317SSD0_ADC_A1      VIA   -    M      A01X+009883Y+017266X0200Y         S2      
017SSD0_ADC_A1      VIA   -    M      A18X+009883Y+017266X0260Y         S2      
017SSD0_ADC_A1            -    MD0100PA00X+009883Y+017266                       
327SSD0_ADC_A1      U51   -1          A01X+009546Y+017990X0090Y0240R090 S1      
327SSD0_ADC_A1      R505  -1          A01X+010175Y+016866X0198Y0197     S1      
327SSD0_ADC_A1      R510  -1   M      A01X+010175Y+017266X0198Y0197     S1      
317SSD1_ADC_A1      VIA   -    M      A01X+020119Y+017266X0200Y         S2      
017SSD1_ADC_A1      VIA   -    M      A18X+020119Y+017266X0260Y         S2      
017SSD1_ADC_A1            -    MD0100PA00X+020119Y+017266                       
327SSD1_ADC_A1      U54   -1          A01X+019782Y+017990X0090Y0240R090 S1      
327SSD1_ADC_A1      R517  -1          A01X+020411Y+016866X0198Y0197     S1      
327SSD1_ADC_A1      R521  -1   M      A01X+020411Y+017266X0198Y0197     S1      
317m2720            VIA   -    M      A01X+038817Y+017219X0200Y         S2      
017m2720            VIA   -    M      A18X+038817Y+017219X0260Y         S2      
017m2720                  -    MD0100PA00X+038817Y+017219                       
327m2720            R546  -2          A01X+038474Y+016870X0198Y0197R180 S1      
327m2720            U56   -13         A01X+039408Y+017734X0090Y0240R180 S1      
327m2720            C308  -1   M      A01X+038480Y+017300X0198Y0197R090 S1      
317m2721            VIA   -    M      A01X+008050Y+017762X0200Y         S2      
017m2721            VIA   -    M      A18X+008050Y+017762X0260Y         S2      
017m2721                  -    MD0100PA00X+008050Y+017762                       
327m2721            R514  -2          A01X+007371Y+017615X0198Y0197R090 S1      
327m2721            U51   -12         A01X+008443Y+017990X0090Y0240R090 S1      
327m2721            C203  -2   M      A01X+007771Y+017615X0198Y0197R090 S1      
327P12V_SSD3_R      PU36  -1          A01X+039034Y+021907X0110Y0240R270 S1      
327P12V_SSD3_R      PU36  -2          A01X+039034Y+021710X0110Y0240R270 S1      
327P12V_SSD3_R      PU36  -3          A01X+039034Y+021513X0110Y0240R270 S1      
327P12V_SSD3_R      PU36  -4          A01X+039034Y+021317X0110Y0240R270 S1      
327P12V_SSD3_R      PU36  -5          A01X+039034Y+021120X0110Y0240R270 S1      
327P12V_SSD3_R      PU77  -6_7        A01X+038662Y+027354X0295Y0354R090 S1      
327P12V_SSD3_R      PC655 -1          A01X+037732Y+027416X0400Y0500R270 S1      
327P12V_SSD3_R      PD91  -C          A01X+036670Y+027104X0670Y0990     S1      
317P12V_SSD3_R      VIA   -    MD0100PA00X+037934Y+026753X0200Y         S0      
317P12V_SSD3_R      VIA   -    MD0100PA00X+037934Y+027003X0200Y         S0      
317P12V_SSD3_R      VIA   -    MD0100PA00X+037684Y+026753X0200Y         S0      
317P12V_SSD3_R      VIA   -    MD0100PA00X+037404Y+026753X0200Y         S0      
317P12V_SSD3_R      VIA   -    MD0100PA00X+037684Y+027003X0200Y         S0      
317P12V_SSD3_R      VIA   -    MD0100PA00X+037404Y+027003X0200Y         S0      
317P12V_SSD3_R      VIA   -    MD0100PA00X+036515Y+026418X0200Y         S0      
317P12V_SSD3_R      VIA   -    MD0100PA00X+036765Y+026418X0200Y         S0      
317P12V_SSD3_R      VIA   -    MD0100PA00X+031405Y+024837X0200Y         S0      
327P12V_SSD3_R      R5853 -1          A01X+031683Y+024837X0198Y0197     S1      
317P12V_SSD3_R      VIA   -    MD0100PA00X+039084Y+016870X0200Y         S0      
327P12V_SSD3_R      R546  -1          A01X+038790Y+016870X0198Y0197R180 S1      
327P12V_SSD3_R      PC392 -1          A01X+038396Y+021661X0198Y0197R090 S1      
327P12V_SSD3_R      PC393 -1          A01X+037774Y+021554X0400Y0500R270 S1      
327P12V_SSD3_R      PD34  -C          A01X+036693Y+021175X0670Y0990     S1      
327P12V_SSD3_R      C211  -1          A01X+038502Y+018426X0198Y0197R090 S1      
327P12V_SSD3_R      R538  -2          A01X+037003Y+018919X1150Y1380R090 S1      
327P12V_SSD3_R      U56   -11         A01X+039152Y+018187X0090Y0240R090 S1      
317P12V_SSD3_R      VIA   -    MD0100PA00X+038761Y+021563X0200Y    R090 S0      
317P12V_SSD3_R      VIA   -    MD0100PA00X+037228Y+021571X0200Y    R090 S0      
317P12V_SSD3_R      VIA   -    MD0100PA00X+038390Y+021386X0200Y    R090 S0      
317P12V_SSD3_R      VIA   -    MD0100PA00X+037885Y+021170X0200Y         S0      
317P12V_SSD3_R      VIA   -    MD0100PA00X+038761Y+021313X0200Y    R090 S0      
317P12V_SSD3_R      VIA   -    MD0100PA00X+038390Y+021136X0200Y    R090 S0      
317P12V_SSD3_R      VIA   -    MD0100PA00X+036182Y+021048X0200Y    R090 S0      
317P12V_SSD3_R      VIA   -    MD0100PA00X+036182Y+021548X0200Y    R090 S0      
317P12V_SSD3_R      VIA   -    MD0100PA00X+036182Y+021298X0200Y    R090 S0      
317P12V_SSD3_R      VIA   -    MD0100PA00X+036182Y+020798X0200Y    R090 S0      
317P12V_SSD3_R      VIA   -    MD0100PA00X+037228Y+021321X0200Y    R090 S0      
317P12V_SSD3_R      VIA   -    MD0100PA00X+037228Y+021071X0200Y    R090 S0      
317P12V_SSD3_R      VIA   -    MD0100PA00X+037635Y+021170X0200Y         S0      
317P12V_SSD3_R      VIA   -    MD0100PA00X+037635Y+020870X0200Y         S0      
317P12V_SSD3_R      VIA   -    M      A01X+037915Y+020870X0200Y         S2      
017P12V_SSD3_R      VIA   -    M      A18X+037915Y+020870X0260Y         S2      
017P12V_SSD3_R            -    MD0100PA00X+037915Y+020870                       
317P12V_SSD3_R      VIA   -    MD0100PA00X+037228Y+020821X0200Y    R090 S0      
317P12V_SSD3_R      VIA   -    MD0100PA00X+037987Y+018422X0200Y         S0      
317P12V_SSD3_R      VIA   -    MD0100PA00X+038249Y+018401X0200Y         S0      
317P12V_SSD3_R      VIA   -    MD0100PA00X+038567Y+018101X0200Y         S0      
317P12V_SSD3_R      VIA   -    MD0100PA00X+037966Y+018143X0200Y         S0      
317P12V_SSD3_R      VIA   -    MD0100PA00X+038287Y+018137X0200Y         S0      
327P12V_SSD1_R      PU32  -1          A01X+018562Y+021907X0110Y0240R270 S1      
327P12V_SSD1_R      PU32  -2          A01X+018562Y+021710X0110Y0240R270 S1      
327P12V_SSD1_R      PU32  -3          A01X+018562Y+021513X0110Y0240R270 S1      
327P12V_SSD1_R      PU32  -4          A01X+018562Y+021317X0110Y0240R270 S1      
327P12V_SSD1_R      PU32  -5          A01X+018562Y+021120X0110Y0240R270 S1      
327P12V_SSD1_R      PC369 -1          A01X+017260Y+027416X0400Y0500R270 S1      
327P12V_SSD1_R      PU75  -6_7        A01X+018189Y+027354X0295Y0354R090 S1      
327P12V_SSD1_R      PD87  -C          A01X+016198Y+027104X0670Y0990     S1      
317P12V_SSD1_R      VIA   -    MD0100PA00X+016932Y+027003X0200Y         S0      
317P12V_SSD1_R      VIA   -    MD0100PA00X+017212Y+027003X0200Y         S0      
317P12V_SSD1_R      VIA   -    MD0100PA00X+017212Y+026753X0200Y         S0      
317P12V_SSD1_R      VIA   -    MD0100PA00X+016932Y+026753X0200Y         S0      
317P12V_SSD1_R      VIA   -    MD0100PA00X+017462Y+027003X0200Y         S0      
317P12V_SSD1_R      VIA   -    MD0100PA00X+017462Y+026753X0200Y         S0      
317P12V_SSD1_R      VIA   -    MD0100PA00X+016292Y+026418X0200Y         S0      
317P12V_SSD1_R      VIA   -    MD0100PA00X+016042Y+026418X0200Y         S0      
317P12V_SSD1_R      VIA   -    MD0100PA00X+010933Y+024837X0200Y         S0      
327P12V_SSD1_R      R5843 -1          A01X+011211Y+024837X0198Y0197     S1      
317P12V_SSD1_R      VIA   -    MD0100PA00X+018612Y+016870X0200Y         S0      
327P12V_SSD1_R      R524  -1          A01X+018317Y+016870X0198Y0197R180 S1      
327P12V_SSD1_R      PC368 -1          A01X+017924Y+021661X0198Y0197R090 S1      
327P12V_SSD1_R      PC645 -1          A01X+017302Y+021554X0400Y0500R270 S1      
327P12V_SSD1_R      PD26  -C          A01X+016221Y+021175X0670Y0990     S1      
327P12V_SSD1_R      C205  -1          A01X+018030Y+018426X0198Y0197R090 S1      
327P12V_SSD1_R      R516  -2          A01X+016531Y+018919X1150Y1380R090 S1      
327P12V_SSD1_R      U54   -11         A01X+018680Y+018187X0090Y0240R090 S1      
317P12V_SSD1_R      VIA   -    MD0100PA00X+018288Y+021563X0200Y    R090 S0      
317P12V_SSD1_R      VIA   -    MD0100PA00X+016755Y+021571X0200Y    R090 S0      
317P12V_SSD1_R      VIA   -    M      A01X+017442Y+020870X0200Y         S2      
017P12V_SSD1_R      VIA   -    M      A18X+017442Y+020870X0260Y         S2      
017P12V_SSD1_R            -    MD0100PA00X+017442Y+020870                       
317P12V_SSD1_R      VIA   -    MD0100PA00X+017162Y+020870X0200Y         S0      
317P12V_SSD1_R      VIA   -    MD0100PA00X+016755Y+021071X0200Y    R090 S0      
317P12V_SSD1_R      VIA   -    MD0100PA00X+016755Y+021321X0200Y    R090 S0      
317P12V_SSD1_R      VIA   -    MD0100PA00X+016755Y+020821X0200Y    R090 S0      
317P12V_SSD1_R      VIA   -    MD0100PA00X+017412Y+021170X0200Y         S0      
317P12V_SSD1_R      VIA   -    MD0100PA00X+017918Y+021386X0200Y    R090 S0      
317P12V_SSD1_R      VIA   -    MD0100PA00X+017918Y+021136X0200Y    R090 S0      
317P12V_SSD1_R      VIA   -    MD0100PA00X+018288Y+021313X0200Y    R090 S0      
317P12V_SSD1_R      VIA   -    MD0100PA00X+017162Y+021170X0200Y         S0      
317P12V_SSD1_R      VIA   -    MD0100PA00X+015710Y+021298X0200Y    R090 S0      
317P12V_SSD1_R      VIA   -    MD0100PA00X+015710Y+021548X0200Y    R090 S0      
317P12V_SSD1_R      VIA   -    MD0100PA00X+015710Y+020798X0200Y    R090 S0      
317P12V_SSD1_R      VIA   -    MD0100PA00X+015710Y+021048X0200Y    R090 S0      
317P12V_SSD1_R      VIA   -    MD0100PA00X+017776Y+018401X0200Y         S0      
317P12V_SSD1_R      VIA   -    MD0100PA00X+017514Y+018422X0200Y         S0      
317P12V_SSD1_R      VIA   -    MD0100PA00X+017494Y+018143X0200Y         S0      
317P12V_SSD1_R      VIA   -    MD0100PA00X+018094Y+018101X0200Y         S0      
317P12V_SSD1_R      VIA   -    MD0100PA00X+017815Y+018137X0200Y         S0      
317SSD1_ADC_A0      VIA   -           A01X+020112Y+017856X0200Y         S2      
017SSD1_ADC_A0      VIA   -           A18X+020112Y+017856X0260Y         S2      
017SSD1_ADC_A0            -     D0100PA00X+020112Y+017856                       
327SSD1_ADC_A0      U54   -2          A01X+019782Y+018187X0090Y0240R090 S1      
327SSD1_ADC_A0      R518  -1          A01X+020411Y+017666X0198Y0197     S1      
327SSD1_ADC_A0      R519  -1   M      A01X+020411Y+018066X0198Y0197     S1      
317m2722            VIA   -    M      A01X+029762Y+019249X0200Y         S2      
017m2722            VIA   -    M      A18X+029762Y+019249X0260Y         S2      
017m2722                  -    MD0100PA00X+029762Y+019249                       
327m2722            R533  -2          A01X+030647Y+019666X0198Y0197R180 S1      
327m2722            U55   -5          A01X+029762Y+018836X0090Y0240R180 S1      
317m2723            VIA   -    MD0100PA00X+091693Y+099440X0200Y         S0      
317m2723            VIA   -    M      A01X+103836Y+087529X0200Y         S2      
017m2723            VIA   -    M      A18X+103836Y+087529X0260Y         S2      
017m2723                  -    MD0100PA00X+103836Y+087529                       
317m2723            VIA   -    MD0100PA00X+091378Y+122106X0200Y         S0      
327m2723            R4436 -1          A01X+091273Y+122493X0198Y0197R090 S1      
327m2723            U6    -G5         A01X+132793Y+087869X0160Y         S1      
317m2723            VIA   -    MD0100PA00X+132636Y+088026X0180Y         S0      
317m2724            VIA   -    M      A01X+020102Y+018383X0200Y         S2      
017m2724            VIA   -    M      A18X+020102Y+018383X0260Y         S2      
017m2724                  -    MD0100PA00X+020102Y+018383                       
327m2724            U54   -3          A01X+019782Y+018383X0090Y0240R090 S1      
327m2724            R520  -1          A01X+020411Y+018466X0198Y0197     S1      
327P1V25_PEX1_R     PC238 -1          A01X+087532Y+112564X0630Y1190R270 S1      
327P1V25_PEX1_R     PC239 -1          A01X+089018Y+111910X0630Y1190R090 S1      
327P1V25_PEX1_R     U90   -11         A01X+089388Y+109268X0090Y0240R090 S1      
327P1V25_PEX1_R     VIA   -           A18X+088997Y+114784X0260Y         S2      
327P1V25_PEX1_R     VIA   -           A18X+088903Y+113408X0260Y         S2      
317P1V25_PEX1_R     VIA   -    MD0100PA00X+086802Y+114808X0200Y         S0      
317P1V25_PEX1_R     VIA   -    MD0100PA00X+087052Y+114808X0200Y         S0      
317P1V25_PEX1_R     VIA   -    MD0100PA00X+089805Y+114517X0200Y         S0      
317P1V25_PEX1_R     VIA   -    MD0100PA00X+089555Y+114517X0200Y         S0      
327P1V25_PEX1_R     PC993 -1          A18X+089670Y+114917X0400Y0500     S2      
327P1V25_PEX1_R     PC990 -1          A18X+089670Y+114117X0400Y0500     S2      
327P1V25_PEX1_R     PC991 -1          A18X+086958Y+114408X0400Y0500R180 S2      
327P1V25_PEX1_R     PC992 -1          A18X+086958Y+115208X0400Y0500R180 S2      
317P1V25_PEX1_R     VIA   -    M      A01X+090239Y+108176X0200Y         S2      
017P1V25_PEX1_R     VIA   -    M      A18X+090239Y+108176X0260Y         S2      
017P1V25_PEX1_R           -    MD0100PA00X+090239Y+108176                       
327P1V25_PEX1_R     R788  -1          A01X+089999Y+108176X0198Y0197R180 S1      
327P1V25_PEX1_R     PL20  -2          A01X+088514Y+114707X1160Y1460R270 S1      
327P1V25_PEX1_R     PC236 -1          A01X+089828Y+113393X0198Y0197     S1      
327P1V25_PEX1_R     C629  -1          A01X+088739Y+109557X0198Y0197R090 S1      
327P1V25_PEX1_R     R781  -2          A01X+087125Y+110031X1150Y1380R090 S1      
317P1V25_PEX1_R     VIA   -    MD0100PA00X+089828Y+113643X0200Y    R270 S0      
327P1V25_PEX1_R     PC235 -1          A18X+089623Y+112810X0400Y0500     S2      
317P1V25_PEX1_R     VIA   -    MD0100PA00X+089258Y+113287X0200Y         S0      
317P1V25_PEX1_R     VIA   -    MD0100PA00X+089528Y+113287X0200Y         S0      
327P1V25_PEX1_R     PC233 -1          A18X+086940Y+113464X0400Y0500R180 S2      
317P1V25_PEX1_R     VIA   -    MD0100PA00X+087136Y+113034X0200Y         S0      
317P1V25_PEX1_R     VIA   -    MD0100PA00X+087396Y+113034X0200Y         S0      
317P1V25_PEX1_R     VIA   -    MD0100PA00X+087656Y+113034X0200Y         S0      
317P1V25_PEX1_R     VIA   -    MD0100PA00X+087926Y+113034X0200Y         S0      
317P1V25_PEX1_R     VIA   -    MD0100PA00X+086866Y+113934X0200Y    R180 S0      
317P1V25_PEX1_R     VIA   -    MD0100PA00X+087136Y+113934X0200Y         S0      
327P1V25_PEX1_R     PC234 -1          A18X+089623Y+111910X0400Y0500     S2      
317P1V25_PEX1_R     VIA   -    MD0100PA00X+089425Y+112380X0200Y         S0      
317P1V25_PEX1_R     VIA   -    MD0100PA00X+089155Y+112380X0200Y         S0      
317P1V25_PEX1_R     VIA   -    MD0100PA00X+088895Y+112380X0200Y         S0      
317P1V25_PEX1_R     VIA   -    MD0100PA00X+088635Y+112380X0200Y         S0      
317P1V25_PEX1_R     VIA   -    MD0100PA00X+088635Y+111410X0200Y         S0      
317P1V25_PEX1_R     VIA   -    MD0100PA00X+088895Y+111410X0200Y         S0      
317P1V25_PEX1_R     VIA   -    MD0100PA00X+089155Y+111410X0200Y         S0      
317P1V25_PEX1_R     VIA   -    MD0100PA00X+089425Y+111410X0200Y         S0      
327P1V25_PEX1_R     PC232 -1          A18X+086940Y+112564X0400Y0500R180 S2      
317P1V25_PEX1_R     VIA   -    MD0100PA00X+086748Y+111018X0200Y         S0      
317P1V25_PEX1_R     VIA   -    MD0100PA00X+087008Y+111018X0200Y         S0      
317P1V25_PEX1_R     VIA   -    MD0100PA00X+087268Y+111018X0200Y         S0      
317P1V25_PEX1_R     VIA   -    MD0100PA00X+087538Y+111018X0200Y         S0      
317P1V25_PEX1_R     VIA   -    MD0100PA00X+087926Y+112064X0200Y         S0      
317P1V25_PEX1_R     VIA   -    MD0100PA00X+087656Y+112064X0200Y         S0      
317P1V25_PEX1_R     VIA   -    MD0100PA00X+087396Y+112064X0200Y         S0      
317P1V25_PEX1_R     VIA   -    MD0100PA00X+087136Y+112064X0200Y         S0      
317P1V25_PEX1_R     VIA   -    MD0100PA00X+086748Y+110765X0200Y         S0      
317P1V25_PEX1_R     VIA   -    MD0100PA00X+087008Y+110765X0200Y         S0      
317P1V25_PEX1_R     VIA   -    MD0100PA00X+087268Y+110765X0200Y         S0      
317P1V25_PEX1_R     VIA   -    MD0100PA00X+087538Y+110765X0200Y         S0      
327P12V_SSD2_R      PU34  -1          A01X+028798Y+021907X0110Y0240R270 S1      
327P12V_SSD2_R      PU34  -2          A01X+028798Y+021710X0110Y0240R270 S1      
327P12V_SSD2_R      PU34  -3          A01X+028798Y+021513X0110Y0240R270 S1      
327P12V_SSD2_R      PU34  -4          A01X+028798Y+021317X0110Y0240R270 S1      
327P12V_SSD2_R      PU34  -5          A01X+028798Y+021120X0110Y0240R270 S1      
327P12V_SSD2_R      PU78  -6_7        A01X+028425Y+027354X0295Y0354R090 S1      
327P12V_SSD2_R      PC381 -1          A01X+027496Y+027416X0400Y0500R270 S1      
327P12V_SSD2_R      PD90  -C          A01X+026434Y+027104X0670Y0990     S1      
317P12V_SSD2_R      VIA   -    MD0100PA00X+027168Y+027003X0200Y         S0      
317P12V_SSD2_R      VIA   -    MD0100PA00X+027448Y+027003X0200Y         S0      
317P12V_SSD2_R      VIA   -    MD0100PA00X+027448Y+026753X0200Y         S0      
317P12V_SSD2_R      VIA   -    MD0100PA00X+027168Y+026753X0200Y         S0      
317P12V_SSD2_R      VIA   -    MD0100PA00X+027698Y+027003X0200Y         S0      
317P12V_SSD2_R      VIA   -    MD0100PA00X+027698Y+026753X0200Y         S0      
317P12V_SSD2_R      VIA   -    MD0100PA00X+026529Y+026418X0200Y         S0      
317P12V_SSD2_R      VIA   -    MD0100PA00X+026279Y+026418X0200Y         S0      
317P12V_SSD2_R      VIA   -    MD0100PA00X+021169Y+024837X0200Y         S0      
327P12V_SSD2_R      R5852 -1          A01X+021447Y+024837X0198Y0197     S1      
317P12V_SSD2_R      VIA   -    MD0100PA00X+028848Y+016870X0200Y         S0      
327P12V_SSD2_R      R535  -1          A01X+028553Y+016870X0198Y0197R180 S1      
327P12V_SSD2_R      PC380 -1          A01X+028160Y+021661X0198Y0197R090 S1      
327P12V_SSD2_R      PC650 -1          A01X+027538Y+021554X0400Y0500R270 S1      
327P12V_SSD2_R      PD30  -C          A01X+026457Y+021175X0670Y0990     S1      
327P12V_SSD2_R      C208  -1          A01X+028266Y+018426X0198Y0197R090 S1      
327P12V_SSD2_R      R527  -2          A01X+026767Y+018919X1150Y1380R090 S1      
327P12V_SSD2_R      U55   -11         A01X+028916Y+018187X0090Y0240R090 S1      
317P12V_SSD2_R      VIA   -    MD0100PA00X+028525Y+021563X0200Y    R090 S0      
317P12V_SSD2_R      VIA   -    MD0100PA00X+026991Y+021571X0200Y    R090 S0      
317P12V_SSD2_R      VIA   -    MD0100PA00X+028154Y+021386X0200Y    R090 S0      
317P12V_SSD2_R      VIA   -    MD0100PA00X+028154Y+021136X0200Y    R090 S0      
317P12V_SSD2_R      VIA   -    MD0100PA00X+028525Y+021313X0200Y    R090 S0      
317P12V_SSD2_R      VIA   -    MD0100PA00X+026991Y+021321X0200Y    R090 S0      
317P12V_SSD2_R      VIA   -    MD0100PA00X+026991Y+020821X0200Y    R090 S0      
317P12V_SSD2_R      VIA   -    MD0100PA00X+027648Y+021170X0200Y         S0      
317P12V_SSD2_R      VIA   -    MD0100PA00X+027398Y+021170X0200Y         S0      
317P12V_SSD2_R      VIA   -    M      A01X+027678Y+020870X0200Y         S2      
017P12V_SSD2_R      VIA   -    M      A18X+027678Y+020870X0260Y         S2      
017P12V_SSD2_R            -    MD0100PA00X+027678Y+020870                       
317P12V_SSD2_R      VIA   -    MD0100PA00X+027398Y+020870X0200Y         S0      
317P12V_SSD2_R      VIA   -    MD0100PA00X+026991Y+021071X0200Y    R090 S0      
317P12V_SSD2_R      VIA   -    MD0100PA00X+025946Y+021298X0200Y    R090 S0      
317P12V_SSD2_R      VIA   -    MD0100PA00X+025946Y+021548X0200Y    R090 S0      
317P12V_SSD2_R      VIA   -    MD0100PA00X+025946Y+020798X0200Y    R090 S0      
317P12V_SSD2_R      VIA   -    MD0100PA00X+025946Y+021048X0200Y    R090 S0      
317P12V_SSD2_R      VIA   -    MD0100PA00X+027751Y+018422X0200Y         S0      
317P12V_SSD2_R      VIA   -    MD0100PA00X+028012Y+018401X0200Y         S0      
317P12V_SSD2_R      VIA   -    MD0100PA00X+028330Y+018101X0200Y         S0      
317P12V_SSD2_R      VIA   -    MD0100PA00X+028051Y+018137X0200Y         S0      
317P12V_SSD2_R      VIA   -    MD0100PA00X+027730Y+018143X0200Y         S0      
317SSD3_ADC_A1      VIA   -    M      A01X+040591Y+017266X0200Y         S2      
017SSD3_ADC_A1      VIA   -    M      A18X+040591Y+017266X0260Y         S2      
017SSD3_ADC_A1            -    MD0100PA00X+040591Y+017266                       
327SSD3_ADC_A1      U56   -1          A01X+040254Y+017990X0090Y0240R090 S1      
327SSD3_ADC_A1      R539  -1          A01X+040883Y+016866X0198Y0197     S1      
327SSD3_ADC_A1      R542  -1   M      A01X+040883Y+017266X0198Y0197     S1      
317m2725            VIA   -    M      A01X+038759Y+017762X0200Y         S2      
017m2725            VIA   -    M      A18X+038759Y+017762X0260Y         S2      
017m2725                  -    MD0100PA00X+038759Y+017762                       
327m2725            U56   -12         A01X+039152Y+017990X0090Y0240R090 S1      
327m2725            R547  -2          A01X+038080Y+017615X0198Y0197R090 S1      
327m2725            C308  -2   M      A01X+038480Y+017615X0198Y0197R090 S1      
317m2726            VIA   -    M      A01X+009290Y+019249X0200Y         S2      
017m2726            VIA   -    M      A18X+009290Y+019249X0260Y         S2      
017m2726                  -    MD0100PA00X+009290Y+019249                       
327m2726            R511  -2          A01X+010175Y+019666X0198Y0197R180 S1      
327m2726            U51   -5          A01X+009290Y+018836X0090Y0240R180 S1      
317m2727            VIA   -    M      A01X+028581Y+017219X0200Y         S2      
017m2727            VIA   -    M      A18X+028581Y+017219X0260Y         S2      
017m2727                  -    MD0100PA00X+028581Y+017219                       
327m2727            R535  -2          A01X+028238Y+016870X0198Y0197R180 S1      
327m2727            U55   -13         A01X+029172Y+017734X0090Y0240R180 S1      
327m2727            C209  -1   M      A01X+028244Y+017300X0198Y0197R090 S1      
327m2728            C74   -2          A01X+018176Y+013241X0120Y0150R180 S1      
327m2728            J31   -B26        A01X+016246Y+013303X0150Y0500R090 S1      
327m2729            C70   -2          A01X+007940Y+011824X0120Y0150R180 S1      
327m2729            J30   -B20        A01X+006010Y+011886X0150Y0500R090 S1      
327m2730            C69   -2          A01X+007940Y+012184X0120Y0150R180 S1      
327m2730            J30   -B21        A01X+006010Y+012122X0150Y0500R090 S1      
327m2731            C79   -2          A01X+017136Y+011472X0120Y0150R180 S1      
327m2731            J31   -B18        A01X+016246Y+011413X0150Y0500R090 S1      
327P12V_SSD3        VIA   -           A18X+038568Y+014773X0260Y         S2      
327P12V_SSD3        VIA   -           A18X+037961Y+007538X0260Y         S2      
327P12V_SSD3        J33   -B1         A01X+036718Y+007398X0150Y0500R090 S1      
327P12V_SSD3        J33   -B2         A01X+036718Y+007634X0150Y0500R090 S1      
327P12V_SSD3        J33   -B3         A01X+036718Y+007870X0150Y0500R090 S1      
327P12V_SSD3        J33   -B4         A01X+036718Y+008106X0150Y0500R090 S1      
327P12V_SSD3        J33   -B5         A01X+036718Y+008342X0150Y0500R090 S1      
327P12V_SSD3        J33   -B6         A01X+036718Y+008579X0150Y0500R090 S1      
327P12V_SSD3        R547  -1          A01X+038080Y+017300X0198Y0197R090 S1      
327P12V_SSD3        R538  -1          A01X+037003Y+017069X1150Y1380R090 S1      
327P12V_SSD3        C3897 -1          A01X+038047Y+008845X0198Y0197R090 S1      
327P12V_SSD3        C3893 -1          A01X+038848Y+008845X0198Y0197R090 S1      
327P12V_SSD3        C3898 -1          A01X+038447Y+008845X0198Y0197R090 S1      
327P12V_SSD3        C3894 -1          A01X+037647Y+008845X0198Y0197R090 S1      
327P12V_SSD3        C3896 -1          A01X+038798Y+008414X0198Y0197     S1      
327P12V_SSD3        C3895 -1          A01X+038798Y+008014X0198Y0197     S1      
327P12V_SSD3        C3899 -1          A01X+038798Y+007614X0198Y0197     S1      
317P12V_SSD3        VIA   -    MD0100PA00X+038066Y+017049X0200Y         S0      
317P12V_SSD3        VIA   -    MD0100PA00X+038066Y+016799X0200Y         S0      
327P12V_SSD3        VIA   -           A18X+036637Y+016945X0260Y         S2      
327P12V_SSD3        VIA   -           A18X+037387Y+016945X0260Y         S2      
317P12V_SSD3        VIA   -    MD0100PA00X+038066Y+016279X0200Y         S0      
317P12V_SSD3        VIA   -    MD0100PA00X+038066Y+016539X0200Y         S0      
317P12V_SSD3        VIA   -    MD0100PA00X+037356Y+016237X0200Y    R090 S0      
317P12V_SSD3        VIA   -    MD0100PA00X+037096Y+016237X0200Y    R090 S0      
317P12V_SSD3        VIA   -    MD0100PA00X+037187Y+007479X0200Y         S0      
317P12V_SSD3        VIA   -    MD0100PA00X+037187Y+007739X0200Y         S0      
317P12V_SSD3        VIA   -    MD0100PA00X+037187Y+007999X0200Y         S0      
317P12V_SSD3        VIA   -    MD0100PA00X+037187Y+008259X0200Y         S0      
317P12V_SSD3        VIA   -    MD0100PA00X+037187Y+008519X0200Y         S0      
327P12V_SSD2        VIA   -           A18X+027461Y+013292X0260Y         S2      
327P12V_SSD2        VIA   -           A18X+027562Y+007538X0260Y         S2      
327P12V_SSD2        J32   -B1         A01X+026482Y+007398X0150Y0500R090 S1      
327P12V_SSD2        J32   -B2         A01X+026482Y+007634X0150Y0500R090 S1      
327P12V_SSD2        J32   -B3         A01X+026482Y+007870X0150Y0500R090 S1      
327P12V_SSD2        J32   -B4         A01X+026482Y+008106X0150Y0500R090 S1      
327P12V_SSD2        J32   -B5         A01X+026482Y+008342X0150Y0500R090 S1      
327P12V_SSD2        J32   -B6         A01X+026482Y+008579X0150Y0500R090 S1      
327P12V_SSD2        C3888 -1          A01X+028210Y+008845X0198Y0197R090 S1      
327P12V_SSD2        C3886 -1          A01X+028611Y+008845X0198Y0197R090 S1      
327P12V_SSD2        C3892 -1          A01X+027810Y+008845X0198Y0197R090 S1      
327P12V_SSD2        C3890 -1          A01X+027410Y+008845X0198Y0197R090 S1      
327P12V_SSD2        C3889 -1          A01X+028562Y+008414X0198Y0197     S1      
327P12V_SSD2        C3887 -1          A01X+028562Y+007614X0198Y0197     S1      
327P12V_SSD2        C3891 -1          A01X+028562Y+008014X0198Y0197     S1      
327P12V_SSD2        R536  -1          A01X+027844Y+017300X0198Y0197R090 S1      
327P12V_SSD2        R527  -1          A01X+026767Y+017069X1150Y1380R090 S1      
327P12V_SSD2        VIA   -           A18X+027150Y+016945X0260Y         S2      
317P12V_SSD2        VIA   -    MD0100PA00X+027830Y+017049X0200Y         S0      
317P12V_SSD2        VIA   -    MD0100PA00X+027830Y+016799X0200Y         S0      
327P12V_SSD2        VIA   -           A18X+026400Y+016945X0260Y         S2      
317P12V_SSD2        VIA   -    MD0100PA00X+027830Y+016539X0200Y         S0      
317P12V_SSD2        VIA   -    MD0100PA00X+027830Y+016279X0200Y         S0      
317P12V_SSD2        VIA   -    MD0100PA00X+027120Y+016237X0200Y    R090 S0      
317P12V_SSD2        VIA   -    MD0100PA00X+026860Y+016237X0200Y    R090 S0      
317P12V_SSD2        VIA   -    MD0100PA00X+026951Y+007999X0200Y         S0      
317P12V_SSD2        VIA   -    MD0100PA00X+026951Y+008259X0200Y         S0      
317P12V_SSD2        VIA   -    MD0100PA00X+026951Y+008519X0200Y         S0      
317P12V_SSD2        VIA   -    MD0100PA00X+026951Y+007479X0200Y         S0      
317P12V_SSD2        VIA   -    MD0100PA00X+026951Y+007739X0200Y         S0      
327P12V_SSD1        VIA   -           A18X+017028Y+012047X0260Y         S2      
327P12V_SSD1        VIA   -           A18X+017140Y+015650X0260Y         S2      
327P12V_SSD1        J31   -B1         A01X+016246Y+007398X0150Y0500R090 S1      
327P12V_SSD1        J31   -B2         A01X+016246Y+007634X0150Y0500R090 S1      
327P12V_SSD1        J31   -B3         A01X+016246Y+007870X0150Y0500R090 S1      
327P12V_SSD1        J31   -B4         A01X+016246Y+008106X0150Y0500R090 S1      
327P12V_SSD1        J31   -B5         A01X+016246Y+008342X0150Y0500R090 S1      
327P12V_SSD1        J31   -B6         A01X+016246Y+008579X0150Y0500R090 S1      
327P12V_SSD1        R525  -1          A01X+017607Y+017300X0198Y0197R090 S1      
327P12V_SSD1        R516  -1          A01X+016531Y+017069X1150Y1380R090 S1      
327P12V_SSD1        C3879 -1          A01X+018375Y+008845X0198Y0197R090 S1      
327P12V_SSD1        C3885 -1          A01X+017574Y+008845X0198Y0197R090 S1      
327P12V_SSD1        C3884 -1          A01X+017174Y+008845X0198Y0197R090 S1      
327P12V_SSD1        C3880 -1          A01X+017974Y+008845X0198Y0197R090 S1      
327P12V_SSD1        C3883 -1          A01X+018326Y+008014X0198Y0197     S1      
327P12V_SSD1        C3882 -1          A01X+018326Y+007614X0198Y0197     S1      
327P12V_SSD1        C3881 -1          A01X+018326Y+008414X0198Y0197     S1      
317P12V_SSD1        VIA   -    MD0100PA00X+017594Y+017049X0200Y         S0      
317P12V_SSD1        VIA   -    MD0100PA00X+017594Y+016799X0200Y         S0      
327P12V_SSD1        VIA   -           A18X+016914Y+016945X0260Y         S2      
327P12V_SSD1        VIA   -           A18X+016164Y+016945X0260Y         S2      
317P12V_SSD1        VIA   -    MD0100PA00X+016884Y+016237X0200Y    R090 S0      
317P12V_SSD1        VIA   -    MD0100PA00X+017594Y+016539X0200Y         S0      
317P12V_SSD1        VIA   -    MD0100PA00X+017594Y+016279X0200Y         S0      
317P12V_SSD1        VIA   -    MD0100PA00X+016624Y+016237X0200Y    R090 S0      
317P12V_SSD1        VIA   -    MD0100PA00X+016715Y+007999X0200Y         S0      
317P12V_SSD1        VIA   -    MD0100PA00X+016715Y+008259X0200Y         S0      
317P12V_SSD1        VIA   -    MD0100PA00X+016715Y+008519X0200Y         S0      
317P12V_SSD1        VIA   -    MD0100PA00X+016715Y+007479X0200Y         S0      
317P12V_SSD1        VIA   -    MD0100PA00X+016715Y+007739X0200Y         S0      
327SMB_PJP1_SCL     PR69  -1          A01X+050817Y+098924X0198Y0197R180 S1      
317SMB_PJP1_SCL     VIA   -    M      A01X+051223Y+098517X0200Y         S2      
017SMB_PJP1_SCL     VIA   -    M      A18X+051223Y+098517X0260Y         S2      
017SMB_PJP1_SCL           -    MD0100PA00X+051223Y+098517                       
327SMB_PJP1_SCL     PJP1  -2          A01X+052137Y+098285X0500Y1350R090 S1      
327P3V3_SSD1        R888  -1          A01X+013456Y+023613X0198Y0197R270 S1      
317P3V3_SSD1        VIA   -    MD0100PA00X+013456Y+023871X0200Y    R090 S0      
327P3V3_SSD1        PU56  -1          A01X+012457Y+021324X0110Y0240     S1      
327P3V3_SSD1        PU56  -2          A01X+012654Y+021324X0110Y0240     S1      
327P3V3_SSD1        PU56  -3          A01X+012851Y+021324X0110Y0240     S1      
327P3V3_SSD1        PU56  -4          A01X+013048Y+021324X0110Y0240     S1      
327P3V3_SSD1        PU56  -5          A01X+013244Y+021324X0110Y0240     S1      
327P3V3_SSD1        PC513 -1          A01X+012811Y+020064X0400Y0500     S1      
327P3V3_SSD1        PC512 -1          A01X+012704Y+020686X0198Y0197R180 S1      
327P3V3_SSD1        PD62  -C          A01X+013289Y+018984X0670Y0990R090 S1      
317P3V3_SSD1        VIA   -    MD0100PA00X+013495Y+020205X0200Y    R090 S0      
317P3V3_SSD1        VIA   -    MD0100PA00X+013195Y+020175X0200Y    R090 S0      
317P3V3_SSD1        VIA   -    MD0100PA00X+012978Y+020681X0200Y    R180 S0      
317P3V3_SSD1        VIA   -    MD0100PA00X+013228Y+020681X0200Y    R180 S0      
317P3V3_SSD1        VIA   -    MD0100PA00X+013051Y+021051X0200Y    R180 S0      
317P3V3_SSD1        VIA   -    MD0100PA00X+012801Y+021051X0200Y    R180 S0      
317P3V3_SSD1        VIA   -    MD0100PA00X+013543Y+019518X0200Y    R180 S0      
317P3V3_SSD1        VIA   -    M      A01X+013495Y+019925X0200Y    R090 S2      
017P3V3_SSD1        VIA   -    M      A18X+013495Y+019925X0260Y    R090 S2      
017P3V3_SSD1              -    MD0100PA00X+013495Y+019925                       
317P3V3_SSD1        VIA   -    MD0100PA00X+013293Y+019518X0200Y    R180 S0      
317P3V3_SSD1        VIA   -    MD0100PA00X+013043Y+019518X0200Y    R180 S0      
317P3V3_SSD1        VIA   -    MD0100PA00X+012793Y+019518X0200Y    R180 S0      
317P3V3_SSD1        VIA   -    MD0100PA00X+013195Y+019925X0200Y    R090 S0      
327P3V3_SSD1        R5875 -1          A01X+007420Y+014754X0198Y0197     S1      
317P3V3_SSD1        VIA   -    MD0100PA00X+007142Y+014754X0200Y         S0      
327P3V3_SSD1        R5733 -1          A01X+018853Y+010824X0198Y0197R270 S1      
317P3V3_SSD1        VIA   -    MD0100PA00X+018596Y+010619X0200Y    R090 S0      
327P3V3_SSD1        R412  -1          A01X+017902Y+010135X0198Y0197R270 S1      
317P3V3_SSD1        VIA   -    MD0100PA00X+017902Y+010378X0200Y    R270 S0      
317P3V3_SSD1        VIA   -    MD0100PA00X+011933Y+011659X0200Y         S0      
317P3V3_SSD1        VIA   -    MD0100PA00X+011933Y+011959X0200Y         S0      
327P3V3_SSD1        PC673 -1   M      A01X+012360Y+011967X0400Y0500R090 S1      
327P3V3_SSD1        R5648 -2          A01X+012478Y+013484X0198Y0197     S1      
327P3V3_SSD1        PU82  -6_7        A01X+011479Y+011762X0295Y0354R270 S1      
327P3V3_SSD1        C966  -2   M      A01X+017294Y+009855X0198Y0197R270 S1      
317P3V3_SSD1        VIA   -    MD0100PA00X+017547Y+009855X0200Y    R090 S0      
327P3V3_SSD1        J31   -B11        A01X+016246Y+009760X0150Y0500R090 S1      
327P3V3_SSD1        R413  -1          A01X+013138Y+009767X0198Y0197     S1      
317P3V3_SSD1        VIA   -    M      A01X+012895Y+009767X0200Y         S2      
017P3V3_SSD1        VIA   -    M      A18X+012895Y+009767X0260Y         S2      
017P3V3_SSD1              -    MD0100PA00X+012895Y+009767                       
327P3V3_SSD1        R1636 -1          A01X+019707Y+008058X0198Y0197R180 S1      
317P3V3_SSD1        VIA   -    MD0100PA00X+019949Y+008058X0200Y         S0      
327P3V3_SSD1        R1635 -1          A01X+019707Y+006858X0198Y0197R180 S1      
317P3V3_SSD1        VIA   -    MD0100PA00X+019947Y+006858X0200Y         S0      
327P3V3_SSD1        C2714 -2   M      A01X+020325Y+005801X0198Y0197R180 S1      
327P3V3_SSD1        U127  -1          A01X+020299Y+006472X0240Y0460R180 S1      
317P3V3_SSD1        VIA   -    MD0100PA00X+020325Y+005551X0200Y         S0      
327PU_CLKREQ1       J31   -A11        A01X+014435Y+009760X0150Y0500R090 S1      
317PU_CLKREQ1       VIA   -    M      A01X+013780Y+009767X0200Y         S2      
017PU_CLKREQ1       VIA   -    M      A18X+013780Y+009767X0260Y         S2      
017PU_CLKREQ1             -    MD0100PA00X+013780Y+009767                       
327PU_CLKREQ1       R413  -2          A01X+013454Y+009767X0198Y0197     S1      
327SMB_PJP1_SDA     PR73  -1          A01X+050108Y+099276X0198Y0197R270 S1      
317SMB_PJP1_SDA     VIA   -    M      A01X+052254Y+099285X0200Y         S2      
017SMB_PJP1_SDA     VIA   -    M      A18X+052254Y+099285X0260Y         S2      
017SMB_PJP1_SDA           -    MD0100PA00X+052254Y+099285                       
327SMB_PJP1_SDA     PJP1  -1          A01X+053287Y+099285X0500Y1350R090 S1      
327PU_CLKREQ3       J33   -A11        A01X+034907Y+009760X0150Y0500R090 S1      
317PU_CLKREQ3       VIA   -    M      A01X+034253Y+009767X0200Y         S2      
017PU_CLKREQ3       VIA   -    M      A18X+034253Y+009767X0260Y         S2      
017PU_CLKREQ3             -    MD0100PA00X+034253Y+009767                       
327PU_CLKREQ3       R419  -2          A01X+033926Y+009767X0198Y0197     S1      
327PU_CLKREQ2       J32   -A11        A01X+024671Y+009760X0150Y0500R090 S1      
317PU_CLKREQ2       VIA   -    M      A01X+024017Y+009767X0200Y         S2      
017PU_CLKREQ2       VIA   -    M      A18X+024017Y+009767X0260Y         S2      
017PU_CLKREQ2             -    MD0100PA00X+024017Y+009767                       
327PU_CLKREQ2       R417  -2          A01X+023690Y+009767X0198Y0197     S1      
327m2732            J33   -B9         A01X+036718Y+009287X0150Y0500R090 S1      
317m2732            VIA   -    M      A01X+037192Y+009287X0200Y         S2      
017m2732            VIA   -    M      A18X+037192Y+009287X0260Y         S2      
017m2732                  -    MD0100PA00X+037192Y+009287                       
327m2732            R420  -2          A01X+038775Y+009820X0198Y0197R270 S1      
327m2732            R418  -2   M      A01X+038375Y+009820X0198Y0197R270 S1      
327m2733            J32   -B9         A01X+026482Y+009287X0150Y0500R090 S1      
317m2733            VIA   -    M      A01X+026955Y+009287X0200Y         S2      
017m2733            VIA   -    M      A18X+026955Y+009287X0260Y         S2      
017m2733                  -    MD0100PA00X+026955Y+009287                       
327m2733            R416  -2          A01X+028538Y+009820X0198Y0197R270 S1      
327m2733            R415  -2   M      A01X+028138Y+009820X0198Y0197R270 S1      
327PRSNT_SSD2_N     J32   -A12        A01X+024671Y+009996X0150Y0500R090 S1      
317PRSNT_SSD2_N     VIA   -    M      A01X+023977Y+010341X0200Y         S2      
017PRSNT_SSD2_N     VIA   -    M      A18X+023977Y+010341X0260Y         S2      
017PRSNT_SSD2_N           -    MD0100PA00X+023977Y+010341                       
327PRSNT_SSD2_N     R4057 -2          A01X+023670Y+010341X0198Y0197R270 S1      
327PRSNT_SSD3_N     J33   -A12        A01X+034907Y+009996X0150Y0500R090 S1      
317PRSNT_SSD3_N     VIA   -    M      A01X+034213Y+010341X0200Y         S2      
017PRSNT_SSD3_N     VIA   -    M      A18X+034213Y+010341X0260Y         S2      
017PRSNT_SSD3_N           -    MD0100PA00X+034213Y+010341                       
327PRSNT_SSD3_N     R4059 -2          A01X+033906Y+010341X0198Y0197R270 S1      
327m2734            C75   -2          A01X+017136Y+012890X0120Y0150R180 S1      
327m2734            J31   -B24        A01X+016246Y+012831X0150Y0500R090 S1      
327m2735            C89   -2          A01X+038649Y+013601X0120Y0150R180 S1      
327m2735            J33   -B27        A01X+036718Y+013539X0150Y0500R090 S1      
327m2736            C85   -2          A01X+028412Y+012184X0120Y0150R180 S1      
327m2736            J32   -B21        A01X+026482Y+012122X0150Y0500R090 S1      
327m2737            C84   -2          A01X+027372Y+012530X0120Y0150R180 S1      
327m2737            J32   -B23        A01X+026482Y+012594X0150Y0500R090 S1      
327m2738            C72   -2          A01X+006900Y+011112X0120Y0150R180 S1      
327m2738            J30   -B17        A01X+006010Y+011177X0150Y0500R090 S1      
327m2739            C87   -2          A01X+027372Y+011472X0120Y0150R180 S1      
327m2739            J32   -B18        A01X+026482Y+011413X0150Y0500R090 S1      
327PRSNT_SSD1_N     J31   -A12        A01X+014435Y+009996X0150Y0500R090 S1      
317PRSNT_SSD1_N     VIA   -    M      A01X+013741Y+010341X0200Y         S2      
017PRSNT_SSD1_N     VIA   -    M      A18X+013741Y+010341X0260Y         S2      
017PRSNT_SSD1_N           -    MD0100PA00X+013741Y+010341                       
327PRSNT_SSD1_N     R4052 -2          A01X+013433Y+010341X0198Y0197R270 S1      
327m2740            C68   -2          A01X+006900Y+012530X0120Y0150R180 S1      
327m2740            J30   -B23        A01X+006010Y+012594X0150Y0500R090 S1      
327m2741            C88   -2          A01X+027372Y+011112X0120Y0150R180 S1      
327m2741            J32   -B17        A01X+026482Y+011177X0150Y0500R090 S1      
327m2742            J31   -B9         A01X+016246Y+009287X0150Y0500R090 S1      
317m2742            VIA   -    M      A01X+016719Y+009287X0200Y         S2      
017m2742            VIA   -    M      A18X+016719Y+009287X0260Y         S2      
017m2742                  -    MD0100PA00X+016719Y+009287                       
327m2742            R414  -2          A01X+018302Y+009820X0198Y0197R270 S1      
327m2742            R412  -2   M      A01X+017902Y+009820X0198Y0197R270 S1      
327m2743            C67   -2          A01X+006900Y+012890X0120Y0150R180 S1      
327m2743            J30   -B24        A01X+006010Y+012831X0150Y0500R090 S1      
327m2744            C77   -2          A01X+018176Y+012184X0120Y0150R180 S1      
327m2744            J31   -B21        A01X+016246Y+012122X0150Y0500R090 S1      
327m2745            C78   -2          A01X+018176Y+011824X0120Y0150R180 S1      
327m2745            J31   -B20        A01X+016246Y+011886X0150Y0500R090 S1      
327m2746            C96   -2          A01X+037608Y+011112X0120Y0150R180 S1      
327m2746            J33   -B17        A01X+036718Y+011177X0150Y0500R090 S1      
327m2747            C83   -2          A01X+027372Y+012890X0120Y0150R180 S1      
327m2747            J32   -B24        A01X+026482Y+012831X0150Y0500R090 S1      
327m2748            C86   -2          A01X+028412Y+011824X0120Y0150R180 S1      
327m2748            J32   -B20        A01X+026482Y+011886X0150Y0500R090 S1      
327m2749            C76   -2          A01X+017136Y+012530X0120Y0150R180 S1      
327m2749            J31   -B23        A01X+016246Y+012594X0150Y0500R090 S1      
327m2750            C92   -2          A01X+037608Y+012530X0120Y0150R180 S1      
327m2750            J33   -B23        A01X+036718Y+012594X0150Y0500R090 S1      
327m2751            J30   -B9         A01X+006010Y+009287X0150Y0500R090 S1      
317m2751            VIA   -    M      A01X+006483Y+009287X0200Y         S2      
017m2751            VIA   -    M      A18X+006483Y+009287X0260Y         S2      
017m2751                  -    MD0100PA00X+006483Y+009287                       
327m2751            R409  -2   M      A01X+007666Y+009820X0198Y0197R270 S1      
327m2751            R411  -2          A01X+008066Y+009820X0198Y0197R270 S1      
327m2752            C93   -2          A01X+038649Y+012184X0120Y0150R180 S1      
327m2752            J33   -B21        A01X+036718Y+012122X0150Y0500R090 S1      
327PRSNT_SSD0_N     J30   -A12        A01X+004199Y+009996X0150Y0500R090 S1      
317PRSNT_SSD0_N     VIA   -    M      A01X+003505Y+010341X0200Y         S2      
017PRSNT_SSD0_N     VIA   -    M      A18X+003505Y+010341X0260Y         S2      
017PRSNT_SSD0_N           -    MD0100PA00X+003505Y+010341                       
327PRSNT_SSD0_N     R4051 -2          A01X+003197Y+010341X0198Y0197R270 S1      
327m2753            C66   -2          A01X+007940Y+013241X0120Y0150R180 S1      
327m2753            J30   -B26        A01X+006010Y+013303X0150Y0500R090 S1      
327m2754            C94   -2          A01X+038649Y+011824X0120Y0150R180 S1      
327m2754            J33   -B20        A01X+036718Y+011886X0150Y0500R090 S1      
327m2755            C73   -2          A01X+018176Y+013601X0120Y0150R180 S1      
327m2755            J31   -B27        A01X+016246Y+013539X0150Y0500R090 S1      
327PU_CLKREQ0       J30   -A11        A01X+004199Y+009760X0150Y0500R090 S1      
317PU_CLKREQ0       VIA   -    M      A01X+003544Y+009767X0200Y         S2      
017PU_CLKREQ0       VIA   -    M      A18X+003544Y+009767X0260Y         S2      
017PU_CLKREQ0             -    MD0100PA00X+003544Y+009767                       
327PU_CLKREQ0       R410  -2          A01X+003217Y+009767X0198Y0197     S1      
327m2756            C95   -2          A01X+037608Y+011472X0120Y0150R180 S1      
327m2756            J33   -B18        A01X+036718Y+011413X0150Y0500R090 S1      
327m2757            C71   -2          A01X+006900Y+011472X0120Y0150R180 S1      
327m2757            J30   -B18        A01X+006010Y+011413X0150Y0500R090 S1      
327m2758            C81   -2          A01X+028412Y+013601X0120Y0150R180 S1      
327m2758            J32   -B27        A01X+026482Y+013539X0150Y0500R090 S1      
327m2759            C80   -2          A01X+017136Y+011112X0120Y0150R180 S1      
327m2759            J31   -B17        A01X+016246Y+011177X0150Y0500R090 S1      
327m2760            C82   -2          A01X+028412Y+013241X0120Y0150R180 S1      
327m2760            J32   -B26        A01X+026482Y+013303X0150Y0500R090 S1      
327m2761            C91   -2          A01X+037608Y+012890X0120Y0150R180 S1      
327m2761            J33   -B24        A01X+036718Y+012831X0150Y0500R090 S1      
327m2762            C90   -2          A01X+038649Y+013241X0120Y0150R180 S1      
327m2762            J33   -B26        A01X+036718Y+013303X0150Y0500R090 S1      
327m2763            C65   -2          A01X+007940Y+013601X0120Y0150R180 S1      
327m2763            J30   -B27        A01X+006010Y+013539X0150Y0500R090 S1      
327P12V_NIC7_OCP    PR206 -1          A01X+175650Y+037663X0198Y0197R270 S1      
327P12V_NIC7_OCP    PU29  -9          A01X+175466Y+038373X0110Y0240R180 S1      
317P12V_NIC7_OCP    VIA   -    M      A01X+175543Y+037903X0200Y         S2      
017P12V_NIC7_OCP    VIA   -    M      A18X+175543Y+037903X0260Y         S2      
017P12V_NIC7_OCP          -    MD0100PA00X+175543Y+037903                       
327P12V_NIC6_SS     PU27  -7          A01X+140958Y+054436X0110Y0240R090 S1      
327P12V_NIC6_SS     PC339 -1          A01X+140281Y+055273X0180Y0200     S1      
317P12V_NIC6_SS     VIA   -    M      A01X+140571Y+055273X0200Y    R180 S2      
017P12V_NIC6_SS     VIA   -    M      A18X+140571Y+055273X0260Y    R180 S2      
017P12V_NIC6_SS           -    MD0100PA00X+140571Y+055273                       
327P12V_NIC3_EN_R   PU28  -11         A01X+088266Y+039707X0110Y0240R180 S1      
317P12V_NIC3_EN_R   VIA   -    M      A01X+089055Y+039204X0200Y    R270 S2      
017P12V_NIC3_EN_R   VIA   -    M      A18X+089055Y+039204X0260Y    R270 S2      
017P12V_NIC3_EN_R         -    MD0100PA00X+089055Y+039204                       
327P12V_NIC3_EN_R   R4456 -2          A01X+089774Y+038886X0198Y0197R090 S1      
327P12V_NIC3_EN_R   C2859 -1   M      A01X+089374Y+038886X0198Y0197R270 S1      
327P12V_NIC2        VIA   -           A18X+054157Y+055674X0260Y         S2      
327P12V_NIC2        VIA   -           A18X+054376Y+056600X0260Y         S2      
327P12V_NIC2        J22   -B1         A01X+063836Y+057545X0140Y0480R270 S1      
327P12V_NIC2        J22   -B2         A01X+063836Y+057309X0140Y0480R270 S1      
327P12V_NIC2        C875  -1          A01X+060997Y+057906X0400Y0500R270 S1      
327P12V_NIC2        C876  -1          A01X+060297Y+057906X0400Y0500R270 S1      
327P12V_NIC2        J22   -B3         A01X+063836Y+057073X0140Y0480R270 S1      
327P12V_NIC2        J22   -B4         A01X+063836Y+056837X0140Y0480R270 S1      
327P12V_NIC2        J22   -B5         A01X+063836Y+056600X0140Y0480R270 S1      
327P12V_NIC2        J22   -B6         A01X+063836Y+056364X0140Y0480R270 S1      
327P12V_NIC2        R712  -1          A01X+054044Y+057161X0198Y0197R180 S1      
327P12V_NIC2        R704  -1          A01X+054275Y+056085X1150Y1380R180 S1      
327P12V_NIC2        C879  -1          A18X+063660Y+057539X0120Y0150R180 S2      
327P12V_NIC2        C877  -1          A18X+063660Y+056219X0120Y0150R180 S2      
327P12V_NIC2        C878  -1          A18X+063660Y+056539X0120Y0150R180 S2      
327P12V_NIC2        C880  -1          A18X+063660Y+056859X0120Y0150R180 S2      
327P12V_NIC2        C881  -1          A18X+063660Y+057199X0120Y0150R180 S2      
317P12V_NIC2        VIA   -    MD0100PA00X+063186Y+056848X0200Y         S0      
317P12V_NIC2        VIA   -    MD0100PA00X+063212Y+057096X0200Y         S0      
317P12V_NIC2        VIA   -    MD0100PA00X+062977Y+056993X0200Y         S0      
317P12V_NIC2        VIA   -    MD0100PA00X+062842Y+057207X0200Y         S0      
317P12V_NIC2        VIA   -    MD0100PA00X+063447Y+056693X0200Y         S0      
317P12V_NIC2        VIA   -    MD0100PA00X+063418Y+056943X0200Y         S0      
317P12V_NIC2        VIA   -    MD0100PA00X+053522Y+055850X0200Y         S0      
317P12V_NIC2        VIA   -    M      A01X+053522Y+056680X0200Y    R180 S2      
017P12V_NIC2        VIA   -    M      A18X+053522Y+056680X0260Y    R180 S2      
017P12V_NIC2              -    MD0100PA00X+053522Y+056680                       
317P12V_NIC2        VIA   -    MD0100PA00X+053522Y+056370X0200Y    R180 S0      
317P12V_NIC2        VIA   -    MD0100PA00X+053522Y+056110X0200Y    R180 S0      
317P12V_NIC2        VIA   -    MD0100PA00X+053522Y+055330X0200Y         S0      
317P12V_NIC2        VIA   -    MD0100PA00X+053522Y+055590X0200Y         S0      
327P12V_NIC4_OCP    PR194 -1          A01X+094572Y+054073X0198Y0197R180 S1      
327P12V_NIC4_OCP    PU23  -9          A01X+095250Y+054042X0110Y0240R090 S1      
317P12V_NIC4_OCP    VIA   -    M      A01X+094853Y+054114X0200Y    R180 S2      
017P12V_NIC4_OCP    VIA   -    M      A18X+094853Y+054114X0260Y    R180 S2      
017P12V_NIC4_OCP          -    MD0100PA00X+094853Y+054114                       
327P12V_NIC3_SS     PU28  -7          A01X+087479Y+039707X0110Y0240R180 S1      
327P12V_NIC3_SS     PC350 -1          A01X+087274Y+038886X0180Y0200R090 S1      
317P12V_NIC3_SS     VIA   -    M      A01X+087274Y+039175X0200Y    R270 S2      
017P12V_NIC3_SS     VIA   -    M      A18X+087274Y+039175X0260Y    R270 S2      
017P12V_NIC3_SS           -    MD0100PA00X+087274Y+039175                       
327P12V_NIC4        VIA   -           A18X+100193Y+056591X0260Y         S2      
327P12V_NIC4        VIA   -           A18X+100041Y+055531X0260Y         S2      
327P12V_NIC4        J24   -B1         A01X+109544Y+057545X0140Y0480R270 S1      
327P12V_NIC4        J24   -B2         A01X+109544Y+057309X0140Y0480R270 S1      
327P12V_NIC4        C906  -1          A01X+106706Y+057906X0400Y0500R270 S1      
327P12V_NIC4        C905  -1          A01X+106006Y+057906X0400Y0500R270 S1      
327P12V_NIC4        J24   -B3         A01X+109544Y+057073X0140Y0480R270 S1      
327P12V_NIC4        J24   -B4         A01X+109544Y+056837X0140Y0480R270 S1      
327P12V_NIC4        J24   -B5         A01X+109544Y+056600X0140Y0480R270 S1      
327P12V_NIC4        J24   -B6         A01X+109544Y+056364X0140Y0480R270 S1      
327P12V_NIC4        R734  -1          A01X+099752Y+057161X0198Y0197R180 S1      
327P12V_NIC4        R727  -1          A01X+099984Y+056085X1150Y1380R180 S1      
327P12V_NIC4        C909  -1          A18X+109369Y+057539X0120Y0150R180 S2      
327P12V_NIC4        C910  -1          A18X+109369Y+056859X0120Y0150R180 S2      
327P12V_NIC4        C908  -1          A18X+109369Y+056539X0120Y0150R180 S2      
327P12V_NIC4        C907  -1          A18X+109369Y+056219X0120Y0150R180 S2      
327P12V_NIC4        C911  -1          A18X+109369Y+057199X0120Y0150R180 S2      
317P12V_NIC4        VIA   -    MD0100PA00X+108551Y+057207X0200Y         S0      
317P12V_NIC4        VIA   -    MD0100PA00X+108686Y+056993X0200Y         S0      
317P12V_NIC4        VIA   -    MD0100PA00X+108921Y+057096X0200Y         S0      
317P12V_NIC4        VIA   -    MD0100PA00X+108895Y+056848X0200Y         S0      
317P12V_NIC4        VIA   -    MD0100PA00X+109127Y+056943X0200Y         S0      
317P12V_NIC4        VIA   -    MD0100PA00X+109156Y+056693X0200Y         S0      
317P12V_NIC4        VIA   -    MD0100PA00X+099231Y+055850X0200Y         S0      
317P12V_NIC4        VIA   -    M      A01X+099231Y+056680X0200Y    R180 S2      
017P12V_NIC4        VIA   -    M      A18X+099231Y+056680X0260Y    R180 S2      
017P12V_NIC4              -    MD0100PA00X+099231Y+056680                       
317P12V_NIC4        VIA   -    MD0100PA00X+099231Y+056370X0200Y    R180 S0      
317P12V_NIC4        VIA   -    MD0100PA00X+099231Y+056110X0200Y    R180 S0      
317P12V_NIC4        VIA   -    MD0100PA00X+099231Y+055330X0200Y         S0      
317P12V_NIC4        VIA   -    MD0100PA00X+099231Y+055590X0200Y         S0      
327P12V_NIC3_OCP    PR205 -1          A01X+088474Y+038886X0198Y0197R270 S1      
327P12V_NIC3_OCP    PU28  -9          A01X+087872Y+039707X0110Y0240R180 S1      
317P12V_NIC3_OCP    VIA   -    M      A01X+088292Y+039110X0200Y    R270 S2      
017P12V_NIC3_OCP    VIA   -    M      A18X+088292Y+039110X0260Y    R270 S2      
017P12V_NIC3_OCP          -    MD0100PA00X+088292Y+039110                       
327P12V_NIC5_OCP    PR198 -1          A01X+129941Y+037663X0198Y0197R270 S1      
327P12V_NIC5_OCP    PU25  -9          A01X+129757Y+038373X0110Y0240R180 S1      
317P12V_NIC5_OCP    VIA   -    M      A01X+129835Y+037903X0200Y         S2      
017P12V_NIC5_OCP    VIA   -    M      A18X+129835Y+037903X0260Y         S2      
017P12V_NIC5_OCP          -    MD0100PA00X+129835Y+037903                       
327P12V_NIC6_OCP    PR202 -1          A01X+140281Y+054073X0198Y0197R180 S1      
327P12V_NIC6_OCP    PU27  -9          A01X+140958Y+054042X0110Y0240R090 S1      
317P12V_NIC6_OCP    VIA   -    M      A01X+140562Y+054114X0200Y    R180 S2      
017P12V_NIC6_OCP    VIA   -    M      A18X+140562Y+054114X0260Y    R180 S2      
017P12V_NIC6_OCP          -    MD0100PA00X+140562Y+054114                       
327P12V_NIC5        VIA   -           A18X+122716Y+043212X0260Y         S2      
327P12V_NIC5        C921  -1          A01X+123172Y+043943X0400Y0500R270 S1      
327P12V_NIC5        J25   -B1         A01X+120259Y+043006X0140Y0480R090 S1      
327P12V_NIC5        J25   -B2         A01X+120259Y+043242X0140Y0480R090 S1      
327P12V_NIC5        J25   -B3         A01X+120259Y+043478X0140Y0480R090 S1      
327P12V_NIC5        J25   -B4         A01X+120259Y+043715X0140Y0480R090 S1      
327P12V_NIC5        J25   -B5         A01X+120259Y+043951X0140Y0480R090 S1      
327P12V_NIC5        J25   -B6         A01X+120259Y+044187X0140Y0480R090 S1      
327P12V_NIC5        R738  -1          A01X+126087Y+042244X1150Y1380     S1      
327P12V_NIC5        R745  -1          A01X+126738Y+041208X0198Y0197R270 S1      
327P12V_NIC5        C920  -1          A01X+123172Y+042694X0400Y0500R090 S1      
327P12V_NIC5        C922  -1          A18X+120420Y+044332X0120Y0150     S2      
327P12V_NIC5        VIA   -           A18X+126056Y+043173X0260Y         S2      
317P12V_NIC5        VIA   -    MD0100PA00X+120663Y+043827X0200Y         S0      
317P12V_NIC5        VIA   -    MD0100PA00X+120663Y+044087X0200Y         S0      
317P12V_NIC5        VIA   -    MD0100PA00X+120663Y+043567X0200Y         S0      
317P12V_NIC5        VIA   -    MD0100PA00X+120663Y+043047X0200Y         S0      
317P12V_NIC5        VIA   -    MD0100PA00X+120663Y+043307X0200Y         S0      
317P12V_NIC5        VIA   -    MD0100PA00X+120943Y+043827X0200Y         S0      
317P12V_NIC5        VIA   -    MD0100PA00X+120943Y+044087X0200Y         S0      
317P12V_NIC5        VIA   -    MD0100PA00X+120943Y+043567X0200Y         S0      
317P12V_NIC5        VIA   -    MD0100PA00X+120943Y+043047X0200Y         S0      
317P12V_NIC5        VIA   -    MD0100PA00X+120943Y+043307X0200Y         S0      
327P12V_NIC5        C925  -1          A18X+120420Y+043352X0120Y0150     S2      
327P12V_NIC5        C924  -1          A18X+120420Y+043012X0120Y0150     S2      
327P12V_NIC5        C923  -1          A18X+120420Y+044012X0120Y0150     S2      
327P12V_NIC5        C926  -1          A18X+120420Y+043692X0120Y0150     S2      
317P12V_NIC5        VIA   -    MD0100PA00X+126833Y+041629X0200Y         S0      
317P12V_NIC5        VIA   -    MD0100PA00X+126833Y+041889X0200Y         S0      
317P12V_NIC5        VIA   -    MD0100PA00X+126833Y+042149X0200Y         S0      
327P12V_NIC5        VIA   -           A18X+126082Y+041900X0260Y         S2      
317P12V_NIC5        VIA   -    MD0100PA00X+126434Y+041211X0200Y    R270 S0      
317P12V_NIC5        VIA   -    MD0100PA00X+125324Y+042209X0200Y         S0      
317P12V_NIC5        VIA   -    MD0100PA00X+125324Y+041949X0200Y         S0      
317P12V_NIC5        VIA   -    MD0100PA00X+125324Y+041689X0200Y         S0      
327P12V_NIC7_EN_R   PU29  -11         A01X+175860Y+038373X0110Y0240R180 S1      
317P12V_NIC7_EN_R   VIA   -    M      A01X+176550Y+037959X0200Y    R270 S2      
017P12V_NIC7_EN_R   VIA   -    M      A18X+176550Y+037959X0260Y    R270 S2      
017P12V_NIC7_EN_R         -    MD0100PA00X+176550Y+037959                       
327P12V_NIC7_EN_R   C2860 -1   M      A01X+176550Y+037663X0198Y0197R270 S1      
327P12V_NIC7_EN_R   R4457 -2          A01X+176950Y+037663X0198Y0197R090 S1      
327P12V_NIC4_EN_R   PU23  -11         A01X+095250Y+053649X0110Y0240R090 S1      
317P12V_NIC4_EN_R   VIA   -    M      A01X+094890Y+053491X0200Y    R180 S2      
017P12V_NIC4_EN_R   VIA   -    M      A18X+094890Y+053491X0260Y    R180 S2      
017P12V_NIC4_EN_R         -    MD0100PA00X+094890Y+053491                       
327P12V_NIC4_EN_R   R4445 -2          A01X+094572Y+052773X0198Y0197     S1      
327P12V_NIC4_EN_R   C2854 -1   M      A01X+094572Y+053173X0198Y0197R180 S1      
327m2764            Q4    -5          A01X+076440Y+031929X0170Y0240R270 S1      
317m2764            VIA   -    M      A01X+075962Y+035396X0200Y         S2      
017m2764            VIA   -    M      A18X+075962Y+035396X0260Y         S2      
017m2764                  -    MD0100PA00X+075962Y+035396                       
317m2764            VIA   -    MD0100PA00X+088074Y+038312X0200Y    R270 S0      
327m2764            R4454 -2          A01X+088074Y+038570X0198Y0197R270 S1      
317m2764            VIA   -    MD0100PA00X+092500Y+047795X0200Y    R270 S0      
327m2764            R5833 -2          A01X+092500Y+047552X0198Y0197R090 S1      
317m2764            VIA   -    MD0100PA00X+085817Y+049503X0200Y         S0      
317m2764            VIA   -    MD0100PA00X+083599Y+071374X0200Y         S0      
317m2764            VIA   -    MD0100PA00X+137045Y+087711X0180Y         S0      
327m2764            U6    -H18        A01X+136887Y+087554X0160Y         S1      
327m2765            PU24  -8          A01X+038143Y+038373X0110Y0240R180 S1      
317m2765            VIA   -    M      A01X+037888Y+037909X0200Y    R270 S2      
017m2765            VIA   -    M      A18X+037888Y+037909X0260Y    R270 S2      
017m2765                  -    MD0100PA00X+037888Y+037909                       
327m2765            R4446 -1          A01X+038124Y+037663X0198Y0197R270 S1      
327m2765            R855  -2   M      A01X+037724Y+037683X0198Y0197R090 S1      
327P12V_NIC2_OCP    PR201 -1          A01X+048864Y+054073X0198Y0197R180 S1      
327P12V_NIC2_OCP    PU26  -9          A01X+049541Y+054042X0110Y0240R090 S1      
317P12V_NIC2_OCP    VIA   -    M      A01X+049144Y+054114X0200Y    R180 S2      
017P12V_NIC2_OCP    VIA   -    M      A18X+049144Y+054114X0260Y    R180 S2      
017P12V_NIC2_OCP          -    MD0100PA00X+049144Y+054114                       
327P12V_NIC6_EN_R   PU27  -11         A01X+140958Y+053649X0110Y0240R090 S1      
317P12V_NIC6_EN_R   VIA   -    M      A01X+140599Y+053491X0200Y    R180 S2      
017P12V_NIC6_EN_R   VIA   -    M      A18X+140599Y+053491X0260Y    R180 S2      
017P12V_NIC6_EN_R         -    MD0100PA00X+140599Y+053491                       
327P12V_NIC6_EN_R   R4453 -2          A01X+140281Y+052773X0198Y0197     S1      
327P12V_NIC6_EN_R   C2858 -1   M      A01X+140281Y+053173X0198Y0197R180 S1      
327P12V_NIC4_SS     PU23  -7          A01X+095250Y+054436X0110Y0240R090 S1      
327P12V_NIC4_SS     PC315 -1          A01X+094572Y+055273X0180Y0200     S1      
317P12V_NIC4_SS     VIA   -    M      A01X+094862Y+055273X0200Y    R180 S2      
017P12V_NIC4_SS     VIA   -    M      A18X+094862Y+055273X0260Y    R180 S2      
017P12V_NIC4_SS           -    MD0100PA00X+094862Y+055273                       
327m2766            PU26  -8          A01X+049541Y+054239X0110Y0240R090 S1      
317m2766            VIA   -    M      A01X+049151Y+054655X0200Y    R180 S2      
017m2766            VIA   -    M      A18X+049151Y+054655X0260Y    R180 S2      
017m2766                  -    MD0100PA00X+049151Y+054655                       
327m2766            R4450 -1          A01X+048864Y+054473X0198Y0197R180 S1      
327m2766            R857  -2   M      A01X+048864Y+054873X0198Y0197     S1      
327P12V_NIC3        C895  -1          A18X+074711Y+044332X0120Y0150     S2      
327P12V_NIC3        VIA   -           A18X+078078Y+043344X0260Y         S2      
327P12V_NIC3        VIA   -           A18X+076758Y+043367X0260Y         S2      
327P12V_NIC3        C892  -1          A18X+074711Y+044012X0120Y0150     S2      
327P12V_NIC3        C893  -1          A18X+074711Y+043012X0120Y0150     S2      
327P12V_NIC3        C894  -1          A18X+074711Y+043352X0120Y0150     S2      
327P12V_NIC3        C896  -1          A18X+074711Y+043692X0120Y0150     S2      
317P12V_NIC3        VIA   -    MD0100PA00X+083138Y+043049X0200Y         S0      
317P12V_NIC3        VIA   -    MD0100PA00X+083138Y+043569X0200Y         S0      
317P12V_NIC3        VIA   -    MD0100PA00X+083138Y+043309X0200Y         S0      
317P12V_NIC3        VIA   -    MD0100PA00X+082510Y+043296X0200Y         S0      
317P12V_NIC3        VIA   -    MD0100PA00X+082510Y+043556X0200Y         S0      
317P12V_NIC3        VIA   -    MD0100PA00X+082510Y+043036X0200Y         S0      
317P12V_NIC3        VIA   -    MD0100PA00X+075234Y+044087X0200Y         S0      
317P12V_NIC3        VIA   -    MD0100PA00X+075234Y+043567X0200Y         S0      
317P12V_NIC3        VIA   -    MD0100PA00X+075234Y+043047X0200Y         S0      
317P12V_NIC3        VIA   -    MD0100PA00X+075234Y+043307X0200Y         S0      
317P12V_NIC3        VIA   -    MD0100PA00X+075234Y+043827X0200Y         S0      
327P12V_NIC3        J23   -B1         A01X+074550Y+043006X0140Y0480R090 S1      
327P12V_NIC3        J23   -B2         A01X+074550Y+043242X0140Y0480R090 S1      
327P12V_NIC3        J23   -B3         A01X+074550Y+043478X0140Y0480R090 S1      
327P12V_NIC3        J23   -B4         A01X+074550Y+043715X0140Y0480R090 S1      
327P12V_NIC3        J23   -B5         A01X+074550Y+043951X0140Y0480R090 S1      
327P12V_NIC3        J23   -B6         A01X+074550Y+044187X0140Y0480R090 S1      
317P12V_NIC3        VIA   -    MD0100PA00X+074954Y+043307X0200Y         S0      
317P12V_NIC3        VIA   -    MD0100PA00X+074954Y+043047X0200Y         S0      
317P12V_NIC3        VIA   -    MD0100PA00X+074954Y+043567X0200Y         S0      
317P12V_NIC3        VIA   -    MD0100PA00X+074954Y+044087X0200Y         S0      
317P12V_NIC3        VIA   -    MD0100PA00X+074954Y+043827X0200Y         S0      
327P12V_NIC3        R723  -1          A01X+085040Y+041876X0198Y0197     S1      
327P12V_NIC3        R716  -1   M      A01X+083913Y+042936X1150Y1380     S1      
317P12V_NIC3        VIA   -    MD0100PA00X+078480Y+042537X0200Y    R270 S0      
327P12V_NIC3        C890  -1          A01X+078043Y+042694X0400Y0500R090 S1      
327P12V_NIC3        C891  -1          A01X+077343Y+042694X0400Y0500R090 S1      
317P12V_NIC3        VIA   -    M      A01X+078490Y+042865X0200Y    R270 S2      
017P12V_NIC3        VIA   -    M      A18X+078490Y+042865X0260Y    R270 S2      
017P12V_NIC3              -    MD0100PA00X+078490Y+042865                       
327P12V_NIC5_SS     PC327 -1          A01X+128744Y+037575X0198Y0197R270 S1      
327P12V_NIC5_SS     PU25  -7          A01X+129363Y+038373X0110Y0240R180 S1      
317P12V_NIC5_SS     VIA   -    M      A01X+128744Y+037943X0200Y    R270 S2      
017P12V_NIC5_SS     VIA   -    M      A18X+128744Y+037943X0260Y    R270 S2      
017P12V_NIC5_SS           -    MD0100PA00X+128744Y+037943                       
327P12V_NIC5_EN_R   PU25  -11         A01X+130151Y+038373X0110Y0240R180 S1      
317P12V_NIC5_EN_R   VIA   -    M      A01X+130841Y+037959X0200Y    R270 S2      
017P12V_NIC5_EN_R   VIA   -    M      A18X+130841Y+037959X0260Y    R270 S2      
017P12V_NIC5_EN_R         -    MD0100PA00X+130841Y+037959                       
327P12V_NIC5_EN_R   R4449 -2          A01X+131241Y+037663X0198Y0197R090 S1      
327P12V_NIC5_EN_R   C2856 -1   M      A01X+130841Y+037663X0198Y0197R270 S1      
327P12V_NIC1_EN_R   PU24  -11         A01X+038734Y+038373X0110Y0240R180 S1      
317P12V_NIC1_EN_R   VIA   -    M      A01X+039424Y+037959X0200Y    R270 S2      
017P12V_NIC1_EN_R   VIA   -    M      A18X+039424Y+037959X0260Y    R270 S2      
017P12V_NIC1_EN_R         -    MD0100PA00X+039424Y+037959                       
327P12V_NIC1_EN_R   R4448 -2          A01X+039824Y+037663X0198Y0197R090 S1      
327P12V_NIC1_EN_R   C2855 -1   M      A01X+039424Y+037663X0198Y0197R270 S1      
327m2767            PU23  -8          A01X+095250Y+054239X0110Y0240R090 S1      
317m2767            VIA   -    M      A01X+094860Y+054655X0200Y    R180 S2      
017m2767            VIA   -    M      A18X+094860Y+054655X0260Y    R180 S2      
017m2767                  -    MD0100PA00X+094860Y+054655                       
327m2767            R4443 -1          A01X+094572Y+054473X0198Y0197R180 S1      
327m2767            R854  -2   M      A01X+094572Y+054873X0198Y0197     S1      
327m2768            PU29  -8          A01X+175269Y+038373X0110Y0240R180 S1      
317m2768            VIA   -    M      A01X+175014Y+037909X0200Y    R270 S2      
017m2768            VIA   -    M      A18X+175014Y+037909X0260Y    R270 S2      
017m2768                  -    MD0100PA00X+175014Y+037909                       
327m2768            R4455 -1          A01X+175250Y+037663X0198Y0197R270 S1      
327m2768            R860  -2   M      A01X+174850Y+037683X0198Y0197R090 S1      
327P12V_NIC2_SS     PU26  -7          A01X+049541Y+054436X0110Y0240R090 S1      
327P12V_NIC2_SS     PC338 -1          A01X+048864Y+055273X0180Y0200     S1      
317P12V_NIC2_SS     VIA   -    M      A01X+049153Y+055273X0200Y    R180 S2      
017P12V_NIC2_SS     VIA   -    M      A18X+049153Y+055273X0260Y    R180 S2      
017P12V_NIC2_SS           -    MD0100PA00X+049153Y+055273                       
327m2769            R5968 -2          A01X+140138Y+062531X0198Y0197R180 S1      
317m2769            VIA   -    MD0100PA00X+139895Y+062531X0200Y         S0      
317m2769            VIA   -    MD0100PA00X+137990Y+086137X0180Y         S0      
327m2769            U6    -M21        A01X+137832Y+086294X0160Y         S1      
327m2769            Q7    -5          A01X+157338Y+069480X0170Y0240R180 S1      
317m2769            VIA   -    M      A01X+139708Y+054473X0200Y    R180 S2      
017m2769            VIA   -    M      A18X+139708Y+054473X0260Y    R180 S2      
017m2769                  -    MD0100PA00X+139708Y+054473                       
327m2769            R4451 -2          A01X+139966Y+054473X0198Y0197R180 S1      
317m2770            VIA   -    MD0100PA00X+137990Y+088656X0180Y         S0      
327m2770            U6    -E21        A01X+137832Y+088499X0160Y         S1      
327m2770            R5831 -2          A01X+042967Y+045918X0198Y0197R090 S1      
317m2770            VIA   -    MD0100PA00X+042967Y+046161X0200Y    R270 S0      
317m2770            VIA   -    MD0100PA00X+034912Y+033610X0200Y         S0      
317m2770            VIA   -    M      A01X+038124Y+037108X0200Y    R270 S2      
017m2770            VIA   -    M      A18X+038124Y+037108X0260Y    R270 S2      
017m2770                  -    MD0100PA00X+038124Y+037108                       
327m2770            Q2    -5          A01X+030731Y+031929X0170Y0240R270 S1      
327m2770            R4446 -2          A01X+038124Y+037348X0198Y0197R270 S1      
317m2770            VIA   -    MD0100PA00X+039147Y+073286X0200Y         S0      
327P12V_NIC7_SS     PU29  -7          A01X+175072Y+038373X0110Y0240R180 S1      
327P12V_NIC7_SS     PC351 -1          A01X+174452Y+037575X0180Y0200R090 S1      
317P12V_NIC7_SS     VIA   -    M      A01X+174452Y+037943X0200Y    R270 S2      
017P12V_NIC7_SS     VIA   -    M      A18X+174452Y+037943X0260Y    R270 S2      
017P12V_NIC7_SS           -    MD0100PA00X+174452Y+037943                       
327P12V_NIC1_OCP    PR197 -1          A01X+038524Y+037663X0198Y0197R270 S1      
327P12V_NIC1_OCP    PU24  -9          A01X+038340Y+038373X0110Y0240R180 S1      
317P12V_NIC1_OCP    VIA   -    M      A01X+038417Y+037903X0200Y         S2      
017P12V_NIC1_OCP    VIA   -    M      A18X+038417Y+037903X0260Y         S2      
017P12V_NIC1_OCP          -    MD0100PA00X+038417Y+037903                       
327P12V_NIC6        VIA   -           A18X+145915Y+056557X0260Y         S2      
327P12V_NIC6        VIA   -           A18X+145696Y+055632X0260Y         S2      
327P12V_NIC6        J26   -B1         A01X+155253Y+057545X0140Y0480R270 S1      
327P12V_NIC6        J26   -B2         A01X+155253Y+057309X0140Y0480R270 S1      
327P12V_NIC6        C936  -1          A01X+151714Y+057906X0400Y0500R270 S1      
327P12V_NIC6        C935  -1          A01X+152414Y+057906X0400Y0500R270 S1      
327P12V_NIC6        J26   -B3         A01X+155253Y+057073X0140Y0480R270 S1      
327P12V_NIC6        J26   -B4         A01X+155253Y+056837X0140Y0480R270 S1      
327P12V_NIC6        J26   -B5         A01X+155253Y+056600X0140Y0480R270 S1      
327P12V_NIC6        J26   -B6         A01X+155253Y+056364X0140Y0480R270 S1      
327P12V_NIC6        R756  -1          A01X+145461Y+057161X0198Y0197R180 S1      
327P12V_NIC6        R748  -1          A01X+145692Y+056085X1150Y1380R180 S1      
327P12V_NIC6        C939  -1          A18X+155078Y+057539X0120Y0150R180 S2      
327P12V_NIC6        C940  -1          A18X+155078Y+056859X0120Y0150R180 S2      
327P12V_NIC6        C938  -1          A18X+155078Y+056539X0120Y0150R180 S2      
327P12V_NIC6        C937  -1          A18X+155078Y+056219X0120Y0150R180 S2      
327P12V_NIC6        C941  -1          A18X+155078Y+057199X0120Y0150R180 S2      
317P12V_NIC6        VIA   -    MD0100PA00X+154864Y+056693X0200Y    R180 S0      
317P12V_NIC6        VIA   -    MD0100PA00X+154836Y+056943X0200Y    R180 S0      
317P12V_NIC6        VIA   -    MD0100PA00X+154604Y+056848X0200Y    R180 S0      
317P12V_NIC6        VIA   -    MD0100PA00X+154629Y+057096X0200Y    R180 S0      
317P12V_NIC6        VIA   -    MD0100PA00X+154395Y+056993X0200Y    R180 S0      
317P12V_NIC6        VIA   -    MD0100PA00X+154270Y+057216X0200Y    R180 S0      
317P12V_NIC6        VIA   -    MD0100PA00X+144939Y+056110X0200Y    R180 S0      
317P12V_NIC6        VIA   -    MD0100PA00X+144939Y+056370X0200Y    R180 S0      
317P12V_NIC6        VIA   -    M      A01X+144939Y+056680X0200Y    R180 S2      
017P12V_NIC6        VIA   -    M      A18X+144939Y+056680X0260Y    R180 S2      
017P12V_NIC6              -    MD0100PA00X+144939Y+056680                       
317P12V_NIC6        VIA   -    MD0100PA00X+144939Y+055850X0200Y         S0      
317P12V_NIC6        VIA   -    MD0100PA00X+144939Y+055590X0200Y         S0      
317P12V_NIC6        VIA   -    MD0100PA00X+144939Y+055330X0200Y         S0      
317m2771            VIA   -    M      A01X+048290Y+054473X0200Y    R180 S2      
017m2771            VIA   -    M      A18X+048290Y+054473X0260Y    R180 S2      
017m2771                  -    MD0100PA00X+048290Y+054473                       
327m2771            R4450 -2          A01X+048548Y+054473X0198Y0197R180 S1      
317m2771            VIA   -    MD0100PA00X+065921Y+069185X0200Y         S0      
327m2771            Q3    -5          A01X+065921Y+069480X0170Y0240R180 S1      
317m2771            VIA   -    MD0100PA00X+054310Y+069877X0200Y         S0      
317m2771            VIA   -    MD0100PA00X+052015Y+093924X0200Y         S0      
327m2771            U6    -G20        A01X+137517Y+087869X0160Y         S1      
317m2771            VIA   -    MD0100PA00X+137675Y+088026X0180Y         S0      
317m2771            VIA   -    MD0100PA00X+048477Y+062531X0200Y         S0      
327m2771            R5832 -2          A01X+048720Y+062531X0198Y0197R180 S1      
327m2772            U6    -J22        A01X+138147Y+087239X0160Y         S1      
317m2772            VIA   -    MD0100PA00X+138305Y+087396X0180Y         S0      
317m2772            VIA   -    M      A01X+093999Y+054473X0200Y    R180 S2      
017m2772            VIA   -    M      A18X+093999Y+054473X0260Y    R180 S2      
017m2772                  -    MD0100PA00X+093999Y+054473                       
327m2772            R4443 -2          A01X+094257Y+054473X0198Y0197R180 S1      
317m2772            VIA   -    MD0100PA00X+094186Y+062531X0200Y         S0      
327m2772            R5966 -2          A01X+094429Y+062531X0198Y0197R180 S1      
317m2772            VIA   -    MD0100PA00X+092969Y+066659X0200Y         S0      
317m2772            VIA   -    MD0100PA00X+111630Y+069185X0200Y         S0      
317m2772            VIA   -    MD0100PA00X+112947Y+073257X0200Y         S0      
317m2772            VIA   -    MD0100PA00X+093397Y+071937X0200Y         S0      
327m2772            Q5    -5          A01X+111630Y+069480X0170Y0240R180 S1      
327m2773            PU28  -8          A01X+087676Y+039707X0110Y0240R180 S1      
317m2773            VIA   -    M      A01X+087791Y+039173X0200Y    R270 S2      
017m2773            VIA   -    M      A18X+087791Y+039173X0260Y    R270 S2      
017m2773                  -    MD0100PA00X+087791Y+039173                       
327m2773            R4454 -1          A01X+088074Y+038886X0198Y0197R270 S1      
327m2773            R859  -2   M      A01X+087674Y+038886X0198Y0197R090 S1      
327m2774            PU27  -8          A01X+140958Y+054239X0110Y0240R090 S1      
317m2774            VIA   -    M      A01X+140568Y+054655X0200Y    R180 S2      
017m2774            VIA   -    M      A18X+140568Y+054655X0260Y    R180 S2      
017m2774                  -    MD0100PA00X+140568Y+054655                       
327m2774            R4451 -1          A01X+140281Y+054473X0198Y0197R180 S1      
327m2774            R858  -2   M      A01X+140281Y+054873X0198Y0197     S1      
327P12V_NIC1_SS     PU24  -7          A01X+037946Y+038373X0110Y0240R180 S1      
327P12V_NIC1_SS     PC326 -1          A01X+037326Y+037575X0180Y0200R090 S1      
317P12V_NIC1_SS     VIA   -    M      A01X+037326Y+037943X0200Y    R270 S2      
017P12V_NIC1_SS     VIA   -    M      A18X+037326Y+037943X0260Y    R270 S2      
017P12V_NIC1_SS           -    MD0100PA00X+037326Y+037943                       
327m2775            PU25  -8          A01X+129560Y+038373X0110Y0240R180 S1      
317m2775            VIA   -    M      A01X+129305Y+037909X0200Y    R270 S2      
017m2775            VIA   -    M      A18X+129305Y+037909X0260Y    R270 S2      
017m2775                  -    MD0100PA00X+129305Y+037909                       
327m2775            R4447 -1          A01X+129541Y+037663X0198Y0197R270 S1      
327m2775            R856  -2   M      A01X+129141Y+037683X0198Y0197R090 S1      
327P12V_NIC2_EN_R   PU26  -11         A01X+049541Y+053649X0110Y0240R090 S1      
317P12V_NIC2_EN_R   VIA   -    M      A01X+049182Y+053491X0200Y    R180 S2      
017P12V_NIC2_EN_R   VIA   -    M      A18X+049182Y+053491X0260Y    R180 S2      
017P12V_NIC2_EN_R         -    MD0100PA00X+049182Y+053491                       
327P12V_NIC2_EN_R   R4452 -2          A01X+048864Y+052773X0198Y0197     S1      
327P12V_NIC2_EN_R   C2857 -1   M      A01X+048864Y+053173X0198Y0197R180 S1      
327m2776            Q8    -5          A01X+167857Y+031929X0170Y0240R270 S1      
317m2776            VIA   -    MD0100PA00X+167781Y+032447X0200Y         S0      
317m2776            VIA   -    MD0100PA00X+180093Y+046161X0200Y    R270 S0      
327m2776            U6    -P21        A01X+137832Y+085664X0160Y         S1      
317m2776            VIA   -    MD0100PA00X+137990Y+085507X0180Y         S0      
317m2776            VIA   -    MD0100PA00X+139394Y+050786X0200Y         S0      
327m2776            R5969 -2          A01X+180093Y+045918X0198Y0197R090 S1      
317m2776            VIA   -    M      A01X+175250Y+037108X0200Y    R270 S2      
017m2776            VIA   -    M      A18X+175250Y+037108X0260Y    R270 S2      
017m2776                  -    MD0100PA00X+175250Y+037108                       
327m2776            R4455 -2          A01X+175250Y+037348X0198Y0197R270 S1      
317m2777            VIA   -    MD0100PA00X+134385Y+046161X0200Y    R270 S0      
317m2777            VIA   -    M      A01X+140308Y+046056X0200Y         S2      
017m2777            VIA   -    M      A18X+140308Y+046056X0260Y         S2      
017m2777                  -    MD0100PA00X+140308Y+046056                       
327m2777            U6    -L16        A01X+136257Y+086609X0160Y         S1      
317m2777            VIA   -    MD0100PA00X+136415Y+086766X0180Y         S0      
327m2777            R5967 -2          A01X+134385Y+045918X0198Y0197R090 S1      
327m2777            R4447 -2          A01X+129541Y+037348X0198Y0197R270 S1      
317m2777            VIA   -    MD0100PA00X+129541Y+037108X0200Y    R270 S0      
327m2777            Q6    -5          A01X+122149Y+031929X0170Y0240R270 S1      
317m2777            VIA   -    MD0100PA00X+122072Y+032447X0200Y         S0      
327P12V_NIC1        C861  -1          A01X+031755Y+043943X0400Y0500R270 S1      
327P12V_NIC1        J21   -B1         A01X+028842Y+043006X0140Y0480R090 S1      
327P12V_NIC1        J21   -B2         A01X+028842Y+043242X0140Y0480R090 S1      
327P12V_NIC1        J21   -B3         A01X+028842Y+043478X0140Y0480R090 S1      
327P12V_NIC1        J21   -B4         A01X+028842Y+043715X0140Y0480R090 S1      
327P12V_NIC1        J21   -B5         A01X+028842Y+043951X0140Y0480R090 S1      
327P12V_NIC1        J21   -B6         A01X+028842Y+044187X0140Y0480R090 S1      
327P12V_NIC1        R701  -1          A01X+035320Y+041208X0198Y0197R270 S1      
327P12V_NIC1        R693  -1          A01X+034670Y+042244X1150Y1380     S1      
327P12V_NIC1        C860  -1          A01X+031755Y+042694X0400Y0500R090 S1      
327P12V_NIC1        C863  -1          A18X+029003Y+044332X0120Y0150     S2      
327P12V_NIC1        VIA   -           A18X+034639Y+043173X0260Y         S2      
327P12V_NIC1        C866  -1          A18X+029003Y+043692X0120Y0150     S2      
327P12V_NIC1        C865  -1          A18X+029003Y+043352X0120Y0150     S2      
327P12V_NIC1        C864  -1          A18X+029003Y+043012X0120Y0150     S2      
327P12V_NIC1        C862  -1          A18X+029003Y+044012X0120Y0150     S2      
317P12V_NIC1        VIA   -    MD0100PA00X+029525Y+043567X0200Y         S0      
317P12V_NIC1        VIA   -    MD0100PA00X+029525Y+043047X0200Y         S0      
317P12V_NIC1        VIA   -    MD0100PA00X+029525Y+043307X0200Y         S0      
317P12V_NIC1        VIA   -    MD0100PA00X+029245Y+043307X0200Y         S0      
317P12V_NIC1        VIA   -    MD0100PA00X+029245Y+043047X0200Y         S0      
317P12V_NIC1        VIA   -    MD0100PA00X+029245Y+043567X0200Y         S0      
317P12V_NIC1        VIA   -    MD0100PA00X+029245Y+044087X0200Y         S0      
317P12V_NIC1        VIA   -    MD0100PA00X+029245Y+043827X0200Y         S0      
317P12V_NIC1        VIA   -    MD0100PA00X+029525Y+043827X0200Y         S0      
317P12V_NIC1        VIA   -    MD0100PA00X+029525Y+044087X0200Y         S0      
317P12V_NIC1        VIA   -    MD0100PA00X+035016Y+041211X0200Y    R270 S0      
317P12V_NIC1        VIA   -    MD0100PA00X+035416Y+041629X0200Y         S0      
317P12V_NIC1        VIA   -    MD0100PA00X+035416Y+041889X0200Y         S0      
317P12V_NIC1        VIA   -    MD0100PA00X+035416Y+042149X0200Y         S0      
327P12V_NIC1        VIA   -           A18X+034664Y+041900X0260Y         S2      
317P12V_NIC1        VIA   -    MD0100PA00X+033907Y+042209X0200Y         S0      
317P12V_NIC1        VIA   -    MD0100PA00X+033907Y+041949X0200Y         S0      
317P12V_NIC1        VIA   -    MD0100PA00X+033907Y+041689X0200Y         S0      
327P12V_NIC7        VIA   -           A18X+170494Y+044208X0260Y         S2      
327P12V_NIC7        VIA   -           A18X+169939Y+043383X0260Y         S2      
327P12V_NIC7        C950  -1          A01X+168881Y+043943X0400Y0500R270 S1      
327P12V_NIC7        J27   -B1         A01X+165968Y+043006X0140Y0480R090 S1      
327P12V_NIC7        J27   -B2         A01X+165968Y+043242X0140Y0480R090 S1      
327P12V_NIC7        J27   -B3         A01X+165968Y+043478X0140Y0480R090 S1      
327P12V_NIC7        J27   -B4         A01X+165968Y+043715X0140Y0480R090 S1      
327P12V_NIC7        J27   -B5         A01X+165968Y+043951X0140Y0480R090 S1      
327P12V_NIC7        J27   -B6         A01X+165968Y+044187X0140Y0480R090 S1      
327P12V_NIC7        R767  -1          A01X+172446Y+041208X0198Y0197R270 S1      
327P12V_NIC7        R758  -1          A01X+171796Y+042244X1150Y1380     S1      
327P12V_NIC7        C951  -1          A01X+168881Y+042694X0400Y0500R090 S1      
327P12V_NIC7        C955  -1          A18X+166129Y+044332X0120Y0150     S2      
327P12V_NIC7        VIA   -           A18X+171765Y+043173X0260Y         S2      
327P12V_NIC7        C956  -1          A18X+166129Y+043692X0120Y0150     S2      
327P12V_NIC7        C954  -1          A18X+166129Y+043352X0120Y0150     S2      
327P12V_NIC7        C953  -1          A18X+166129Y+043012X0120Y0150     S2      
327P12V_NIC7        C952  -1          A18X+166129Y+044012X0120Y0150     S2      
317P12V_NIC7        VIA   -    MD0100PA00X+166371Y+043567X0200Y         S0      
317P12V_NIC7        VIA   -    MD0100PA00X+166371Y+043047X0200Y         S0      
317P12V_NIC7        VIA   -    MD0100PA00X+166371Y+043307X0200Y         S0      
317P12V_NIC7        VIA   -    MD0100PA00X+166651Y+043827X0200Y         S0      
317P12V_NIC7        VIA   -    MD0100PA00X+166651Y+044087X0200Y         S0      
317P12V_NIC7        VIA   -    MD0100PA00X+166651Y+043567X0200Y         S0      
317P12V_NIC7        VIA   -    MD0100PA00X+166651Y+043047X0200Y         S0      
317P12V_NIC7        VIA   -    MD0100PA00X+166651Y+043307X0200Y         S0      
317P12V_NIC7        VIA   -    MD0100PA00X+166371Y+043827X0200Y         S0      
317P12V_NIC7        VIA   -    MD0100PA00X+166371Y+044087X0200Y         S0      
327P12V_NIC7        VIA   -           A18X+171790Y+041900X0260Y         S2      
317P12V_NIC7        VIA   -    MD0100PA00X+172142Y+041211X0200Y    R270 S0      
317P12V_NIC7        VIA   -    MD0100PA00X+172542Y+042149X0200Y         S0      
317P12V_NIC7        VIA   -    MD0100PA00X+172542Y+041889X0200Y         S0      
317P12V_NIC7        VIA   -    MD0100PA00X+172542Y+041629X0200Y         S0      
317m2778            VIA   -    MD0100PA01X+072761Y+140840X0180Y         S0      
317m2778            J5    -W4   D0122PA01X+065555Y+146807X0282Y    R180 S3      
327m2778            C2535 -2          A01X+072771Y+140350X0120Y0150R090 S1      
317m2779            J5    -R8   D0122PA01X+069020Y+149366X0282Y    R180 S3      
317m2779            VIA   -    MD0080PA01X+077795Y+119862X0160Y    R270 S0      
327m2779            PEX1  -T48        A01X+077795Y+119862X0180Y         S1      
317m2780            VIA   -    MD0100PA01X+070313Y+140850X0180Y         S0      
317m2780            J5    -X1   D0122PA01X+062957Y+146374X0282Y    R180 S3      
327m2780            C2529 -2          A01X+070323Y+140359X0120Y0150R090 S1      
317m2781            J5    -S7   D0122PA01X+068154Y+148933X0282Y    R180 S3      
317m2781            VIA   -    MD0080PA01X+077047Y+120236X0160Y    R270 S0      
327m2781            PEX1  -R46        A01X+077047Y+120236X0180Y         S1      
317m2782            J5    -R4   D0122PA01X+065555Y+149366X0282Y    R180 S3      
317m2782            VIA   -    MD0080PA01X+077795Y+121358X0160Y    R270 S0      
327m2782            PEX1  -M48        A01X+077795Y+121358X0180Y         S1      
317m2783            J5    -E8   D0122PA01X+069020Y+160114X0282Y    R180 S3      
317m2783            VIA   -    MD0080PA01X+077421Y+125472X0160Y         S0      
327m2783            PEX1  -A47        A01X+077421Y+125472X0180Y         S1      
317m2784            VIA   -    MD0100PA01X+071197Y+138430X0180Y         S0      
327m2784            C2530 -2          A01X+071187Y+137939X0120Y0150R090 S1      
317m2784            J5    -X2   D0122PA01X+063823Y+146295X0282Y    R180 S3      
317m2785            J5    -F3   D0122PA01X+064689Y+159681X0282Y    R180 S3      
317m2785            VIA   -    MD0080PA01X+075551Y+124724X0160Y         S0      
327m2785            PEX1  -C42        A01X+075551Y+124724X0180Y         S1      
317m2786            VIA   -    MD0100PA01X+069089Y+138430X0180Y         S0      
317m2786            J5    -L7   D0122PA01X+068154Y+156610X0282Y    R180 S3      
327m2786            C2525 -2          A01X+069099Y+137939X0120Y0150R090 S1      
317m2787            VIA   -    MD0100PA01X+066641Y+138430X0180Y         S0      
317m2787            J5    -K4   D0122PA01X+065555Y+157043X0282Y    R180 S3      
327m2787            C2519 -2          A01X+066651Y+137939X0120Y0150R090 S1      
317m2788            VIA   -    MD0100PA01X+067525Y+140850X0180Y         S0      
317m2788            J5    -L6   D0122PA01X+067287Y+156532X0282Y    R180 S3      
327m2788            C2522 -2          A01X+067515Y+140359X0120Y0150R090 S1      
317m2789            J5    -R3   D0122PA01X+064689Y+149445X0282Y    R180 S3      
317m2789            VIA   -    MD0080PA01X+077421Y+121732X0160Y    R270 S0      
327m2789            PEX1  -L47        A01X+077421Y+121732X0180Y         S1      
317m2790            VIA   -    MD0100PA01X+072761Y+136010X0180Y         S0      
317m2790            J5    -X3   D0122PA01X+064689Y+146374X0282Y    R180 S3      
327m2790            C2533 -2          A01X+072771Y+135519X0120Y0150R090 S1      
317m2791            VIA   -    MD0100PA01X+073645Y+138430X0180Y         S0      
317m2791            J5    -Y5   D0122PA01X+066421Y+145862X0282Y    R180 S3      
327m2791            C2536 -2          A01X+073635Y+137939X0120Y0150R090 S1      
317m2792            J5    -G1   D0122PA01X+062957Y+159169X0282Y    R180 S3      
317m2792            VIA   -    MD0080PA01X+074803Y+124350X0160Y         S0      
327m2792            PEX1  -D40        A01X+074803Y+124350X0180Y         S1      
317m2793            VIA   -    MD0100PA01X+076093Y+138430X0180Y         S0      
317m2793            J5    -Y7   D0122PA01X+068154Y+145862X0282Y    R180 S3      
327m2793            C2540 -2          A01X+076083Y+137939X0120Y0150R090 S1      
317m2794            J5    -F4   D0122PA01X+065555Y+159602X0282Y    R180 S3      
317m2794            VIA   -    MD0080PA01X+075925Y+125098X0160Y         S0      
327m2794            PEX1  -B43        A01X+075925Y+125098X0180Y         S1      
317m2795            VIA   -    MD0100PA01X+065417Y+140850X0180Y         S0      
317m2795            J5    -L3   D0122PA01X+064689Y+156610X0282Y    R180 S3      
327m2795            C2517 -2          A01X+065427Y+140359X0120Y0150R090 S1      
317m2796            J5    -E6   D0122PA01X+067287Y+160114X0282Y    R180 S3      
317m2796            VIA   -    MD0080PA01X+076673Y+125472X0160Y         S0      
327m2796            PEX1  -A45        A01X+076673Y+125472X0180Y         S1      
317m2797            J5    -F8   D0122PA01X+069020Y+159602X0282Y    R180 S3      
317m2797            VIA   -    MD0080PA01X+077421Y+125098X0160Y         S0      
327m2797            PEX1  -B47        A01X+077421Y+125098X0180Y         S1      
317m2798            J5    -F1   D0122PA01X+062957Y+159681X0282Y    R180 S3      
317m2798            VIA   -    MD0080PA01X+074803Y+124724X0160Y         S0      
327m2798            PEX1  -C40        A01X+074803Y+124724X0180Y         S1      
317m2799            J5    -W8   D0122PA01X+069020Y+146807X0282Y    R180 S3      
327m2799            C2543 -2          A01X+077667Y+135519X0120Y0150R090 S1      
317m2799            VIA   -    MD0100PA01X+077657Y+136010X0180Y         S0      
317m2800            J5    -X8   D0122PA01X+069020Y+146295X0282Y    R180 S3      
327m2800            C2542 -2          A01X+077307Y+135519X0120Y0150R090 S1      
317m2800            VIA   -    MD0100PA01X+077317Y+136010X0180Y         S0      
317m2801            J5    -R7   D0122PA01X+068154Y+149445X0282Y    R180 S3      
317m2801            VIA   -    MD0080PA01X+077421Y+120236X0160Y    R270 S0      
327m2801            PEX1  -R47        A01X+077421Y+120236X0180Y         S1      
317m2802            J5    -S3   D0122PA01X+064689Y+148933X0282Y    R180 S3      
317m2802            VIA   -    MD0080PA01X+077047Y+121732X0160Y    R270 S0      
327m2802            PEX1  -L46        A01X+077047Y+121732X0180Y         S1      
317m2803            VIA   -    MD0100PA01X+066301Y+138430X0180Y         S0      
317m2803            J5    -L4   D0122PA01X+065555Y+156532X0282Y    R180 S3      
327m2803            C2518 -2          A01X+066291Y+137939X0120Y0150R090 S1      
317m2804            VIA   -    MD0100PA01X+065077Y+140850X0180Y         S0      
317m2804            J5    -M3   D0122PA01X+064689Y+156098X0282Y    R180 S3      
327m2804            C2516 -2          A01X+065067Y+140359X0120Y0150R090 S1      
317m2805            J5    -F7   D0122PA01X+068154Y+159681X0282Y    R180 S3      
317m2805            VIA   -    MD0080PA01X+077047Y+124724X0160Y         S0      
327m2805            PEX1  -C46        A01X+077047Y+124724X0180Y         S1      
317m2806            VIA   -    MD0100PA01X+065077Y+136010X0180Y         S0      
317m2806            J5    -L2   D0122PA01X+063823Y+156532X0282Y    R180 S3      
327m2806            C2514 -2          A01X+065067Y+135519X0120Y0150R090 S1      
317m2807            VIA   -    MD0100PA01X+067525Y+136010X0180Y         S0      
317m2807            J5    -M5   D0122PA01X+066421Y+156098X0282Y    R180 S3      
327m2807            C2520 -2          A01X+067515Y+135519X0120Y0150R090 S1      
317m2808            VIA   -    MD0100PA01X+071537Y+138430X0180Y         S0      
317m2808            J5    -W2   D0122PA01X+063823Y+146807X0282Y    R180 S3      
327m2808            C2531 -2          A01X+071547Y+137939X0120Y0150R090 S1      
317m2809            J5    -Q6   D0122PA01X+067287Y+149878X0282Y    R180 S3      
317m2809            VIA   -    MD0080PA01X+078169Y+120610X0160Y    R270 S0      
327m2809            PEX1  -P49        A01X+078169Y+120610X0180Y         S1      
317m2810            J5    -Q2   D0122PA01X+063823Y+149878X0282Y    R180 S3      
317m2810            VIA   -    MD0080PA01X+078169Y+122106X0160Y    R090 S0      
327m2810            PEX1  -K49        A01X+078169Y+122106X0180Y         S1      
317m2811            VIA   -    MD0100PA01X+064193Y+138430X0180Y         S0      
317m2811            J5    -L1   D0122PA01X+062957Y+156610X0282Y    R180 S3      
327m2811            C2513 -2          A01X+064203Y+137939X0120Y0150R090 S1      
317m2812            J5    -E4   D0122PA01X+065555Y+160114X0282Y    R180 S3      
317m2812            VIA   -    MD0080PA01X+075925Y+125472X0160Y         S0      
327m2812            PEX1  -A43        A01X+075925Y+125472X0180Y         S1      
317m2813            J5    -R1   D0122PA01X+062957Y+149445X0282Y    R180 S3      
317m2813            VIA   -    MD0080PA01X+078169Y+124724X0160Y    R270 S0      
327m2813            PEX1  -C49        A01X+078169Y+124724X0180Y         S1      
317m2814            VIA   -    MD0100PA01X+063853Y+138430X0180Y         S0      
317m2814            J5    -M1   D0122PA01X+062957Y+156098X0282Y    R180 S3      
327m2814            C2512 -2          A01X+063843Y+137939X0120Y0150R090 S1      
317m2815            J5    -E2   D0122PA01X+063823Y+160114X0282Y    R180 S3      
317m2815            VIA   -    MD0080PA01X+075177Y+125472X0160Y         S0      
327m2815            PEX1  -A41        A01X+075177Y+125472X0180Y         S1      
317m2816            VIA   -    MD0100PA01X+073985Y+138430X0180Y         S0      
317m2816            J5    -X5   D0122PA01X+066421Y+146374X0282Y    R180 S3      
327m2816            C2537 -2          A01X+073995Y+137939X0120Y0150R090 S1      
317m2817            J5    -R2   D0122PA01X+063823Y+149366X0282Y    R180 S3      
317m2817            VIA   -    MD0080PA01X+077795Y+122106X0160Y    R090 S0      
327m2817            PEX1  -K48        A01X+077795Y+122106X0180Y         S1      
317m2818            VIA   -    MD0100PA01X+072421Y+136010X0180Y         S0      
317m2818            J5    -Y3   D0122PA01X+064689Y+145862X0282Y    R180 S3      
327m2818            C2532 -2          A01X+072411Y+135519X0120Y0150R090 S1      
317m2819            VIA   -    MD0100PA01X+065417Y+136010X0180Y         S0      
317m2819            J5    -K2   D0122PA01X+063823Y+157043X0282Y    R180 S3      
327m2819            C2515 -2          A01X+065427Y+135519X0120Y0150R090 S1      
317m2820            J5    -R5   D0122PA01X+066421Y+149445X0282Y    R180 S3      
317m2820            VIA   -    MD0080PA01X+077421Y+120984X0160Y    R270 S0      
327m2820            PEX1  -N47        A01X+077421Y+120984X0180Y         S1      
317m2821            J5    -F2   D0122PA01X+063823Y+159602X0282Y    R180 S3      
317m2821            VIA   -    MD0080PA01X+075177Y+125098X0160Y         S0      
327m2821            PEX1  -B41        A01X+075177Y+125098X0180Y         S1      
317m2822            J5    -Q4   D0122PA01X+065555Y+149878X0282Y    R180 S3      
317m2822            VIA   -    MD0080PA01X+078169Y+121358X0160Y    R270 S0      
327m2822            PEX1  -M49        A01X+078169Y+121358X0180Y         S1      
317m2823            VIA   -    MD0100PA01X+067865Y+136010X0180Y         S0      
317m2823            J5    -L5   D0122PA01X+066421Y+156610X0282Y    R180 S3      
327m2823            C2521 -2          A01X+067875Y+135519X0120Y0150R090 S1      
317m2824            J5    -S5   D0122PA01X+066421Y+148933X0282Y    R180 S3      
317m2824            VIA   -    MD0080PA01X+077047Y+120984X0160Y    R270 S0      
327m2824            PEX1  -N46        A01X+077047Y+120984X0180Y         S1      
317m2825            VIA   -    MD0100PA01X+068749Y+138430X0180Y         S0      
317m2825            J5    -M7   D0122PA01X+068154Y+156098X0282Y    R180 S3      
327m2825            C2524 -2          A01X+068739Y+137939X0120Y0150R090 S1      
317m2826            VIA   -    MD0100PA01X+074869Y+136010X0180Y         S0      
317m2826            J5    -X6   D0122PA01X+067287Y+146295X0282Y    R180 S3      
327m2826            C2538 -2          A01X+074859Y+135519X0120Y0150R090 S1      
317m2827            VIA   -    MD0100PA01X+067865Y+140850X0180Y         S0      
317m2827            J5    -K6   D0122PA01X+067287Y+157043X0282Y    R180 S3      
327m2827            C2523 -2          A01X+067875Y+140359X0120Y0150R090 S1      
317m2828            J5    -G7   D0122PA01X+068154Y+159169X0282Y    R180 S3      
317m2828            VIA   -    MD0080PA01X+077047Y+124350X0160Y         S0      
327m2828            PEX1  -D46        A01X+077047Y+124350X0180Y         S1      
317m2829            J5    -Q8   D0122PA01X+069020Y+149878X0282Y    R180 S3      
317m2829            VIA   -    MD0080PA01X+078169Y+119862X0160Y    R270 S0      
327m2829            PEX1  -T49        A01X+078169Y+119862X0180Y         S1      
317m2830            VIA   -    MD0100PA01X+069973Y+136010X0180Y         S0      
317m2830            J5    -L8   D0122PA01X+069020Y+156532X0282Y    R180 S3      
327m2830            C2526 -2          A01X+069963Y+135519X0120Y0150R090 S1      
317m2831            VIA   -    MD0100PA01X+072421Y+140840X0180Y         S0      
327m2831            C2534 -2          A01X+072411Y+140350X0120Y0150R090 S1      
317m2831            J5    -X4   D0122PA01X+065555Y+146295X0282Y    R180 S3      
317m2832            J5    -F5   D0122PA01X+066421Y+159681X0282Y    R180 S3      
317m2832            VIA   -    MD0080PA01X+076299Y+124724X0160Y         S0      
327m2832            PEX1  -C44        A01X+076299Y+124724X0180Y         S1      
317m2833            J5    -S1   D0122PA01X+062957Y+148933X0282Y    R180 S3      
317m2833            VIA   -    MD0080PA01X+077795Y+124724X0160Y    R270 S0      
327m2833            PEX1  -C48        A01X+077795Y+124724X0180Y         S1      
317m2834            J5    -G5   D0122PA01X+066421Y+159169X0282Y    R180 S3      
317m2834            VIA   -    MD0080PA01X+076299Y+124350X0160Y         S0      
327m2834            PEX1  -D44        A01X+076299Y+124350X0180Y         S1      
317m2835            J5    -R6   D0122PA01X+067287Y+149366X0282Y    R180 S3      
317m2835            VIA   -    MD0080PA01X+077795Y+120610X0160Y         S0      
327m2835            PEX1  -P48        A01X+077795Y+120610X0180Y         S1      
317m2836            J5    -G3   D0122PA01X+064689Y+159169X0282Y    R180 S3      
317m2836            VIA   -    MD0080PA01X+075551Y+124350X0160Y         S0      
327m2836            PEX1  -D42        A01X+075551Y+124350X0180Y         S1      
317m2837            VIA   -    MD0100PA01X+069973Y+140850X0180Y         S0      
317m2837            J5    -Y1   D0122PA01X+062957Y+145862X0282Y    R180 S3      
327m2837            C2528 -2          A01X+069963Y+140359X0120Y0150R090 S1      
317m2838            J5    -F6   D0122PA01X+067287Y+159602X0282Y    R180 S3      
317m2838            VIA   -    MD0080PA01X+076673Y+125098X0160Y         S0      
327m2838            PEX1  -B45        A01X+076673Y+125098X0180Y         S1      
317m2839            VIA   -    MD0100PA01X+070313Y+136010X0180Y         S0      
317m2839            J5    -K8   D0122PA01X+069020Y+157043X0282Y    R180 S3      
327m2839            C2527 -2          A01X+070323Y+135519X0120Y0150R090 S1      
317m2840            VIA   -    MD0100PA01X+076433Y+138430X0180Y         S0      
317m2840            J5    -X7   D0122PA01X+068154Y+146374X0282Y    R180 S3      
327m2840            C2541 -2          A01X+076443Y+137939X0120Y0150R090 S1      
317m2841            VIA   -    MD0100PA01X+075209Y+136010X0180Y         S0      
317m2841            J5    -W6   D0122PA01X+067287Y+146807X0282Y    R180 S3      
327m2841            C2539 -2          A01X+075219Y+135519X0120Y0150R090 S1      
317m2842            VIA   -    MD0080PA01X+075551Y+122480X0160Y    R270 S0      
317m2842            VIA   -    MD0100PA01X+065077Y+139658X0180Y         S0      
327m2842            PEX1  -J42        A01X+075551Y+122480X0180Y         S1      
327m2842            C2516 -1          A01X+065067Y+140149X0120Y0150R090 S1      
327m2843            C2539 -1          A01X+075219Y+135309X0120Y0150R090 S1      
317m2843            VIA   -    MD0100PA01X+075209Y+134819X0180Y         S0      
317m2843            VIA   -    MD0080PA01X+075551Y+120610X0160Y    R270 S0      
327m2843            PEX1  -P42        A01X+075551Y+120610X0180Y         S1      
327m2844            C2536 -1          A01X+073635Y+137729X0120Y0150R090 S1      
317m2844            VIA   -    MD0100PA01X+073645Y+137238X0180Y         S0      
317m2844            VIA   -    MD0080PA01X+075925Y+120984X0160Y    R270 S0      
327m2844            PEX1  -N43        A01X+075925Y+120984X0180Y         S1      
327m2845            C2529 -1          A01X+070323Y+140149X0120Y0150R090 S1      
317m2845            VIA   -    MD0100PA01X+070313Y+139658X0180Y         S0      
317m2845            VIA   -    MD0080PA01X+078169Y+123976X0160Y         S0      
327m2845            PEX1  -E49        A01X+078169Y+123976X0180Y         S1      
317m2846            VIA   -    MD0100PA01X+077317Y+134819X0180Y         S0      
327m2846            C2542 -1          A01X+077307Y+135309X0120Y0150R090 S1      
317m2846            VIA   -    MD0080PA01X+075177Y+119862X0160Y    R270 S0      
327m2846            PEX1  -T41        A01X+075177Y+119862X0180Y         S1      
317m2847            VIA   -    MD0080PA01X+075925Y+123602X0160Y    R270 S0      
317m2847            VIA   -    MD0100PA01X+066641Y+137238X0180Y         S0      
327m2847            PEX1  -F43        A01X+075925Y+123602X0180Y         S1      
327m2847            C2519 -1          A01X+066651Y+137729X0120Y0150R090 S1      
327m2848            C2532 -1          A01X+072411Y+135309X0120Y0150R090 S1      
317m2848            VIA   -    MD0100PA01X+072421Y+134819X0180Y         S0      
317m2848            VIA   -    MD0080PA01X+075925Y+121732X0160Y    R270 S0      
327m2848            PEX1  -L43        A01X+075925Y+121732X0180Y         S1      
317m2849            VIA   -    MD0080PA01X+076299Y+122480X0160Y    R270 S0      
317m2849            VIA   -    MD0100PA01X+067525Y+134819X0180Y         S0      
327m2849            PEX1  -J44        A01X+076299Y+122480X0180Y         S1      
327m2849            C2520 -1          A01X+067515Y+135309X0120Y0150R090 S1      
327m2850            C2540 -1          A01X+076083Y+137729X0120Y0150R090 S1      
317m2850            VIA   -    MD0100PA01X+076093Y+137238X0180Y         S0      
317m2850            VIA   -    MD0080PA01X+075925Y+120236X0160Y    R270 S0      
327m2850            PEX1  -R43        A01X+075925Y+120236X0180Y         S1      
317m2851            VIA   -    MD0080PA01X+074803Y+122854X0160Y    R270 S0      
317m2851            VIA   -    MD0100PA01X+064193Y+137238X0180Y         S0      
327m2851            PEX1  -H40        A01X+074803Y+122854X0180Y         S1      
327m2851            C2513 -1          A01X+064203Y+137729X0120Y0150R090 S1      
317m2852            VIA   -    MD0080PA01X+075925Y+123228X0160Y    R270 S0      
317m2852            VIA   -    MD0100PA01X+066301Y+137238X0180Y         S0      
327m2852            PEX1  -G43        A01X+075925Y+123228X0180Y         S1      
327m2852            C2518 -1          A01X+066291Y+137729X0120Y0150R090 S1      
317m2853            VIA   -    MD0080PA01X+076673Y+123602X0160Y    R270 S0      
317m2853            VIA   -    MD0100PA01X+067865Y+139658X0180Y         S0      
327m2853            PEX1  -F45        A01X+076673Y+123602X0180Y         S1      
327m2853            C2523 -1          A01X+067875Y+140149X0120Y0150R090 S1      
317m2854            VIA   -    MD0080PA01X+077421Y+123602X0160Y    R270 S0      
317m2854            VIA   -    MD0100PA01X+070313Y+134819X0180Y         S0      
327m2854            PEX1  -F47        A01X+077421Y+123602X0180Y         S1      
327m2854            C2527 -1          A01X+070323Y+135309X0120Y0150R090 S1      
327m2855            C2538 -1          A01X+074859Y+135309X0120Y0150R090 S1      
317m2855            VIA   -    MD0100PA01X+074869Y+134819X0180Y         S0      
317m2855            VIA   -    MD0080PA01X+075177Y+120610X0160Y    R270 S0      
327m2855            PEX1  -P41        A01X+075177Y+120610X0180Y         S1      
327m2856            C2528 -1          A01X+069963Y+140149X0120Y0150R090 S1      
317m2856            VIA   -    MD0100PA01X+069973Y+139658X0180Y         S0      
317m2856            VIA   -    MD0080PA01X+077795Y+123976X0160Y         S0      
327m2856            PEX1  -E48        A01X+077795Y+123976X0180Y         S1      
317m2857            VIA   -    MD0080PA01X+076673Y+123228X0160Y    R270 S0      
317m2857            VIA   -    MD0100PA01X+067525Y+139658X0180Y         S0      
327m2857            PEX1  -G45        A01X+076673Y+123228X0180Y         S1      
327m2857            C2522 -1          A01X+067515Y+140149X0120Y0150R090 S1      
317m2858            VIA   -    MD0080PA01X+075177Y+123228X0160Y    R270 S0      
317m2858            VIA   -    MD0100PA01X+065077Y+134819X0180Y         S0      
327m2858            PEX1  -G41        A01X+075177Y+123228X0180Y         S1      
327m2858            C2514 -1          A01X+065067Y+135309X0120Y0150R090 S1      
317m2859            VIA   -    MD0080PA01X+076299Y+122854X0160Y    R270 S0      
317m2859            VIA   -    MD0100PA01X+067865Y+134819X0180Y         S0      
327m2859            PEX1  -H44        A01X+076299Y+122854X0180Y         S1      
327m2859            C2521 -1          A01X+067875Y+135309X0120Y0150R090 S1      
317m2860            VIA   -    MD0080PA01X+075177Y+123602X0160Y    R270 S0      
317m2860            VIA   -    MD0100PA01X+065417Y+134819X0180Y         S0      
327m2860            PEX1  -F41        A01X+075177Y+123602X0180Y         S1      
327m2860            C2515 -1          A01X+065427Y+135309X0120Y0150R090 S1      
317m2861            VIA   -    MD0080PA01X+077421Y+123228X0160Y    R270 S0      
317m2861            VIA   -    MD0100PA01X+069973Y+134819X0180Y         S0      
327m2861            PEX1  -G47        A01X+077421Y+123228X0180Y         S1      
327m2861            C2526 -1          A01X+069963Y+135309X0120Y0150R090 S1      
327m2862            C2530 -1          A01X+071187Y+137729X0120Y0150R090 S1      
317m2862            VIA   -    MD0100PA01X+071197Y+137238X0180Y         S0      
317m2862            VIA   -    MD0080PA01X+077795Y+122854X0160Y    R270 S0      
327m2862            PEX1  -H48        A01X+077795Y+122854X0180Y         S1      
317m2863            VIA   -    MD0100PA01X+077657Y+134819X0180Y         S0      
327m2863            C2543 -1          A01X+077667Y+135309X0120Y0150R090 S1      
317m2863            VIA   -    MD0080PA01X+075551Y+119862X0160Y    R270 S0      
327m2863            PEX1  -T42        A01X+075551Y+119862X0180Y         S1      
327m2864            C2535 -1          A01X+072771Y+140140X0120Y0150R090 S1      
317m2864            VIA   -    MD0100PA01X+072761Y+139649X0180Y         S0      
317m2864            VIA   -    MD0080PA01X+075551Y+121358X0160Y    R270 S0      
327m2864            PEX1  -M42        A01X+075551Y+121358X0180Y         S1      
327m2865            C2537 -1          A01X+073995Y+137729X0120Y0150R090 S1      
317m2865            VIA   -    MD0100PA01X+073985Y+137238X0180Y         S0      
317m2865            VIA   -    MD0080PA01X+076299Y+120984X0160Y    R270 S0      
327m2865            PEX1  -N44        A01X+076299Y+120984X0180Y         S1      
317m2866            VIA   -    MD0080PA01X+077047Y+122480X0160Y    R270 S0      
317m2866            VIA   -    MD0100PA01X+068749Y+137238X0180Y         S0      
327m2866            PEX1  -J46        A01X+077047Y+122480X0180Y         S1      
327m2866            C2524 -1          A01X+068739Y+137729X0120Y0150R090 S1      
317m2867            VIA   -    MD0080PA01X+075551Y+122854X0160Y    R270 S0      
317m2867            VIA   -    MD0100PA01X+065417Y+139658X0180Y         S0      
327m2867            PEX1  -H42        A01X+075551Y+122854X0180Y         S1      
327m2867            C2517 -1          A01X+065427Y+140149X0120Y0150R090 S1      
317m2868            VIA   -    MD0080PA01X+074803Y+122480X0160Y    R270 S0      
317m2868            VIA   -    MD0100PA01X+063853Y+137238X0180Y         S0      
327m2868            PEX1  -J40        A01X+074803Y+122480X0180Y         S1      
327m2868            C2512 -1          A01X+063843Y+137729X0120Y0150R090 S1      
327m2869            C2534 -1          A01X+072411Y+140140X0120Y0150R090 S1      
317m2869            VIA   -    MD0100PA01X+072421Y+139649X0180Y         S0      
317m2869            VIA   -    MD0080PA01X+075177Y+121358X0160Y    R270 S0      
327m2869            PEX1  -M41        A01X+075177Y+121358X0180Y         S1      
327m2870            C2533 -1          A01X+072771Y+135309X0120Y0150R090 S1      
317m2870            VIA   -    MD0100PA01X+072761Y+134819X0180Y         S0      
317m2870            VIA   -    MD0080PA01X+076299Y+121732X0160Y    R270 S0      
327m2870            PEX1  -L44        A01X+076299Y+121732X0180Y         S1      
327m2871            C2531 -1          A01X+071547Y+137729X0120Y0150R090 S1      
317m2871            VIA   -    MD0100PA01X+071537Y+137238X0180Y         S0      
317m2871            VIA   -    MD0080PA01X+078169Y+122854X0160Y    R270 S0      
327m2871            PEX1  -H49        A01X+078169Y+122854X0180Y         S1      
327m2872            C2541 -1          A01X+076443Y+137729X0120Y0150R090 S1      
317m2872            VIA   -    MD0100PA01X+076433Y+137238X0180Y         S0      
317m2872            VIA   -    MD0080PA01X+076299Y+120236X0160Y    R270 S0      
327m2872            PEX1  -R44        A01X+076299Y+120236X0180Y         S1      
317m2873            VIA   -    MD0080PA01X+077047Y+122854X0160Y    R270 S0      
317m2873            VIA   -    MD0100PA01X+069089Y+137238X0180Y         S0      
327m2873            PEX1  -H46        A01X+077047Y+122854X0180Y         S1      
327m2873            C2525 -1          A01X+069099Y+137729X0120Y0150R090 S1      
317m2874            VIA   -    M      A01X+054694Y+087139X0200Y         S2      
017m2874            VIA   -    M      A18X+054694Y+087139X0260Y         S2      
017m2874                  -    MD0100PA00X+054694Y+087139                       
327m2874            R3461 -1          A18X+055190Y+087139X0198Y0197R090 S2      
317m2874            VIA   -    MD0100PA00X+061763Y+104928X0200Y         S0      
327m2874            R3453 -1          A18X+061339Y+113533X0198Y0197R270 S2      
327m2875            VIA   -    M      A18X+054300Y+087486X0260Y         S2      
327m2875            R3464 -1          A18X+053598Y+087486X0198Y0197     S2      
327m2875            U66   -9          A18X+054347Y+088323X0140Y0610R180 S2      
327m2876            VIA   -    M      A18X+051604Y+088016X0260Y         S2      
327m2876            R3465 -1          A18X+051604Y+087418X0198Y0197R090 S2      
327m2876            U66   -7          A18X+054097Y+090483X0140Y0610R180 S2      
327m2877            VIA   -    M      A18X+055334Y+090540X0260Y         S2      
327m2877            U66   -4          A18X+053347Y+090483X0140Y0610R180 S2      
327m2877            R3462 -1          A18X+055229Y+090058X0198Y0197R090 S2      
317m2878            VIA   -    M      A01X+053108Y+091319X0200Y         S2      
017m2878            VIA   -    M      A18X+053108Y+091319X0260Y         S2      
017m2878                  -    MD0100PA00X+053108Y+091319                       
327m2878            U66   -2          A18X+052847Y+090483X0140Y0610R180 S2      
327m2878            R3451 -1          A18X+061713Y+113533X0198Y0197R270 S2      
317m2878            VIA   -    MD0100PA00X+061296Y+106294X0200Y         S0      
317m2879            VIA   -    MD0100PA00X+053097Y+088828X0200Y         S0      
327m2879            R3455 -1          A18X+061368Y+116910X0198Y0197R180 S2      
317m2879            VIA   -    M      A01X+060643Y+104190X0200Y         S2      
017m2879            VIA   -    M      A18X+060643Y+104190X0260Y         S2      
017m2879                  -    MD0100PA00X+060643Y+104190                       
327m2879            U66   -14         A18X+053097Y+088323X0140Y0610R180 S2      
317m2880            VIA   -    MD0100PA00X+053847Y+088803X0200Y         S0      
327m2880            R3456 -1          A18X+061368Y+116456X0198Y0197R180 S2      
317m2880            VIA   -    M      A01X+060799Y+103692X0200Y         S2      
017m2880            VIA   -    M      A18X+060799Y+103692X0260Y         S2      
017m2880                  -    MD0100PA00X+060799Y+103692                       
327m2880            U66   -11         A18X+053847Y+088323X0140Y0610R180 S2      
327m2881            VIA   -    M      A18X+054784Y+089297X0260Y         S2      
327m2881            U66   -12         A18X+053597Y+088323X0140Y0610R180 S2      
327m2881            R3460 -2          A18X+054833Y+089742X0198Y0197R090 S2      
317SPI_PEX1_CLK_R   VIA   -    MD0100PA00X+053314Y+089791X0200Y         S0      
327SPI_PEX1_CLK_R   U66   -5          A18X+053597Y+090483X0140Y0610R180 S2      
317SPI_PEX1_CLK_R   VIA   -    M      A01X+061078Y+105104X0200Y         S2      
017SPI_PEX1_CLK_R   VIA   -    M      A18X+061078Y+105104X0260Y         S2      
017SPI_PEX1_CLK_R         -    MD0100PA00X+061078Y+105104                       
327SPI_PEX1_CLK_R   R3452 -1          A18X+061322Y+114853X0198Y0197R180 S2      
317m2882            VIA   -    M      A01X+051690Y+091025X0200Y         S2      
017m2882            VIA   -    M      A18X+051690Y+091025X0260Y         S2      
017m2882                  -    MD0100PA00X+051690Y+091025                       
327m2882            R3463 -1          A18X+051690Y+090550X0198Y0197     S2      
327m2882            R3454 -1          A18X+061346Y+116065X0198Y0197R180 S2      
317m2882            VIA   -    MD0100PA00X+060368Y+105346X0200Y         S0      
317m2883            VIA   -    M      A01X+142490Y+093678X0200Y         S2      
017m2883            VIA   -    M      A18X+142490Y+093678X0260Y         S2      
017m2883                  -    MD0100PA00X+142490Y+093678                       
327m2883            R3501 -1          A18X+143108Y+090550X0198Y0197     S2      
317m2883            VIA   -    MD0100PA00X+151786Y+105346X0200Y         S0      
327m2883            R3492 -1          A18X+152763Y+116065X0198Y0197R180 S2      
327m2884            U68   -2          A18X+144264Y+090483X0140Y0610R180 S2      
317m2884            VIA   -    M      A01X+142991Y+093700X0200Y         S2      
017m2884            VIA   -    M      A18X+142991Y+093700X0260Y         S2      
017m2884                  -    MD0100PA00X+142991Y+093700                       
327m2884            R3491 -1          A18X+153130Y+113533X0198Y0197R270 S2      
317m2884            VIA   -    MD0100PA00X+153155Y+106277X0200Y         S0      
317m2885            VIA   -    MD0100PA00X+145264Y+088803X0200Y         S0      
327m2885            U68   -11         A18X+145264Y+088323X0140Y0610R180 S2      
327m2885            R3494 -1          A18X+152785Y+116456X0198Y0197R180 S2      
317m2885            VIA   -    M      A01X+152210Y+103552X0200Y         S2      
017m2885            VIA   -    M      A18X+152210Y+103552X0260Y         S2      
017m2885                  -    MD0100PA00X+152210Y+103552                       
327m2886            VIA   -    M      A18X+146239Y+089282X0260Y         S2      
327m2886            U68   -12         A18X+145014Y+088323X0140Y0610R180 S2      
327m2886            R3499 -2          A18X+146250Y+089742X0198Y0197R090 S2      
327m2887            VIA   -    M      A18X+143022Y+088016X0260Y         S2      
327m2887            R3503 -1          A18X+143022Y+087418X0198Y0197R090 S2      
327m2887            U68   -7          A18X+145514Y+090483X0140Y0610R180 S2      
327m2888            VIA   -    M      A18X+146751Y+090540X0260Y         S2      
327m2888            U68   -4          A18X+144764Y+090483X0140Y0610R180 S2      
327m2888            R3500 -1          A18X+146646Y+090058X0198Y0197R090 S2      
317m2889            VIA   -    M      A01X+146111Y+087139X0200Y         S2      
017m2889            VIA   -    M      A18X+146111Y+087139X0260Y         S2      
017m2889                  -    MD0100PA00X+146111Y+087139                       
327m2889            R3498 -1          A18X+146608Y+087139X0198Y0197R090 S2      
327m2889            R3490 -1          A18X+152756Y+113533X0198Y0197R270 S2      
317m2889            VIA   -    MD0100PA00X+153195Y+104621X0200Y         S0      
327m2890            VIA   -    M      A18X+145717Y+087486X0260Y         S2      
327m2890            U68   -9          A18X+145764Y+088323X0140Y0610R180 S2      
327m2890            R3502 -1          A18X+145015Y+087486X0198Y0197     S2      
317m2891            VIA   -    MD0100PA00X+144122Y+089196X0200Y         S0      
327m2891            U68   -14         A18X+144514Y+088323X0140Y0610R180 S2      
317m2891            VIA   -    M      A01X+152194Y+104082X0200Y         S2      
017m2891            VIA   -    M      A18X+152194Y+104082X0260Y         S2      
017m2891                  -    MD0100PA00X+152194Y+104082                       
327m2891            R3493 -1          A18X+152785Y+116910X0198Y0197R180 S2      
317SPI_PEX3_CLK_R   VIA   -    MD0100PA00X+144726Y+089857X0200Y         S0      
327SPI_PEX3_CLK_R   U68   -5          A18X+145014Y+090483X0140Y0610R180 S2      
327SPI_PEX3_CLK_R   R3489 -1          A18X+152739Y+114853X0198Y0197R180 S2      
317SPI_PEX3_CLK_R   VIA   -    M      A01X+152495Y+105104X0200Y         S2      
017SPI_PEX3_CLK_R   VIA   -    M      A18X+152495Y+105104X0260Y         S2      
017SPI_PEX3_CLK_R         -    MD0100PA00X+152495Y+105104                       
317m2892            VIA   -    MD0100PA01X+019851Y+140850X0180Y         S0      
317m2892            J3    -X8   D0122PA01X+017051Y+146295X0282Y    R180 S3      
327m2892            C2182 -2          A01X+019841Y+140359X0120Y0150R090 S1      
317m2893            J7    -S3   D0122PA01X+114917Y+148933X0282Y    R180 S3      
317m2893            VIA   -    MD0080PA01X+122756Y+121732X0160Y    R270 S0      
327m2893            PEX2  -L46        A01X+122756Y+121732X0180Y         S1      
317m2894            VIA   -    MD0100PA01X+017743Y+136010X0180Y         S0      
317m2894            J3    -W4   D0122PA01X+013587Y+146807X0282Y    R180 S3      
327m2894            C2175 -2          A01X+017753Y+135519X0120Y0150R090 S1      
317m2895            VIA   -    MD0100PA01X+111591Y+138430X0180Y         S0      
317m2895            J7    -L8   D0122PA01X+119248Y+156532X0282Y    R180 S3      
327m2895            C2355 -2          A01X+111581Y+137939X0120Y0150R090 S1      
317m2896            VIA   -    MD0100PA01X+015295Y+140850X0180Y         S0      
317m2896            J3    -W2   D0122PA01X+011854Y+146807X0282Y    R180 S3      
327m2896            C2171 -2          A01X+015305Y+140359X0120Y0150R090 S1      
317m2897            VIA   -    MD0100PA01X+010399Y+139658X0180Y    R180 S0      
317m2897            VIA   -    MD0080PA01X+030216Y+123602X0160Y    R270 S0      
327m2897            PEX0  -F43        A01X+030216Y+123602X0180Y         S1      
327m2897            C2159 -1          A01X+010409Y+140149X0120Y0150R090 S1      
317m2898            VIA   -    MD0100PA01X+107919Y+140850X0180Y         S0      
317m2898            J7    -L4   D0122PA01X+115783Y+156532X0282Y    R180 S3      
327m2898            C2347 -2          A01X+107909Y+140359X0120Y0150R090 S1      
327m2899            PU46  -8          A01X+004815Y+049565X0110Y0240R090 S1      
317m2899            VIA   -    M      A01X+004526Y+049599X0200Y    R180 S2      
017m2899            VIA   -    M      A18X+004526Y+049599X0260Y    R180 S2      
017m2899                  -    MD0100PA00X+004526Y+049599                       
327m2899            R4474 -1          A01X+004138Y+049198X0198Y0197R180 S1      
327m2899            R878  -2   M      A01X+004138Y+049598X0198Y0197     S1      
317m2900            J3    -S3   D0122PA01X+012720Y+148933X0282Y    R180 S3      
317m2900            VIA   -    MD0080PA01X+031338Y+121732X0160Y    R270 S0      
327m2900            PEX0  -L46        A01X+031338Y+121732X0180Y         S1      
327m2901            C2178 -1          A01X+018617Y+137729X0120Y0150R090 S1      
317m2901            VIA   -    MD0100PA01X+018627Y+137238X0180Y         S0      
317m2901            VIA   -    MD0080PA01X+029468Y+120610X0160Y    R270 S0      
327m2901            PEX0  -P41        A01X+029468Y+120610X0180Y         S1      
317m2902            VIA   -    MD0100PA01X+112815Y+136010X0180Y         S0      
317m2902            J7    -Y1   D0122PA01X+113185Y+145862X0282Y    R180 S3      
327m2902            C2357 -2          A01X+112805Y+135519X0120Y0150R090 S1      
327P3V3_NIC0        C852  -1          A18X+018002Y+055440X0198Y0197R180 S2      
327P3V3_NIC0        C854  -1          A18X+018002Y+055040X0198Y0197R180 S2      
327P3V3_NIC0        VIA   -           A18X+016172Y+054606X0260Y         S2      
327P3V3_NIC0        VIA   -           A18X+014043Y+054680X0260Y         S2      
327P3V3_NIC0        VIA   -           A18X+011754Y+054792X0260Y         S2      
327P3V3_NIC0        R878  -1          A01X+003823Y+049598X0198Y0197     S1      
317P3V3_NIC0        VIA   -    MD0100PA00X+003565Y+049598X0200Y    R180 S0      
327P3V3_NIC0        R5862 -1          A01X+004964Y+047049X0198Y0197R270 S1      
317P3V3_NIC0        VIA   -    MD0100PA00X+004964Y+047290X0200Y    R180 S0      
327P3V3_NIC0        PU46  -1          A01X+005997Y+048778X0110Y0240R090 S1      
327P3V3_NIC0        PU46  -2          A01X+005997Y+048974X0110Y0240R090 S1      
327P3V3_NIC0        PU46  -3          A01X+005997Y+049171X0110Y0240R090 S1      
327P3V3_NIC0        PU46  -4          A01X+005997Y+049368X0110Y0240R090 S1      
327P3V3_NIC0        PU46  -5          A01X+005997Y+049565X0110Y0240R090 S1      
327P3V3_NIC0        R49   -1          A01X+024869Y+067589X0198Y0197     S1      
317P3V3_NIC0        VIA   -    MD0100PA00X+024869Y+067852X0200Y         S0      
327P3V3_NIC0        C859  -1   M      A01X+024500Y+067583X0198Y0197R180 S1      
327P3V3_NIC0        U12   -2          A01X+024258Y+066991X0400Y0500R180 S1      
317P3V3_NIC0        VIA   -    MD0100PA00X+024500Y+067846X0200Y         S0      
327P3V3_NIC0        R2463 -1          A01X+024210Y+065382X0198Y0197R270 S1      
317P3V3_NIC0        VIA   -    MD0100PA00X+024210Y+065632X0200Y         S0      
327P3V3_NIC0        R11   -2          A01X+015042Y+062360X0198Y0197R180 S1      
317P3V3_NIC0        VIA   -    MD0100PA00X+014792Y+062360X0200Y         S0      
327P3V3_NIC0        R27   -2          A18X+019352Y+061040X0198Y0197     S2      
317P3V3_NIC0        VIA   -    MD0100PA00X+019112Y+061040X0200Y    R180 S0      
327P3V3_NIC0        R12   -2          A01X+015042Y+061960X0198Y0197R180 S1      
317P3V3_NIC0        VIA   -    MD0100PA00X+014792Y+061960X0200Y         S0      
327P3V3_NIC0        R25   -2          A01X+015042Y+060360X0198Y0197R180 S1      
317P3V3_NIC0        VIA   -    MD0100PA00X+014792Y+060360X0200Y         S0      
327P3V3_NIC0        R10   -2          A01X+022158Y+055880X0198Y0197     S1      
327P3V3_NIC0        R35   -2          A01X+022702Y+055770X0198Y0197R180 S1      
317P3V3_NIC0        VIA   -    MD0100PA00X+022404Y+055880X0200Y         S0      
327P3V3_NIC0        R9    -2          A01X+022158Y+056280X0198Y0197     S1      
317P3V3_NIC0        VIA   -    MD0100PA00X+022410Y+056280X0200Y         S0      
327P3V3_NIC0        PU80  -6_7        A01X+006463Y+045549X0295Y0354R270 S1      
327P3V3_NIC0        PC661 -1          A01X+007264Y+045592X0400Y0500R090 S1      
327P3V3_NIC0        J20   -B11        A01X+018127Y+055183X0140Y0480R270 S1      
327P3V3_NIC0        C855  -1          A01X+013897Y+054197X0198Y0197R270 S1      
327P3V3_NIC0        C853  -1          A01X+014296Y+054192X0198Y0197R270 S1      
327P3V3_NIC0        PD52  -C          A01X+008337Y+049610X0670Y0990R180 S1      
317P3V3_NIC0        VIA   -    MD0100PA00X+007396Y+049815X0200Y    R180 S0      
317P3V3_NIC0        VIA   -    MD0100PA00X+007803Y+049363X0200Y    R270 S0      
317P3V3_NIC0        VIA   -    MD0100PA00X+007803Y+049613X0200Y    R270 S0      
317P3V3_NIC0        VIA   -    MD0100PA00X+007803Y+049863X0200Y    R270 S0      
317P3V3_NIC0        VIA   -    MD0100PA00X+007396Y+049515X0200Y    R180 S0      
317P3V3_NIC0        VIA   -    MD0100PA00X+007146Y+049515X0200Y    R180 S0      
317P3V3_NIC0        VIA   -    MD0100PA00X+007146Y+049815X0200Y    R180 S0      
317P3V3_NIC0        VIA   -    MD0100PA00X+006640Y+049299X0200Y    R270 S0      
317P3V3_NIC0        VIA   -    MD0100PA00X+006270Y+049371X0200Y    R270 S0      
317P3V3_NIC0        VIA   -    MD0100PA00X+006640Y+049549X0200Y    R270 S0      
327P3V3_NIC0        PC453 -1          A01X+007256Y+049131X0400Y0500R090 S1      
317P3V3_NIC0        VIA   -    MD0100PA00X+007803Y+049113X0200Y    R270 S0      
327P3V3_NIC0        PC452 -1          A01X+006634Y+049024X0198Y0197R270 S1      
317P3V3_NIC0        VIA   -    MD0100PA00X+006270Y+049121X0200Y    R270 S0      
317P3V3_NIC0        VIA   -    MD0100PA00X+007363Y+046465X0200Y         S0      
317P3V3_NIC0        VIA   -    MD0100PA00X+007363Y+046215X0200Y         S0      
317P3V3_NIC0        VIA   -    MD0100PA00X+007363Y+045965X0200Y         S0      
317P3V3_NIC0        VIA   -    MD0100PA00X+007113Y+046465X0200Y         S0      
317P3V3_NIC0        VIA   -    MD0100PA00X+007113Y+045965X0200Y         S0      
317P3V3_NIC0        VIA   -    MD0100PA00X+007113Y+046215X0200Y         S0      
317P3V3_NIC0        VIA   -    MD0100PA00X+017312Y+055341X0200Y         S0      
317P3V3_NIC0        VIA   -    MD0100PA00X+017562Y+055341X0200Y         S0      
317P3V3_NIC0        VIA   -    MD0100PA00X+017312Y+055091X0200Y         S0      
317P3V3_NIC0        VIA   -    MD0100PA00X+017562Y+055091X0200Y         S0      
317m2903            VIA   -    MD0100PA01X+010059Y+136010X0180Y         S0      
317m2903            J3    -M3   D0122PA01X+012720Y+156098X0282Y    R180 S3      
327m2903            C2156 -2          A01X+010049Y+135519X0120Y0150R090 S1      
317m2904            J7    -R6   D0122PA01X+117516Y+149366X0282Y    R180 S3      
317m2904            VIA   -    MD0080PA01X+123504Y+120610X0160Y         S0      
327m2904            PEX2  -P48        A01X+123504Y+120610X0180Y         S1      
317m2905            VIA   -    MD0100PA01X+118051Y+140850X0180Y         S0      
317m2905            J7    -W8   D0122PA01X+119248Y+146807X0282Y    R180 S3      
327m2905            C2372 -2          A01X+118061Y+140359X0120Y0150R090 S1      
327m2906            R5858 -2          A01X+004164Y+047049X0198Y0197R090 S1      
317m2906            VIA   -    MD0100PA00X+003565Y+049198X0200Y    R180 S0      
317m2906            VIA   -    MD0100PA00X+004164Y+047342X0200Y         S0      
317m2906            VIA   -    M      A01X+012244Y+086078X0200Y         S2      
017m2906            VIA   -    M      A18X+012244Y+086078X0260Y         S2      
017m2906                  -    MD0100PA00X+012244Y+086078                       
327m2906            U6    -F17        A01X+136572Y+088184X0160Y         S1      
317m2906            VIA   -    MD0100PA00X+136730Y+088341X0180Y         S0      
327m2906            R4474 -2          A01X+003823Y+049198X0198Y0197R180 S1      
317m2907            VIA   -    MD0100PA01X+014955Y+139658X0180Y         S0      
317m2907            VIA   -    MD0080PA01X+032087Y+122854X0160Y    R270 S0      
327m2907            C2170 -1          A01X+014945Y+140149X0120Y0150R090 S1      
327m2907            PEX0  -H48        A01X+032087Y+122854X0180Y         S1      
317m2908            VIA   -    MD0100PA01X+115603Y+136010X0180Y         S0      
317m2908            J7    -W4   D0122PA01X+115783Y+146807X0282Y    R180 S3      
327m2908            C2364 -2          A01X+115613Y+135519X0120Y0150R090 S1      
327P3V3_NIC0_SS     PU46  -7          A01X+004815Y+049762X0110Y0240R090 S1      
317P3V3_NIC0_SS     VIA   -    M      A01X+004380Y+050020X0200Y    R180 S2      
017P3V3_NIC0_SS     VIA   -    M      A18X+004380Y+050020X0260Y    R180 S2      
017P3V3_NIC0_SS           -    MD0100PA00X+004380Y+050020                       
327P3V3_NIC0_SS     PC458 -1          A01X+004138Y+049998X0198Y0197R180 S1      
317m2909            VIA   -    MD0100PA01X+012847Y+139658X0180Y         S0      
317m2909            VIA   -    MD0080PA01X+031338Y+122854X0160Y    R270 S0      
327m2909            PEX0  -H46        A01X+031338Y+122854X0180Y         S1      
327m2909            C2165 -1          A01X+012857Y+140149X0120Y0150R090 S1      
317m2910            J7    -F4   D0122PA01X+115783Y+159602X0282Y    R180 S3      
317m2910            VIA   -    MD0080PA01X+121634Y+125098X0160Y         S0      
327m2910            PEX2  -B43        A01X+121634Y+125098X0180Y         S1      
327P3V3_NIC0_OCP    PR241 -1          A01X+004138Y+048798X0198Y0197R180 S1      
327P3V3_NIC0_OCP    PU46  -9          A01X+004815Y+049368X0110Y0240R090 S1      
317P3V3_NIC0_OCP    VIA   -    M      A01X+004395Y+049211X0200Y    R180 S2      
017P3V3_NIC0_OCP    VIA   -    M      A18X+004395Y+049211X0260Y    R180 S2      
017P3V3_NIC0_OCP          -    MD0100PA00X+004395Y+049211                       
317m2911            VIA   -    MD0100PA01X+113155Y+140850X0180Y         S0      
317m2911            J7    -W2   D0122PA01X+114051Y+146807X0282Y    R180 S3      
327m2911            C2360 -2          A01X+113165Y+140359X0120Y0150R090 S1      
327m2912            C2459 -1          A01X+169698Y+135309X0120Y0150R090 S1      
317m2912            VIA   -    MD0100PA01X+169708Y+134819X0180Y         S0      
317m2912            VIA   -    MD0080PA01X+167342Y+121732X0160Y    R270 S0      
327m2912            PEX3  -L43        A01X+167342Y+121732X0180Y         S1      
317m2913            VIA   -    MD0100PA01X+013731Y+137238X0180Y         S0      
317m2913            VIA   -    MD0080PA01X+031712Y+123228X0160Y    R270 S0      
327m2913            PEX0  -G47        A01X+031712Y+123228X0180Y         S1      
327m2913            C2166 -1          A01X+013721Y+137729X0120Y0150R090 S1      
317m2914            VIA   -    MD0100PA01X+110707Y+136010X0180Y         S0      
317m2914            J7    -K6   D0122PA01X+117516Y+157043X0282Y    R180 S3      
327m2914            C2352 -2          A01X+110717Y+135519X0120Y0150R090 S1      
327m2915            C2454 -1          A01X+167610Y+135309X0120Y0150R090 S1      
317m2915            VIA   -    MD0100PA01X+167600Y+134819X0180Y         S0      
317m2915            VIA   -    MD0080PA01X+168838Y+123602X0160Y    R270 S0      
327m2915            PEX3  -F47        A01X+168838Y+123602X0180Y         S1      
317m2916            VIA   -    MD0100PA01X+011283Y+137238X0180Y         S0      
317m2916            VIA   -    MD0080PA01X+030590Y+122480X0160Y    R270 S0      
327m2916            PEX0  -J44        A01X+030590Y+122480X0180Y         S1      
327m2916            C2160 -1          A01X+011273Y+137729X0120Y0150R090 S1      
317m2917            VIA   -    MD0100PA01X+117711Y+140850X0180Y         S0      
317m2917            J7    -X8   D0122PA01X+119248Y+146295X0282Y    R180 S3      
327m2917            C2371 -2          A01X+117701Y+140359X0120Y0150R090 S1      
327m2918            C2443 -1          A01X+162354Y+140149X0120Y0150R090 S1      
317m2918            VIA   -    MD0100PA01X+162364Y+139658X0180Y         S0      
317m2918            VIA   -    MD0080PA01X+166968Y+122480X0160Y    R270 S0      
327m2918            PEX3  -J42        A01X+166968Y+122480X0180Y         S1      
317m2919            VIA   -    MD0100PA01X+015295Y+139658X0180Y         S0      
317m2919            VIA   -    MD0080PA01X+032461Y+122854X0160Y    R270 S0      
327m2919            C2171 -1          A01X+015305Y+140149X0120Y0150R090 S1      
327m2919            PEX0  -H49        A01X+032461Y+122854X0180Y         S1      
317m2920            VIA   -    MD0100PA01X+107919Y+136010X0180Y         S0      
317m2920            J7    -M3   D0122PA01X+114917Y+156098X0282Y    R180 S3      
327m2920            C2345 -2          A01X+107909Y+135519X0120Y0150R090 S1      
317m2921            J7    -S1   D0122PA01X+113185Y+148933X0282Y    R180 S3      
317m2921            VIA   -    MD0080PA01X+123504Y+124724X0160Y    R270 S0      
327m2921            PEX2  -C48        A01X+123504Y+124724X0180Y         S1      
327m2922            C2453 -1          A01X+167250Y+135309X0120Y0150R090 S1      
317m2922            VIA   -    MD0100PA01X+167260Y+134819X0180Y         S0      
317m2922            VIA   -    MD0080PA01X+168838Y+123228X0160Y    R270 S0      
327m2922            PEX3  -G47        A01X+168838Y+123228X0180Y         S1      
317m2923            J7    -F8   D0122PA01X+119248Y+159602X0282Y    R180 S3      
317m2923            VIA   -    MD0080PA01X+123130Y+125098X0160Y         S0      
327m2923            PEX2  -B47        A01X+123130Y+125098X0180Y         S1      
317m2924            VIA   -    MD0100PA01X+115603Y+140850X0180Y         S0      
317m2924            J7    -X5   D0122PA01X+116650Y+146374X0282Y    R180 S3      
327m2924            C2366 -2          A01X+115613Y+140359X0120Y0150R090 S1      
317m2925            VIA   -    MD0100PA01X+114379Y+138430X0180Y         S0      
317m2925            J7    -X3   D0122PA01X+114917Y+146374X0282Y    R180 S3      
327m2925            C2362 -2          A01X+114389Y+137939X0120Y0150R090 S1      
327m2926            C2447 -1          A01X+164802Y+135309X0120Y0150R090 S1      
317m2926            VIA   -    MD0100PA01X+164812Y+134819X0180Y         S0      
317m2926            VIA   -    MD0080PA01X+167716Y+122480X0160Y    R270 S0      
327m2926            PEX3  -J44        A01X+167716Y+122480X0180Y         S1      
317m2927            VIA   -    MD0100PA01X+115263Y+136010X0180Y         S0      
317m2927            J7    -X4   D0122PA01X+115783Y+146295X0282Y    R180 S3      
327m2927            C2363 -2          A01X+115253Y+135519X0120Y0150R090 S1      
317m2928            J7    -S7   D0122PA01X+118382Y+148933X0282Y    R180 S3      
317m2928            VIA   -    MD0080PA01X+122756Y+120236X0160Y    R270 S0      
327m2928            PEX2  -R46        A01X+122756Y+120236X0180Y         S1      
327m2929            C2470 -1          A01X+173730Y+137729X0120Y0150R090 S1      
317m2929            VIA   -    MD0100PA01X+173720Y+137238X0180Y         S0      
317m2929            VIA   -    MD0080PA01X+166968Y+119862X0160Y    R270 S0      
327m2929            PEX3  -T42        A01X+166968Y+119862X0180Y         S1      
317m2930            J7    -R3   D0122PA01X+114917Y+149445X0282Y    R180 S3      
317m2930            VIA   -    MD0080PA01X+123130Y+121732X0160Y    R270 S0      
327m2930            PEX2  -L47        A01X+123130Y+121732X0180Y         S1      
327m2931            C2452 -1          A01X+166386Y+137729X0120Y0150R090 S1      
317m2931            VIA   -    MD0100PA01X+166376Y+137238X0180Y         S0      
317m2931            VIA   -    MD0080PA01X+168464Y+122854X0160Y    R270 S0      
327m2931            PEX3  -H46        A01X+168464Y+122854X0180Y         S1      
317m2932            J7    -R8   D0122PA01X+119248Y+149366X0282Y    R180 S3      
317m2932            VIA   -    MD0080PA01X+123504Y+119862X0160Y    R270 S0      
327m2932            PEX2  -T48        A01X+123504Y+119862X0180Y         S1      
317m2933            J7    -E4   D0122PA01X+115783Y+160114X0282Y    R180 S3      
317m2933            VIA   -    MD0080PA01X+121634Y+125472X0160Y         S0      
327m2933            PEX2  -A43        A01X+121634Y+125472X0180Y         S1      
327m2934            C2451 -1          A01X+166026Y+137729X0120Y0150R090 S1      
317m2934            VIA   -    MD0100PA01X+166036Y+137238X0180Y         S0      
317m2934            VIA   -    MD0080PA01X+168464Y+122480X0160Y    R270 S0      
327m2934            PEX3  -J46        A01X+168464Y+122480X0180Y         S1      
317m2935            J7    -G7   D0122PA01X+118382Y+159169X0282Y    R180 S3      
317m2935            VIA   -    MD0080PA01X+122756Y+124350X0160Y         S0      
327m2935            PEX2  -D46        A01X+122756Y+124350X0180Y         S1      
317m2936            VIA   -    MD0100PA01X+107035Y+138430X0180Y         S0      
317m2936            J7    -K2   D0122PA01X+114051Y+157043X0282Y    R180 S3      
327m2936            C2344 -2          A01X+107045Y+137939X0120Y0150R090 S1      
317m2937            VIA   -    MD0100PA01X+108259Y+140850X0180Y         S0      
317m2937            J7    -K4   D0122PA01X+115783Y+157043X0282Y    R180 S3      
327m2937            C2348 -2          A01X+108269Y+140359X0120Y0150R090 S1      
317m2938            J7    -F2   D0122PA01X+114051Y+159602X0282Y    R180 S3      
317m2938            VIA   -    MD0080PA01X+120886Y+125098X0160Y         S0      
327m2938            PEX2  -B41        A01X+120886Y+125098X0180Y         S1      
327m2939            C2458 -1          A01X+168834Y+137729X0120Y0150R090 S1      
317m2939            VIA   -    MD0100PA01X+168824Y+137238X0180Y         S0      
317m2939            VIA   -    MD0080PA01X+169587Y+122854X0160Y    R270 S0      
327m2939            PEX3  -H49        A01X+169587Y+122854X0180Y         S1      
327m2940            C2469 -1          A01X+173370Y+137729X0120Y0150R090 S1      
317m2940            VIA   -    MD0100PA01X+173380Y+137238X0180Y         S0      
317m2940            VIA   -    MD0080PA01X+166594Y+119862X0160Y    R270 S0      
327m2940            PEX3  -T41        A01X+166594Y+119862X0180Y         S1      
327m2941            C2439 -1          A01X+161130Y+137729X0120Y0150R090 S1      
317m2941            VIA   -    MD0100PA01X+161140Y+137238X0180Y         S0      
317m2941            VIA   -    MD0080PA01X+166220Y+122480X0160Y    R270 S0      
327m2941            PEX3  -J40        A01X+166220Y+122480X0180Y         S1      
327m2942            C2457 -1          A01X+168474Y+137729X0120Y0150R090 S1      
317m2942            VIA   -    MD0100PA01X+168484Y+137238X0180Y         S0      
317m2942            VIA   -    MD0080PA01X+169213Y+122854X0160Y    R270 S0      
327m2942            PEX3  -H48        A01X+169213Y+122854X0180Y         S1      
327m2943            C2449 -1          A01X+164802Y+140149X0120Y0150R090 S1      
317m2943            VIA   -    MD0100PA01X+164812Y+139658X0180Y         S0      
317m2943            VIA   -    MD0080PA01X+168090Y+123228X0160Y    R270 S0      
327m2943            PEX3  -G45        A01X+168090Y+123228X0180Y         S1      
327m2944            C2461 -1          A01X+169698Y+140149X0120Y0150R090 S1      
317m2944            VIA   -    MD0100PA01X+169708Y+139658X0180Y         S0      
317m2944            VIA   -    MD0080PA01X+166594Y+121358X0160Y    R270 S0      
327m2944            PEX3  -M41        A01X+166594Y+121358X0180Y         S1      
327m2945            C2468 -1          A01X+172506Y+140149X0120Y0150R090 S1      
317m2945            VIA   -    MD0100PA01X+172496Y+139658X0180Y         S0      
317m2945            VIA   -    MD0080PA01X+167716Y+120236X0160Y    R270 S0      
327m2945            PEX3  -R44        A01X+167716Y+120236X0180Y         S1      
327m2946            C2466 -1          A01X+172506Y+135309X0120Y0150R090 S1      
317m2946            VIA   -    MD0100PA01X+172496Y+134819X0180Y         S0      
317m2946            VIA   -    MD0080PA01X+166968Y+120610X0160Y    R270 S0      
327m2946            PEX3  -P42        A01X+166968Y+120610X0180Y         S1      
327m2947            C2450 -1          A01X+165162Y+140149X0120Y0150R090 S1      
317m2947            VIA   -    MD0100PA01X+165152Y+139658X0180Y         S0      
317m2947            VIA   -    MD0080PA01X+168090Y+123602X0160Y    R270 S0      
327m2947            PEX3  -F45        A01X+168090Y+123602X0180Y         S1      
317m2948            VIA   -    MD0100PA01X+166036Y+138430X0180Y         S0      
317m2948            J9    -M7   D0122PA01X+170350Y+156098X0282Y    R180 S3      
327m2948            C2451 -2          A01X+166026Y+137939X0120Y0150R090 S1      
327m2949            C2463 -1          A01X+170922Y+137729X0120Y0150R090 S1      
317m2949            VIA   -    MD0100PA01X+170932Y+137238X0180Y         S0      
317m2949            VIA   -    MD0080PA01X+167342Y+120984X0160Y    R270 S0      
327m2949            PEX3  -N43        A01X+167342Y+120984X0180Y         S1      
317m2950            VIA   -    MD0100PA01X+167260Y+136010X0180Y         S0      
317m2950            J9    -L8   D0122PA01X+171216Y+156532X0282Y    R180 S3      
327m2950            C2453 -2          A01X+167250Y+135519X0120Y0150R090 S1      
327m2951            C2442 -1          A01X+162714Y+135309X0120Y0150R090 S1      
317m2951            VIA   -    MD0100PA01X+162704Y+134819X0180Y         S0      
317m2951            VIA   -    MD0080PA01X+166594Y+123602X0160Y    R270 S0      
327m2951            PEX3  -F41        A01X+166594Y+123602X0180Y         S1      
317m2952            VIA   -    MD0100PA01X+161480Y+138430X0180Y         S0      
317m2952            J9    -L1   D0122PA01X+165154Y+156610X0282Y    R180 S3      
327m2952            C2440 -2          A01X+161490Y+137939X0120Y0150R090 S1      
317m2953            VIA   -    MD0100PA01X+165152Y+140850X0180Y         S0      
317m2953            J9    -K6   D0122PA01X+169484Y+157043X0282Y    R180 S3      
327m2953            C2450 -2          A01X+165162Y+140359X0120Y0150R090 S1      
317m2954            VIA   -    MD0100PA01X+170048Y+140850X0180Y         S0      
317m2954            J9    -W4   D0122PA01X+167752Y+146807X0282Y    R180 S3      
327m2954            C2462 -2          A01X+170058Y+140359X0120Y0150R090 S1      
317m2955            J9    -F6   D0122PA01X+169484Y+159602X0282Y    R180 S3      
317m2955            VIA   -    MD0080PA01X+168090Y+125098X0160Y         S0      
327m2955            PEX3  -B45        A01X+168090Y+125098X0180Y         S1      
317m2956            J9    -Q8   D0122PA01X+171216Y+149878X0282Y    R180 S3      
317m2956            VIA   -    MD0080PA01X+169587Y+119862X0160Y    R270 S0      
327m2956            PEX3  -T49        A01X+169587Y+119862X0180Y         S1      
327m2957            C2441 -1          A01X+162354Y+135309X0120Y0150R090 S1      
317m2957            VIA   -    MD0100PA01X+162364Y+134819X0180Y         S0      
317m2957            VIA   -    MD0080PA01X+166594Y+123228X0160Y    R270 S0      
327m2957            PEX3  -G41        A01X+166594Y+123228X0180Y         S1      
317m2958            J9    -R1   D0122PA01X+165154Y+149445X0282Y    R180 S3      
317m2958            VIA   -    MD0080PA01X+169587Y+124724X0160Y    R270 S0      
327m2958            PEX3  -C49        A01X+169587Y+124724X0180Y         S1      
327m2959            C2462 -1          A01X+170058Y+140149X0120Y0150R090 S1      
317m2959            VIA   -    MD0100PA01X+170048Y+139658X0180Y         S0      
317m2959            VIA   -    MD0080PA01X+166968Y+121358X0160Y    R270 S0      
327m2959            PEX3  -M42        A01X+166968Y+121358X0180Y         S1      
317m2960            J9    -G3   D0122PA01X+166886Y+159169X0282Y    R180 S3      
317m2960            VIA   -    MD0080PA01X+166968Y+124350X0160Y         S0      
327m2960            PEX3  -D42        A01X+166968Y+124350X0180Y         S1      
317m2961            J9    -R3   D0122PA01X+166886Y+149445X0282Y    R180 S3      
317m2961            VIA   -    MD0080PA01X+168838Y+121732X0160Y    R270 S0      
327m2961            PEX3  -L47        A01X+168838Y+121732X0180Y         S1      
327m2962            C2467 -1          A01X+172146Y+140149X0120Y0150R090 S1      
317m2962            VIA   -    MD0100PA01X+172156Y+139658X0180Y         S0      
317m2962            VIA   -    MD0080PA01X+167342Y+120236X0160Y    R270 S0      
327m2962            PEX3  -R43        A01X+167342Y+120236X0180Y         S1      
317m2963            VIA   -    MD0100PA01X+172496Y+140850X0180Y         S0      
317m2963            J9    -X7   D0122PA01X+170350Y+146374X0282Y    R180 S3      
327m2963            C2468 -2          A01X+172506Y+140359X0120Y0150R090 S1      
327m2964            C2445 -1          A01X+163578Y+137729X0120Y0150R090 S1      
317m2964            VIA   -    MD0100PA01X+163588Y+137238X0180Y         S0      
317m2964            VIA   -    MD0080PA01X+167342Y+123228X0160Y    R270 S0      
327m2964            PEX3  -G43        A01X+167342Y+123228X0180Y         S1      
317m2965            VIA   -    MD0100PA01X+172156Y+136010X0180Y         S0      
317m2965            J9    -X6   D0122PA01X+169484Y+146295X0282Y    R180 S3      
327m2965            C2465 -2          A01X+172146Y+135519X0120Y0150R090 S1      
327m2966            C2460 -1          A01X+170058Y+135309X0120Y0150R090 S1      
317m2966            VIA   -    MD0100PA01X+170048Y+134819X0180Y         S0      
317m2966            VIA   -    MD0080PA01X+167716Y+121732X0160Y    R270 S0      
327m2966            PEX3  -L44        A01X+167716Y+121732X0180Y         S1      
317m2967            J9    -F3   D0122PA01X+166886Y+159681X0282Y    R180 S3      
317m2967            VIA   -    MD0080PA01X+166968Y+124724X0160Y         S0      
327m2967            PEX3  -C42        A01X+166968Y+124724X0180Y         S1      
327m2968            C2444 -1          A01X+162714Y+140149X0120Y0150R090 S1      
317m2968            VIA   -    MD0100PA01X+162704Y+139658X0180Y         S0      
317m2968            VIA   -    MD0080PA01X+166968Y+122854X0160Y    R270 S0      
327m2968            PEX3  -H42        A01X+166968Y+122854X0180Y         S1      
317m2969            J9    -Q6   D0122PA01X+169484Y+149878X0282Y    R180 S3      
317m2969            VIA   -    MD0080PA01X+169587Y+120610X0160Y    R270 S0      
327m2969            PEX3  -P49        A01X+169587Y+120610X0180Y         S1      
327m2970            JPEX2 -7   M      A01X+101063Y+090030X0200Y0600R090 S1      
327m2970            U319  -7   M      A01X+101126Y+090030X0320Y0750R090 S1      
317m2970            VIA   -    M      A01X+102141Y+089501X0200Y         S2      
017m2970            VIA   -    M      A18X+102141Y+089501X0260Y         S2      
017m2970                  -    MD0100PA00X+102141Y+089501                       
327m2970            R3487 -2          A18X+101390Y+089340X0198Y0197R270 S2      
327m2970            R3481 -2          A18X+101390Y+089712X0198Y0197R090 S2      
317m2971            J9    -E6   D0122PA01X+169484Y+160114X0282Y    R180 S3      
317m2971            VIA   -    MD0080PA01X+168090Y+125472X0160Y         S0      
327m2971            PEX3  -A45        A01X+168090Y+125472X0180Y         S1      
327m2972            C2455 -1          A01X+167250Y+140149X0120Y0150R090 S1      
317m2972            VIA   -    MD0100PA01X+167260Y+139658X0180Y         S0      
317m2972            VIA   -    MD0080PA01X+169213Y+123976X0160Y         S0      
327m2972            PEX3  -E48        A01X+169213Y+123976X0180Y         S1      
327m2973            JPEX2 -15         A01X+097283Y+087530X0200Y0600R090 S1      
317m2973            VIA   -    M      A01X+099244Y+087040X0200Y         S2      
017m2973            VIA   -    M      A18X+099244Y+087040X0260Y         S2      
017m2973                  -    MD0100PA00X+099244Y+087040                       
327m2973            U319  -15  M      A01X+097283Y+087530X0320Y0750R270 S1      
327m2973            R3483 -2          A18X+099763Y+087040X0198Y0197     S2      
317m2974            J9    -R5   D0122PA01X+168618Y+149445X0282Y    R180 S3      
317m2974            VIA   -    MD0080PA01X+168838Y+120984X0160Y    R270 S0      
327m2974            PEX3  -N47        A01X+168838Y+120984X0180Y         S1      
327P12V_SSD0_OCP    PU30  -9          A01X+009507Y+021317X0110Y0240R270 S1      
317P12V_SSD0_OCP    VIA   -    M      A01X+009903Y+021246X0200Y         S2      
017P12V_SSD0_OCP    VIA   -    M      A18X+009903Y+021246X0260Y         S2      
017P12V_SSD0_OCP          -    MD0100PA00X+009903Y+021246                       
327P12V_SSD0_OCP    PR209 -1          A01X+010184Y+021286X0198Y0197     S1      
317SPI_PEX2_SDIO1   VIA   -    MD0080PA00X+108356Y+115935X0160Y         S0      
327SPI_PEX2_SDIO1   VIA   -    M      A18X+108169Y+116496X0260Y         S2      
327SPI_PEX2_SDIO1   R3474 -2          A18X+107391Y+116910X0198Y0197R180 S2      
327SPI_PEX2_SDIO1   PEX2  -AF8        A01X+108543Y+116122X0180Y         S1      
317m2975            J9    -R2   D0122PA01X+166020Y+149366X0282Y    R180 S3      
317m2975            VIA   -    MD0080PA01X+169213Y+122106X0160Y    R090 S0      
327m2975            PEX3  -K48        A01X+169213Y+122106X0180Y         S1      
327P12V_SSD0_SS     PC362 -1          A01X+010184Y+020086X0198Y0197     S1      
317P12V_SSD0_SS     VIA   -    M      A01X+009894Y+020086X0200Y         S2      
017P12V_SSD0_SS     VIA   -    M      A18X+009894Y+020086X0260Y         S2      
017P12V_SSD0_SS           -    MD0100PA00X+009894Y+020086                       
327P12V_SSD0_SS     PU30  -7          A01X+009507Y+020923X0110Y0240R270 S1      
317SPI_PEX2_SDIO0   VIA   -    M      A01X+107982Y+115935X0200Y         S2      
017SPI_PEX2_SDIO0   VIA   -    M      A18X+107982Y+115935X0260Y         S2      
017SPI_PEX2_SDIO0         -    MD0100PA00X+107982Y+115935                       
327SPI_PEX2_SDIO0   R3475 -2          A18X+107391Y+116456X0198Y0197R180 S2      
327SPI_PEX2_SDIO0   PEX2  -AF7        A01X+108169Y+116122X0180Y         S1      
317m2976            J9    -F2   D0122PA01X+166020Y+159602X0282Y    R180 S3      
317m2976            VIA   -    MD0080PA01X+166594Y+125098X0160Y         S0      
327m2976            PEX3  -B41        A01X+166594Y+125098X0180Y         S1      
327m2977            C2440 -1          A01X+161490Y+137729X0120Y0150R090 S1      
317m2977            VIA   -    MD0100PA01X+161480Y+137238X0180Y         S0      
317m2977            VIA   -    MD0080PA01X+166220Y+122854X0160Y    R270 S0      
327m2977            PEX3  -H40        A01X+166220Y+122854X0180Y         S1      
327m2978            JPEX2 -8   M      A01X+101063Y+090530X0200Y0600R090 S1      
317m2978            VIA   -    M      A01X+100541Y+090530X0200Y         S2      
017m2978            VIA   -    M      A18X+100541Y+090530X0260Y         S2      
017m2978                  -    MD0100PA00X+100541Y+090530                       
327m2978            R3480 -1          A18X+100541Y+090058X0198Y0197R090 S2      
327m2978            U319  -8   M      A01X+101126Y+090530X0320Y0750R090 S1      
317m2979            VIA   -    MD0100PA01X+170048Y+136010X0180Y         S0      
317m2979            J9    -X3   D0122PA01X+166886Y+146374X0282Y    R180 S3      
327m2979            C2460 -2          A01X+170058Y+135519X0120Y0150R090 S1      
317SPI_PEX2_SDIO2   VIA   -    M      A01X+108356Y+115561X0200Y         S2      
017SPI_PEX2_SDIO2   VIA   -    M      A18X+108356Y+115561X0260Y         S2      
017SPI_PEX2_SDIO2         -    MD0100PA00X+108356Y+115561                       
327SPI_PEX2_SDIO2   R3473 -2          A18X+107370Y+116065X0198Y0197R180 S2      
327SPI_PEX2_SDIO2   PEX2  -AG8        A01X+108543Y+115748X0180Y         S1      
317m2980            VIA   -    MD0100PA01X+164812Y+140850X0180Y         S0      
317m2980            J9    -L6   D0122PA01X+169484Y+156532X0282Y    R180 S3      
327m2980            C2449 -2          A01X+164802Y+140359X0120Y0150R090 S1      
327m2981            PU30  -8          A01X+009507Y+021120X0110Y0240R270 S1      
317m2981            VIA   -    M      A01X+009897Y+020704X0200Y         S2      
017m2981            VIA   -    M      A18X+009897Y+020704X0260Y         S2      
017m2981                  -    MD0100PA00X+009897Y+020704                       
327m2981            R861  -2          A01X+010184Y+020486X0198Y0197R180 S1      
327m2981            R4458 -1   M      A01X+010184Y+020886X0198Y0197     S1      
327m2982            JPEX2 -1          A01X+101063Y+087030X0200Y0600R090 S1      
327m2982            U319  -1   M      A01X+101126Y+087030X0320Y0750R090 S1      
317m2982            VIA   -    M      A01X+101780Y+086706X0200Y         S2      
017m2982            VIA   -    M      A18X+101780Y+086706X0260Y         S2      
017m2982                  -    MD0100PA00X+101780Y+086706                       
327m2982            R3479 -2          A18X+100899Y+086824X0198Y0197R090 S2      
327m2982            R3486 -2   M      A18X+101308Y+086821X0198Y0197R090 S2      
317m2983            J9    -F8   D0122PA01X+171216Y+159602X0282Y    R180 S3      
317m2983            VIA   -    MD0080PA01X+168838Y+125098X0160Y         S0      
327m2983            PEX3  -B47        A01X+168838Y+125098X0180Y         S1      
327m2984            C2465 -1          A01X+172146Y+135309X0120Y0150R090 S1      
317m2984            VIA   -    MD0100PA01X+172156Y+134819X0180Y         S0      
317m2984            VIA   -    MD0080PA01X+166594Y+120610X0160Y    R270 S0      
327m2984            PEX3  -P41        A01X+166594Y+120610X0180Y         S1      
317m2985            VIA   -    M      A01X+010757Y+020886X0200Y         S2      
017m2985            VIA   -    M      A18X+010757Y+020886X0260Y         S2      
017m2985                  -    MD0100PA00X+010757Y+020886                       
327m2985            U6    -A9         A01X+134053Y+089759X0160Y         S1      
317m2985            VIA   -    MD0100PA00X+134000Y+090000X0200Y         S0      
317m2985            VIA   -    MD0100PA00X+011847Y+079678X0200Y         S0      
327m2985            R4458 -2          A01X+010499Y+020886X0198Y0197     S1      
327m2985            R5838 -2          A01X+001372Y+024208X0198Y0197R180 S1      
317m2985            VIA   -    MD0100PA00X+005799Y+025888X0200Y    R180 S0      
327m2986            JPEX2 -9          A01X+097283Y+090530X0200Y0600R090 S1      
327m2986            R3482 -2   M      A18X+097126Y+090550X0198Y0197     S2      
327m2986            R3488 -1          A18X+097126Y+089750X0198Y0197R180 S2      
327m2986            R3485 -2   M      A18X+097126Y+090150X0198Y0197     S2      
317m2986            VIA   -    M      A01X+096681Y+090456X0200Y         S2      
017m2986            VIA   -    M      A18X+096681Y+090456X0260Y         S2      
017m2986                  -    MD0100PA00X+096681Y+090456                       
327m2986            U319  -9   M      A01X+097283Y+090530X0320Y0750R270 S1      
317m2987            VIA   -    MD0100PA01X+172156Y+140850X0180Y         S0      
317m2987            J9    -Y7   D0122PA01X+170350Y+145862X0282Y    R180 S3      
327m2987            C2467 -2          A01X+172146Y+140359X0120Y0150R090 S1      
327m2988            JPEX2 -16         A01X+097283Y+087030X0200Y0600R090 S1      
327m2988            R3484 -2          A18X+097313Y+087103X0198Y0197R090 S2      
317m2988            VIA   -    M      A01X+097888Y+086955X0200Y         S2      
017m2988            VIA   -    M      A18X+097888Y+086955X0260Y         S2      
017m2988                  -    MD0100PA00X+097888Y+086955                       
327m2988            U319  -16  M      A01X+097283Y+087030X0320Y0750R270 S1      
317m2989            VIA   -    MD0100PA01X+167260Y+140850X0180Y         S0      
317m2989            J9    -Y1   D0122PA01X+165154Y+145862X0282Y    R180 S3      
327m2989            C2455 -2          A01X+167250Y+140359X0120Y0150R090 S1      
327m2990            C2448 -1          A01X+165162Y+135309X0120Y0150R090 S1      
317m2990            VIA   -    MD0100PA01X+165152Y+134819X0180Y         S0      
317m2990            VIA   -    MD0080PA01X+167716Y+122854X0160Y    R270 S0      
327m2990            PEX3  -H44        A01X+167716Y+122854X0180Y         S1      
327m2991            VIA   -    M      A18X+097777Y+088768X0260Y         S2      
327m2991            R3478 -1          A18X+097777Y+088322X0198Y0197R090 S2      
327m2991            U67   -15         A18X+098555Y+088323X0140Y0610R180 S2      
317m2992            VIA   -    MD0100PA01X+171272Y+138430X0180Y         S0      
317m2992            J9    -X5   D0122PA01X+168618Y+146374X0282Y    R180 S3      
327m2992            C2464 -2          A01X+171282Y+137939X0120Y0150R090 S1      
327m2993            C2464 -1          A01X+171282Y+137729X0120Y0150R090 S1      
317m2993            VIA   -    MD0100PA01X+171272Y+137238X0180Y         S0      
317m2993            VIA   -    MD0080PA01X+167716Y+120984X0160Y    R270 S0      
327m2993            PEX3  -N44        A01X+167716Y+120984X0180Y         S1      
317SPI_PEX2_CLK     VIA   -    M      A01X+107982Y+115187X0200Y         S2      
017SPI_PEX2_CLK     VIA   -    M      A18X+107982Y+115187X0260Y         S2      
017SPI_PEX2_CLK           -    MD0100PA00X+107982Y+115187                       
327SPI_PEX2_CLK     R3471 -2          A18X+107345Y+114853X0198Y0197R180 S2      
327SPI_PEX2_CLK     PEX2  -AH7        A01X+108169Y+115374X0180Y         S1      
317m2994            J9    -E8   D0122PA01X+171216Y+160114X0282Y    R180 S3      
317m2994            VIA   -    MD0080PA01X+168838Y+125472X0160Y         S0      
327m2994            PEX3  -A47        A01X+168838Y+125472X0180Y         S1      
317SPI_PEX2_SDIO3   VIA   -    MD0080PA00X+108356Y+115187X0160Y         S0      
327SPI_PEX2_SDIO3   VIA   -    M      A18X+107047Y+114339X0260Y         S2      
327SPI_PEX2_SDIO3   R3472 -2          A18X+107047Y+113848X0198Y0197R270 S2      
327SPI_PEX2_SDIO3   PEX2  -AH8        A01X+108543Y+115374X0180Y         S1      
317m2995            VIA   -    MD0100PA01X+167600Y+136010X0180Y         S0      
317m2995            J9    -K8   D0122PA01X+171216Y+157043X0282Y    R180 S3      
327m2995            C2454 -2          A01X+167610Y+135519X0120Y0150R090 S1      
327m2996            C2456 -1          A01X+167610Y+140149X0120Y0150R090 S1      
317m2996            VIA   -    MD0100PA01X+167600Y+139658X0180Y         S0      
317m2996            VIA   -    MD0080PA01X+169587Y+123976X0160Y         S0      
327m2996            PEX3  -E49        A01X+169587Y+123976X0180Y         S1      
317SPI_PEX2_CS_N    VIA   -    MD0080PA00X+107982Y+114813X0160Y         S0      
327SPI_PEX2_CS_N    VIA   -    M      A18X+108168Y+114627X0260Y         S2      
327SPI_PEX2_CS_N    R3470 -2          A18X+107421Y+113848X0198Y0197R270 S2      
327SPI_PEX2_CS_N    PEX2  -AJ7        A01X+108169Y+115000X0180Y         S1      
327SPI_PEX2_CS_N    R6159 -1   M      A18X+107795Y+113848X0198Y0197R090 S2      
317m2997            VIA   -    MD0100PA01X+164812Y+136010X0180Y         S0      
317m2997            J9    -M5   D0122PA01X+168618Y+156098X0282Y    R180 S3      
327m2997            C2447 -2          A01X+164802Y+135519X0120Y0150R090 S1      
327m2998            C2446 -1          A01X+163938Y+137729X0120Y0150R090 S1      
317m2998            VIA   -    MD0100PA01X+163928Y+137238X0180Y         S0      
317m2998            VIA   -    MD0080PA01X+167342Y+123602X0160Y    R270 S0      
327m2998            PEX3  -F43        A01X+167342Y+123602X0180Y         S1      
317m2999            J9    -R6   D0122PA01X+169484Y+149366X0282Y    R180 S3      
317m2999            VIA   -    MD0080PA01X+169213Y+120610X0160Y         S0      
327m2999            PEX3  -P48        A01X+169213Y+120610X0180Y         S1      
317m3000            VIA   -    MD0100PA01X+163928Y+138430X0180Y         S0      
317m3000            J9    -K4   D0122PA01X+167752Y+157043X0282Y    R180 S3      
327m3000            C2446 -2          A01X+163938Y+137939X0120Y0150R090 S1      
317m3001            J9    -F5   D0122PA01X+168618Y+159681X0282Y    R180 S3      
317m3001            VIA   -    MD0080PA01X+167716Y+124724X0160Y         S0      
327m3001            PEX3  -C44        A01X+167716Y+124724X0180Y         S1      
327m3002            R3437 -2   M      A18X+005681Y+090150X0198Y0197     S2      
317m3002            VIA   -    M      A01X+005208Y+090530X0200Y         S2      
017m3002            VIA   -    M      A18X+005208Y+090530X0260Y         S2      
017m3002                  -    MD0100PA00X+005208Y+090530                       
327m3002            U317  -9   M      A01X+005850Y+090530X0320Y0750R270 S1      
327m3002            JPEX0 -9   M      A01X+005913Y+090530X0200Y0600R090 S1      
327m3002            R3441 -1          A18X+005681Y+089750X0198Y0197R180 S2      
327m3002            R3448 -2   M      A18X+005681Y+090550X0198Y0197     S2      
317m3003            VIA   -    MD0100PA01X+162704Y+136010X0180Y         S0      
317m3003            J9    -K2   D0122PA01X+166020Y+157043X0282Y    R180 S3      
327m3003            C2442 -2          A01X+162714Y+135519X0120Y0150R090 S1      
317SPI_PEX0_SDIO3   VIA   -    MD0080PA00X+016939Y+115187X0160Y         S0      
327SPI_PEX0_SDIO3   VIA   -    M      A18X+015630Y+114339X0260Y         S2      
327SPI_PEX0_SDIO3   R3434 -2          A18X+015630Y+113848X0198Y0197R270 S2      
327SPI_PEX0_SDIO3   PEX0  -AH8        A01X+017126Y+115374X0180Y         S1      
317m3004            J9    -G1   D0122PA01X+165154Y+159169X0282Y    R180 S3      
317m3004            VIA   -    MD0080PA01X+166220Y+124350X0160Y         S0      
327m3004            PEX3  -D40        A01X+166220Y+124350X0180Y         S1      
317SPI_PEX0_CS_N    VIA   -    MD0080PA00X+016565Y+114813X0160Y         S0      
327SPI_PEX0_CS_N    VIA   -    M      A18X+016751Y+114627X0260Y         S2      
327SPI_PEX0_CS_N    PEX0  -AJ7        A01X+016752Y+115000X0180Y         S1      
327SPI_PEX0_CS_N    R3292 -2          A18X+016004Y+113848X0198Y0197R270 S2      
327SPI_PEX0_CS_N    R6157 -1   M      A18X+016354Y+113848X0198Y0197R090 S2      
317m3005            VIA   -    MD0100PA01X+162364Y+140850X0180Y         S0      
317m3005            J9    -M3   D0122PA01X+166886Y+156098X0282Y    R180 S3      
327m3005            C2443 -2          A01X+162354Y+140359X0120Y0150R090 S1      
317SPI_PEX0_SDIO2   VIA   -    M      A01X+016939Y+115561X0200Y         S2      
017SPI_PEX0_SDIO2   VIA   -    M      A18X+016939Y+115561X0260Y         S2      
017SPI_PEX0_SDIO2         -    MD0100PA00X+016939Y+115561                       
327SPI_PEX0_SDIO2   R3435 -2          A18X+015952Y+116065X0198Y0197R180 S2      
327SPI_PEX0_SDIO2   PEX0  -AG8        A01X+017126Y+115748X0180Y         S1      
317m3006            J9    -Q4   D0122PA01X+167752Y+149878X0282Y    R180 S3      
317m3006            VIA   -    MD0080PA01X+169587Y+121358X0160Y    R270 S0      
327m3006            PEX3  -M49        A01X+169587Y+121358X0180Y         S1      
327m3007            VIA   -    M      A18X+006374Y+088776X0260Y         S2      
327m3007            U65   -15         A18X+007153Y+088323X0140Y0610R180 S2      
327m3007            R3442 -1          A18X+006374Y+088322X0198Y0197R090 S2      
317m3008            J9    -S5   D0122PA01X+168618Y+148933X0282Y    R180 S3      
317m3008            VIA   -    MD0080PA01X+168464Y+120984X0160Y    R270 S0      
327m3008            PEX3  -N46        A01X+168464Y+120984X0180Y         S1      
317m3009            VIA   -    M      A01X+009139Y+090530X0200Y         S2      
017m3009            VIA   -    M      A18X+009139Y+090530X0260Y         S2      
017m3009                  -    MD0100PA00X+009139Y+090530                       
327m3009            R3445 -1          A18X+009139Y+090058X0198Y0197R090 S2      
327m3009            U317  -8   M      A01X+009693Y+090530X0320Y0750R090 S1      
327m3009            JPEX0 -8          A01X+009693Y+090530X0200Y0600R090 S1      
317m3010            VIA   -    MD0100PA01X+170932Y+138430X0180Y         S0      
317m3010            J9    -Y5   D0122PA01X+168618Y+145862X0282Y    R180 S3      
327m3010            C2463 -2          A01X+170922Y+137939X0120Y0150R090 S1      
317m3011            VIA   -    M      A01X+006393Y+087469X0200Y         S2      
017m3011            VIA   -    M      A18X+006393Y+087469X0260Y         S2      
017m3011                  -    MD0100PA00X+006393Y+087469                       
327m3011            U317  -15         A01X+005850Y+087530X0320Y0750R270 S1      
327m3011            JPEX0 -15  M      A01X+005913Y+087530X0200Y0600R090 S1      
327m3011            R3449 -2          A18X+007589Y+087486X0198Y0197     S2      
317m3012            J9    -Q2   D0122PA01X+166020Y+149878X0282Y    R180 S3      
317m3012            VIA   -    MD0080PA01X+169587Y+122106X0160Y    R090 S0      
327m3012            PEX3  -K49        A01X+169587Y+122106X0180Y         S1      
327m3013            R3438 -2   M      A18X+009906Y+086821X0198Y0197R090 S2      
327m3013            U317  -1   M      A01X+009693Y+087030X0320Y0750R090 S1      
327m3013            JPEX0 -1          A01X+009693Y+087030X0200Y0600R090 S1      
317m3013            VIA   -    M      A01X+010377Y+086821X0200Y         S2      
017m3013            VIA   -    M      A18X+010377Y+086821X0260Y         S2      
017m3013                  -    MD0100PA00X+010377Y+086821                       
327m3013            R3446 -2          A18X+009496Y+086824X0198Y0197R090 S2      
317m3014            J9    -E4   D0122PA01X+167752Y+160114X0282Y    R180 S3      
317m3014            VIA   -    MD0080PA01X+167342Y+125472X0160Y         S0      
327m3014            PEX3  -A43        A01X+167342Y+125472X0180Y         S1      
317SPI_PEX0_CLK     VIA   -    M      A01X+016565Y+115187X0200Y         S2      
017SPI_PEX0_CLK     VIA   -    M      A18X+016565Y+115187X0260Y         S2      
017SPI_PEX0_CLK           -    MD0100PA00X+016565Y+115187                       
327SPI_PEX0_CLK     R3293 -2          A18X+015928Y+114853X0198Y0197R180 S2      
327SPI_PEX0_CLK     PEX0  -AH7        A01X+016752Y+115374X0180Y         S1      
317m3015            J9    -F7   D0122PA01X+170350Y+159681X0282Y    R180 S3      
317m3015            VIA   -    MD0080PA01X+168464Y+124724X0160Y         S0      
327m3015            PEX3  -C46        A01X+168464Y+124724X0180Y         S1      
317SPI_PEX0_SDIO0   VIA   -    M      A01X+016565Y+115935X0200Y         S2      
017SPI_PEX0_SDIO0   VIA   -    M      A18X+016565Y+115935X0260Y         S2      
017SPI_PEX0_SDIO0         -    MD0100PA00X+016565Y+115935                       
327SPI_PEX0_SDIO0   R3295 -2          A18X+015974Y+116456X0198Y0197R180 S2      
327SPI_PEX0_SDIO0   PEX0  -AF7        A01X+016752Y+116122X0180Y         S1      
317m3016            VIA   -    MD0100PA01X+173380Y+138430X0180Y         S0      
317m3016            J9    -X8   D0122PA01X+171216Y+146295X0282Y    R180 S3      
327m3016            C2469 -2          A01X+173370Y+137939X0120Y0150R090 S1      
317m3017            VIA   -    M      A01X+006397Y+086948X0200Y         S2      
017m3017            VIA   -    M      A18X+006397Y+086948X0260Y         S2      
017m3017                  -    MD0100PA00X+006397Y+086948                       
327m3017            U317  -16         A01X+005850Y+087030X0320Y0750R270 S1      
327m3017            JPEX0 -16  M      A01X+005913Y+087030X0200Y0600R090 S1      
327m3017            R3450 -2          A18X+005910Y+087103X0198Y0197R090 S2      
317m3018            VIA   -    MD0100PA01X+169708Y+140850X0180Y         S0      
317m3018            J9    -X4   D0122PA01X+167752Y+146295X0282Y    R180 S3      
327m3018            C2461 -2          A01X+169698Y+140359X0120Y0150R090 S1      
317SPI_PEX0_SDIO1   VIA   -    MD0080PA00X+016939Y+115935X0160Y         S0      
327SPI_PEX0_SDIO1   VIA   -    M      A18X+016752Y+116496X0260Y         S2      
327SPI_PEX0_SDIO1   PEX0  -AF8        A01X+017126Y+116122X0180Y         S1      
327SPI_PEX0_SDIO1   R3294 -2          A18X+015974Y+116910X0198Y0197R180 S2      
317m3019            VIA   -    MD0100PA01X+163588Y+138430X0180Y         S0      
317m3019            J9    -L4   D0122PA01X+167752Y+156532X0282Y    R180 S3      
327m3019            C2445 -2          A01X+163578Y+137939X0120Y0150R090 S1      
327m3020            R3439 -2          A18X+009644Y+089345X0198Y0197R270 S2      
317m3020            VIA   -    M      A01X+010369Y+090030X0200Y         S2      
017m3020            VIA   -    M      A18X+010369Y+090030X0260Y         S2      
017m3020                  -    MD0100PA00X+010369Y+090030                       
327m3020            U317  -7   M      A01X+009693Y+090030X0320Y0750R090 S1      
327m3020            JPEX0 -7          A01X+009693Y+090030X0200Y0600R090 S1      
327m3020            R3447 -2   M      A18X+009535Y+089742X0198Y0197R090 S2      
317m3021            VIA   -    MD0100PA01X+173720Y+138430X0180Y         S0      
317m3021            J9    -W8   D0122PA01X+171216Y+146807X0282Y    R180 S3      
327m3021            C2470 -2          A01X+173730Y+137939X0120Y0150R090 S1      
317m3022            J9    -S3   D0122PA01X+166886Y+148933X0282Y    R180 S3      
317m3022            VIA   -    MD0080PA01X+168464Y+121732X0160Y    R270 S0      
327m3022            PEX3  -L46        A01X+168464Y+121732X0180Y         S1      
317m3023            J9    -S1   D0122PA01X+165154Y+148933X0282Y    R180 S3      
317m3023            VIA   -    MD0080PA01X+169213Y+124724X0160Y    R270 S0      
327m3023            PEX3  -C48        A01X+169213Y+124724X0180Y         S1      
317m3024            J9    -G5   D0122PA01X+168618Y+159169X0282Y    R180 S3      
317m3024            VIA   -    MD0080PA01X+167716Y+124350X0160Y         S0      
327m3024            PEX3  -D44        A01X+167716Y+124350X0180Y         S1      
317SPI_PEX1_SDIO3   VIA   -    MD0080PA00X+062648Y+115187X0160Y         S0      
327SPI_PEX1_SDIO3   VIA   -    M      A18X+061339Y+114339X0260Y         S2      
327SPI_PEX1_SDIO3   R3453 -2          A18X+061339Y+113848X0198Y0197R270 S2      
327SPI_PEX1_SDIO3   PEX1  -AH8        A01X+062835Y+115374X0180Y         S1      
317m3025            VIA   -    MD0100PA01X+165152Y+136010X0180Y         S0      
317m3025            J9    -L5   D0122PA01X+168618Y+156610X0282Y    R180 S3      
327m3025            C2448 -2          A01X+165162Y+135519X0120Y0150R090 S1      
317SPI_PEX1_SDIO0   VIA   -    M      A01X+062274Y+115935X0200Y         S2      
017SPI_PEX1_SDIO0   VIA   -    M      A18X+062274Y+115935X0260Y         S2      
017SPI_PEX1_SDIO0         -    MD0100PA00X+062274Y+115935                       
327SPI_PEX1_SDIO0   R3456 -2          A18X+061683Y+116456X0198Y0197R180 S2      
327SPI_PEX1_SDIO0   PEX1  -AF7        A01X+062461Y+116122X0180Y         S1      
317m3026            J9    -R7   D0122PA01X+170350Y+149445X0282Y    R180 S3      
317m3026            VIA   -    MD0080PA01X+168838Y+120236X0160Y    R270 S0      
327m3026            PEX3  -R47        A01X+168838Y+120236X0180Y         S1      
317SPI_PEX1_SDIO2   VIA   -    M      A01X+062648Y+115561X0200Y         S2      
017SPI_PEX1_SDIO2   VIA   -    M      A18X+062648Y+115561X0260Y         S2      
017SPI_PEX1_SDIO2         -    MD0100PA00X+062648Y+115561                       
327SPI_PEX1_SDIO2   R3454 -2          A18X+061661Y+116065X0198Y0197R180 S2      
327SPI_PEX1_SDIO2   PEX1  -AG8        A01X+062835Y+115748X0180Y         S1      
317m3027            J9    -E2   D0122PA01X+166020Y+160114X0282Y    R180 S3      
317m3027            VIA   -    MD0080PA01X+166594Y+125472X0160Y         S0      
327m3027            PEX3  -A41        A01X+166594Y+125472X0180Y         S1      
327m3028            U320  -16  M      A01X+051544Y+087030X0320Y0750R270 S1      
327m3028            JPEX1 -16         A01X+051607Y+087030X0200Y0600R090 S1      
317m3028            VIA   -    M      A01X+050825Y+087332X0200Y         S2      
017m3028            VIA   -    M      A18X+050825Y+087332X0260Y         S2      
017m3028                  -    MD0100PA00X+050825Y+087332                       
327m3028            R3465 -2          A18X+051604Y+087103X0198Y0197R090 S2      
317m3029            J9    -R8   D0122PA01X+171216Y+149366X0282Y    R180 S3      
317m3029            VIA   -    MD0080PA01X+169213Y+119862X0160Y    R270 S0      
327m3029            PEX3  -T48        A01X+169213Y+119862X0180Y         S1      
317SPI_PEX1_SDIO1   VIA   -    MD0080PA00X+062648Y+115935X0160Y         S0      
327SPI_PEX1_SDIO1   VIA   -    M      A18X+062461Y+116496X0260Y         S2      
327SPI_PEX1_SDIO1   R3455 -2          A18X+061683Y+116910X0198Y0197R180 S2      
327SPI_PEX1_SDIO1   PEX1  -AF8        A01X+062835Y+116122X0180Y         S1      
317m3030            J9    -R4   D0122PA01X+167752Y+149366X0282Y    R180 S3      
317m3030            VIA   -    MD0080PA01X+169213Y+121358X0160Y    R270 S0      
327m3030            PEX3  -M48        A01X+169213Y+121358X0180Y         S1      
317m3031            VIA   -    M      A01X+114747Y+076609X0200Y         S2      
017m3031            VIA   -    M      A18X+114747Y+076609X0260Y         S2      
017m3031                  -    MD0100PA00X+114747Y+076609                       
317m3031            VIA   -    MD0100PA00X+082215Y+075228X0200Y         S0      
327m3031            R5421 -1          A01X+082728Y+070964X0198Y0197R270 S1      
327m3031            R5300 -2   M      A01X+082728Y+071344X0198Y0197R270 S1      
317m3031            VIA   -    MD0100PA00X+143910Y+089856X0200Y         S0      
327m3031            U68   -1          A18X+144014Y+090483X0140Y0610R180 S2      
327m3031            U64   -2          A18X+115717Y+077224X0240Y0420     S2      
327m3032            U320  -7   M      A01X+055387Y+090030X0320Y0750R090 S1      
327m3032            JPEX1 -7          A01X+055387Y+090030X0200Y0600R090 S1      
317m3032            VIA   -    M      A01X+055921Y+089742X0200Y         S2      
017m3032            VIA   -    M      A18X+055921Y+089742X0260Y         S2      
017m3032                  -    MD0100PA00X+055921Y+089742                       
327m3032            R3468 -2          A18X+055338Y+089345X0198Y0197R270 S2      
327m3032            R3462 -2   M      A18X+055229Y+089742X0198Y0197R090 S2      
317m3033            VIA   -    MD0100PA01X+166376Y+138430X0180Y         S0      
317m3033            J9    -L7   D0122PA01X+170350Y+156610X0282Y    R180 S3      
327m3033            C2452 -2          A01X+166386Y+137939X0120Y0150R090 S1      
327m3034            U320  -1   M      A01X+055387Y+087030X0320Y0750R090 S1      
327m3034            JPEX1 -1          A01X+055387Y+087030X0200Y0600R090 S1      
317m3034            VIA   -    M      A01X+056113Y+086929X0200Y         S2      
017m3034            VIA   -    M      A18X+056113Y+086929X0260Y         S2      
017m3034                  -    MD0100PA00X+056113Y+086929                       
327m3034            R3461 -2          A18X+055190Y+086824X0198Y0197R090 S2      
327m3034            R3467 -2   M      A18X+055600Y+086821X0198Y0197R090 S2      
317m3035            J9    -S7   D0122PA01X+170350Y+148933X0282Y    R180 S3      
317m3035            VIA   -    MD0080PA01X+168464Y+120236X0160Y    R270 S0      
327m3035            PEX3  -R46        A01X+168464Y+120236X0180Y         S1      
327m3036            VIA   -    M      A18X+052068Y+088776X0260Y         S2      
327m3036            R3459 -1          A18X+052068Y+088322X0198Y0197R090 S2      
327m3036            U66   -15         A18X+052847Y+088323X0140Y0610R180 S2      
317m3037            VIA   -    MD0100PA01X+168824Y+138430X0180Y         S0      
317m3037            J9    -W2   D0122PA01X+166020Y+146807X0282Y    R180 S3      
327m3037            C2458 -2          A01X+168834Y+137939X0120Y0150R090 S1      
327m3038            U320  -9   M      A01X+051544Y+090530X0320Y0750R270 S1      
327m3038            JPEX1 -9          A01X+051607Y+090530X0200Y0600R090 S1      
317m3038            VIA   -    M      A01X+050902Y+090530X0200Y         S2      
017m3038            VIA   -    M      A18X+050902Y+090530X0260Y         S2      
017m3038                  -    MD0100PA00X+050902Y+090530                       
327m3038            R3463 -2   M      A18X+051375Y+090550X0198Y0197     S2      
327m3038            R3469 -1          A18X+051375Y+089750X0198Y0197R180 S2      
327m3038            R3466 -2   M      A18X+051375Y+090150X0198Y0197     S2      
317m3039            VIA   -    MD0100PA01X+162364Y+136010X0180Y         S0      
317m3039            J9    -L2   D0122PA01X+166020Y+156532X0282Y    R180 S3      
327m3039            C2441 -2          A01X+162354Y+135519X0120Y0150R090 S1      
317SPI_PEX1_CLK     VIA   -    M      A01X+062274Y+115187X0200Y         S2      
017SPI_PEX1_CLK     VIA   -    M      A18X+062274Y+115187X0260Y         S2      
017SPI_PEX1_CLK           -    MD0100PA00X+062274Y+115187                       
327SPI_PEX1_CLK     R3452 -2          A18X+061637Y+114853X0198Y0197R180 S2      
327SPI_PEX1_CLK     PEX1  -AH7        A01X+062461Y+115374X0180Y         S1      
317m3040            J9    -G7   D0122PA01X+170350Y+159169X0282Y    R180 S3      
317m3040            VIA   -    MD0080PA01X+168464Y+124350X0160Y         S0      
327m3040            PEX3  -D46        A01X+168464Y+124350X0180Y         S1      
327m3041            U320  -15         A01X+051544Y+087530X0320Y0750R270 S1      
317m3041            VIA   -    M      A01X+052087Y+087469X0200Y         S2      
017m3041            VIA   -    M      A18X+052087Y+087469X0260Y         S2      
017m3041                  -    MD0100PA00X+052087Y+087469                       
327m3041            JPEX1 -15  M      A01X+051607Y+087530X0200Y0600R090 S1      
327m3041            R3464 -2          A18X+053283Y+087486X0198Y0197     S2      
317m3042            VIA   -    MD0100PA01X+168484Y+138430X0180Y         S0      
317m3042            J9    -X2   D0122PA01X+166020Y+146295X0282Y    R180 S3      
327m3042            C2457 -2          A01X+168474Y+137939X0120Y0150R090 S1      
327m3043            JPEX1 -8          A01X+055387Y+090530X0200Y0600R090 S1      
327m3043            U320  -8   M      A01X+055387Y+090530X0320Y0750R090 S1      
317m3043            VIA   -    M      A01X+054833Y+090530X0200Y         S2      
017m3043            VIA   -    M      A18X+054833Y+090530X0260Y         S2      
017m3043                  -    MD0100PA00X+054833Y+090530                       
327m3043            R3460 -1          A18X+054833Y+090058X0198Y0197R090 S2      
317m3044            VIA   -    MD0100PA01X+169708Y+136010X0180Y         S0      
317m3044            J9    -Y3   D0122PA01X+166886Y+145862X0282Y    R180 S3      
327m3044            C2459 -2          A01X+169698Y+135519X0120Y0150R090 S1      
317SPI_PEX1_CS_N    VIA   -    MD0080PA00X+062274Y+114813X0160Y         S0      
327SPI_PEX1_CS_N    PEX1  -AJ7        A01X+062461Y+115000X0180Y         S1      
327SPI_PEX1_CS_N    VIA   -    M      A18X+062459Y+114627X0260Y         S2      
327SPI_PEX1_CS_N    R3451 -2          A18X+061713Y+113848X0198Y0197R270 S2      
327SPI_PEX1_CS_N    R6158 -1   M      A18X+062087Y+113848X0198Y0197R090 S2      
317m3045            J9    -F1   D0122PA01X+165154Y+159681X0282Y    R180 S3      
317m3045            VIA   -    MD0080PA01X+166220Y+124724X0160Y         S0      
327m3045            PEX3  -C40        A01X+166220Y+124724X0180Y         S1      
317m3046            VIA   -    MD0100PA01X+172496Y+136010X0180Y         S0      
317m3046            J9    -W6   D0122PA01X+169484Y+146807X0282Y    R180 S3      
327m3046            C2466 -2          A01X+172506Y+135519X0120Y0150R090 S1      
317m3047            VIA   -    MD0100PA01X+162704Y+140850X0180Y         S0      
317m3047            J9    -L3   D0122PA01X+166886Y+156610X0282Y    R180 S3      
327m3047            C2444 -2          A01X+162714Y+140359X0120Y0150R090 S1      
317m3048            J9    -F4   D0122PA01X+167752Y+159602X0282Y    R180 S3      
317m3048            VIA   -    MD0080PA01X+167342Y+125098X0160Y         S0      
327m3048            PEX3  -B43        A01X+167342Y+125098X0180Y         S1      
317m3049            VIA   -    MD0100PA01X+161140Y+138430X0180Y         S0      
317m3049            J9    -M1   D0122PA01X+165154Y+156098X0282Y    R180 S3      
327m3049            C2439 -2          A01X+161130Y+137939X0120Y0150R090 S1      
317m3050            VIA   -    MD0100PA01X+167600Y+140850X0180Y         S0      
317m3050            J9    -X1   D0122PA01X+165154Y+146374X0282Y    R180 S3      
327m3050            C2456 -2          A01X+167610Y+140359X0120Y0150R090 S1      
327P12V_NIC0_EN_R   PU22  -11         A01X+003832Y+053649X0110Y0240R090 S1      
317P12V_NIC0_EN_R   VIA   -    M      A01X+003473Y+053491X0200Y    R180 S2      
017P12V_NIC0_EN_R   VIA   -    M      A18X+003473Y+053491X0260Y    R180 S2      
017P12V_NIC0_EN_R         -    MD0100PA00X+003473Y+053491                       
327P12V_NIC0_EN_R   R4444 -2          A01X+003155Y+052773X0198Y0197     S1      
327P12V_NIC0_EN_R   C2853 -1   M      A01X+003155Y+053173X0198Y0197R180 S1      
327m3051            Q1    -5          A18X+023823Y+063568X0170Y0240R270 S2      
317m3051            VIA   -    MD0100PA00X+024019Y+064311X0200Y         S0      
317m3051            VIA   -    MD0100PA00X+024809Y+069111X0200Y         S0      
317m3051            VIA   -    MD0100PA00X+138305Y+089286X0180Y         S0      
327m3051            U6    -C22        A01X+138147Y+089129X0160Y         S1      
317m3051            VIA   -    M      A01X+002769Y+062531X0200Y         S2      
017m3051            VIA   -    M      A18X+002769Y+062531X0260Y         S2      
017m3051                  -    MD0100PA00X+002769Y+062531                       
327m3051            R5830 -2          A01X+003012Y+062531X0198Y0197R180 S1      
317m3051            VIA   -    MD0100PA00X+002582Y+054473X0200Y    R180 S0      
327m3051            R4442 -2          A01X+002840Y+054473X0198Y0197R180 S1      
327P12V_NIC0_OCP    PU22  -9          A01X+003832Y+054042X0110Y0240R090 S1      
317P12V_NIC0_OCP    VIA   -    M      A01X+003436Y+054114X0200Y    R180 S2      
017P12V_NIC0_OCP    VIA   -    M      A18X+003436Y+054114X0260Y    R180 S2      
017P12V_NIC0_OCP          -    MD0100PA00X+003436Y+054114                       
327P12V_NIC0_OCP    PR193 -1          A01X+003155Y+054073X0198Y0197R180 S1      
327P12V_NIC0        VIA   -           A18X+008724Y+056489X0260Y         S2      
327P12V_NIC0        VIA   -           A18X+008581Y+055816X0260Y         S2      
327P12V_NIC0        J20   -B1         A01X+018127Y+057545X0140Y0480R270 S1      
327P12V_NIC0        J20   -B2         A01X+018127Y+057309X0140Y0480R270 S1      
327P12V_NIC0        C846  -1          A01X+015288Y+057906X0400Y0500R270 S1      
327P12V_NIC0        C845  -1          A01X+014588Y+057906X0400Y0500R270 S1      
327P12V_NIC0        J20   -B3         A01X+018127Y+057073X0140Y0480R270 S1      
327P12V_NIC0        J20   -B4         A01X+018127Y+056837X0140Y0480R270 S1      
327P12V_NIC0        J20   -B5         A01X+018127Y+056600X0140Y0480R270 S1      
327P12V_NIC0        J20   -B6         A01X+018127Y+056364X0140Y0480R270 S1      
327P12V_NIC0        R690  -1          A01X+008335Y+057161X0198Y0197R180 S1      
327P12V_NIC0        R682  -1          A01X+008566Y+056085X1150Y1380R180 S1      
327P12V_NIC0        C851  -1          A18X+017952Y+057539X0120Y0150R180 S2      
327P12V_NIC0        C847  -1          A18X+017952Y+056219X0120Y0150R180 S2      
327P12V_NIC0        C848  -1          A18X+017952Y+056539X0120Y0150R180 S2      
327P12V_NIC0        C849  -1          A18X+017952Y+056859X0120Y0150R180 S2      
327P12V_NIC0        C850  -1          A18X+017952Y+057199X0120Y0150R180 S2      
317P12V_NIC0        VIA   -    MD0100PA00X+017710Y+056943X0200Y         S0      
317P12V_NIC0        VIA   -    MD0100PA00X+017478Y+056848X0200Y         S0      
317P12V_NIC0        VIA   -    MD0100PA00X+017503Y+057096X0200Y         S0      
317P12V_NIC0        VIA   -    MD0100PA00X+017269Y+056993X0200Y         S0      
317P12V_NIC0        VIA   -    MD0100PA00X+017134Y+057207X0200Y         S0      
317P12V_NIC0        VIA   -    MD0100PA00X+017738Y+056693X0200Y         S0      
317P12V_NIC0        VIA   -    MD0100PA00X+007813Y+056110X0200Y    R180 S0      
317P12V_NIC0        VIA   -    MD0100PA00X+007813Y+056370X0200Y    R180 S0      
317P12V_NIC0        VIA   -    M      A01X+007813Y+056660X0200Y    R180 S2      
017P12V_NIC0        VIA   -    M      A18X+007813Y+056660X0260Y    R180 S2      
017P12V_NIC0              -    MD0100PA00X+007813Y+056660                       
317P12V_NIC0        VIA   -    MD0100PA00X+007813Y+055850X0200Y         S0      
317P12V_NIC0        VIA   -    MD0100PA00X+007813Y+055590X0200Y         S0      
317P12V_NIC0        VIA   -    MD0100PA00X+007813Y+055330X0200Y         S0      
327P12V_NIC0_SS     PU22  -7          A01X+003832Y+054436X0110Y0240R090 S1      
317P12V_NIC0_SS     VIA   -    M      A01X+003445Y+055273X0200Y    R180 S2      
017P12V_NIC0_SS     VIA   -    M      A18X+003445Y+055273X0260Y    R180 S2      
017P12V_NIC0_SS           -    MD0100PA00X+003445Y+055273                       
327P12V_NIC0_SS     PC314 -1          A01X+003155Y+055273X0198Y0197R180 S1      
327m3052            PU22  -8          A01X+003832Y+054239X0110Y0240R090 S1      
317m3052            VIA   -    M      A01X+003442Y+054655X0200Y    R180 S2      
017m3052            VIA   -    M      A18X+003442Y+054655X0260Y    R180 S2      
017m3052                  -    MD0100PA00X+003442Y+054655                       
327m3052            R4442 -1          A01X+003155Y+054473X0198Y0197R180 S1      
327m3052            R853  -2   M      A01X+003155Y+054873X0198Y0197     S1      
327m3053            JPEX3 -16  M      A01X+143025Y+087030X0200Y0600R090 S1      
327m3053            U321  -16         A01X+142962Y+087030X0320Y0750R270 S1      
317m3053            VIA   -    M      A01X+143508Y+086948X0200Y         S2      
017m3053            VIA   -    M      A18X+143508Y+086948X0260Y         S2      
017m3053                  -    MD0100PA00X+143508Y+086948                       
327m3053            R3503 -2          A18X+143022Y+087103X0198Y0197R090 S2      
317m3054            VIA   -    M      A01X+146250Y+090530X0200Y         S2      
017m3054            VIA   -    M      A18X+146250Y+090530X0260Y         S2      
017m3054                  -    MD0100PA00X+146250Y+090530                       
327m3054            JPEX3 -8   M      A01X+146804Y+090530X0200Y0600R090 S1      
327m3054            U321  -8          A01X+146804Y+090530X0320Y0750R090 S1      
327m3054            R3499 -1          A18X+146250Y+090058X0198Y0197R090 S2      
327m3055            JPEX3 -1          A01X+146804Y+087030X0200Y0600R090 S1      
327m3055            U321  -1   M      A01X+146804Y+087030X0320Y0750R090 S1      
317m3055            VIA   -    M      A01X+147488Y+086821X0200Y         S2      
017m3055            VIA   -    M      A18X+147488Y+086821X0260Y         S2      
017m3055                  -    MD0100PA00X+147488Y+086821                       
327m3055            R3498 -2          A18X+146608Y+086824X0198Y0197R090 S2      
327m3055            R3505 -2   M      A18X+147017Y+086821X0198Y0197R090 S2      
327m3056            JPEX3 -9          A01X+143025Y+090530X0200Y0600R090 S1      
327m3056            U321  -9   M      A01X+142962Y+090530X0320Y0750R270 S1      
317m3056            VIA   -    M      A01X+142319Y+090530X0200Y         S2      
017m3056            VIA   -    M      A18X+142319Y+090530X0260Y         S2      
017m3056                  -    MD0100PA00X+142319Y+090530                       
327m3056            R3507 -1          A18X+142792Y+089750X0198Y0197R180 S2      
327m3056            R3504 -2   M      A18X+142792Y+090150X0198Y0197     S2      
327m3056            R3501 -2   M      A18X+142792Y+090550X0198Y0197     S2      
327m3057            R3506 -2          A18X+146756Y+089345X0198Y0197R270 S2      
327m3057            R3500 -2   M      A18X+146646Y+089742X0198Y0197R090 S2      
317m3057            VIA   -    M      A01X+147339Y+089742X0200Y         S2      
017m3057            VIA   -    M      A18X+147339Y+089742X0260Y         S2      
017m3057                  -    MD0100PA00X+147339Y+089742                       
327m3057            JPEX3 -7          A01X+146804Y+090030X0200Y0600R090 S1      
327m3057            U321  -7   M      A01X+146804Y+090030X0320Y0750R090 S1      
317m3058            VIA   -    MD0080PA01X+120886Y+123602X0160Y    R270 S0      
317m3058            VIA   -    MD0100PA01X+107035Y+137238X0180Y         S0      
327m3058            C2344 -1          A01X+107045Y+137729X0120Y0150R090 S1      
327m3058            PEX2  -F41        A01X+120886Y+123602X0180Y         S1      
327m3059            C2365 -1          A01X+115253Y+140149X0120Y0150R090 S1      
317m3059            VIA   -    MD0100PA01X+115263Y+139658X0180Y         S0      
317m3059            VIA   -    MD0080PA01X+121634Y+120984X0160Y    R270 S0      
327m3059            PEX2  -N43        A01X+121634Y+120984X0180Y         S1      
327m3060            C2363 -1          A01X+115253Y+135309X0120Y0150R090 S1      
317m3060            VIA   -    MD0100PA01X+115263Y+134819X0180Y         S0      
317m3060            VIA   -    MD0080PA01X+120886Y+121358X0160Y    R270 S0      
327m3060            PEX2  -M41        A01X+120886Y+121358X0180Y         S1      
327m3061            C2367 -1          A01X+116477Y+137729X0120Y0150R090 S1      
317m3061            VIA   -    MD0100PA01X+116487Y+137238X0180Y         S0      
317m3061            VIA   -    MD0080PA01X+120886Y+120610X0160Y    R270 S0      
327m3061            PEX2  -P41        A01X+120886Y+120610X0180Y         S1      
327m3062            R3399 -1          A01X+117548Y+084222X0198Y0197R270 S1      
317m3062            VIA   -    M      A01X+118434Y+085107X0200Y         S2      
017m3062            VIA   -    M      A18X+118434Y+085107X0260Y         S2      
017m3062                  -    MD0100PA00X+118434Y+085107                       
327m3062            U68   -6          A18X+145264Y+090483X0140Y0610R180 S2      
317m3062            VIA   -    MD0100PA00X+145129Y+089855X0200Y         S0      
327m3063            C2357 -1          A01X+112805Y+135309X0120Y0150R090 S1      
317m3063            VIA   -    MD0100PA01X+112815Y+134819X0180Y         S0      
317m3063            VIA   -    MD0080PA01X+123504Y+123976X0160Y         S0      
327m3063            PEX2  -E48        A01X+123504Y+123976X0180Y         S1      
327m3064            R3398 -1          A01X+117948Y+084222X0198Y0197R270 S1      
317m3064            VIA   -    M      A01X+119097Y+084870X0200Y         S2      
017m3064            VIA   -    M      A18X+119097Y+084870X0260Y         S2      
017m3064                  -    MD0100PA00X+119097Y+084870                       
327m3064            U68   -3          A18X+144514Y+090483X0140Y0610R180 S2      
317m3064            VIA   -    MD0100PA00X+144323Y+089901X0200Y         S0      
327m3065            C2364 -1          A01X+115613Y+135309X0120Y0150R090 S1      
317m3065            VIA   -    MD0100PA01X+115603Y+134819X0180Y         S0      
317m3065            VIA   -    MD0080PA01X+121260Y+121358X0160Y    R270 S0      
327m3065            PEX2  -M42        A01X+121260Y+121358X0180Y         S1      
317m3066            VIA   -    MD0100PA00X+144537Y+089189X0200Y         S0      
327m3066            U68   -13         A18X+144764Y+088323X0140Y0610R180 S2      
327m3066            R3401 -1          A01X+115948Y+084222X0198Y0197R270 S1      
317m3066            VIA   -    M      A01X+119021Y+085682X0200Y         S2      
017m3066            VIA   -    M      A18X+119021Y+085682X0260Y         S2      
017m3066                  -    MD0100PA00X+119021Y+085682                       
327m3067            R3400 -1          A01X+116748Y+084222X0198Y0197R270 S1      
317m3067            VIA   -    M      A01X+118301Y+085655X0200Y         S2      
017m3067            VIA   -    M      A18X+118301Y+085655X0260Y         S2      
017m3067                  -    MD0100PA00X+118301Y+085655                       
317m3067            VIA   -    MD0100PA00X+145722Y+088876X0200Y         S0      
327m3067            U68   -10         A18X+145514Y+088323X0140Y0610R180 S2      
317m3068            VIA   -    MD0080PA01X+122008Y+122854X0160Y    R270 S0      
317m3068            VIA   -    MD0100PA01X+109483Y+137238X0180Y         S0      
327m3068            PEX2  -H44        A01X+122008Y+122854X0180Y         S1      
327m3068            C2350 -1          A01X+109493Y+137729X0120Y0150R090 S1      
327m3069            C2361 -1          A01X+114029Y+137729X0120Y0150R090 S1      
317m3069            VIA   -    MD0100PA01X+114039Y+137238X0180Y         S0      
317m3069            VIA   -    MD0080PA01X+121634Y+121732X0160Y    R270 S0      
327m3069            PEX2  -L43        A01X+121634Y+121732X0180Y         S1      
327m3070            R3396 -1          A01X+116348Y+084222X0198Y0197R270 S1      
317m3070            VIA   -    M      A01X+116154Y+084417X0200Y         S2      
017m3070            VIA   -    M      A18X+116154Y+084417X0260Y         S2      
017m3070                  -    MD0100PA00X+116154Y+084417                       
327m3070            U67   -10         A18X+099805Y+088323X0140Y0610R180 S2      
327m3071            U66   -10         A18X+054097Y+088323X0140Y0610R180 S2      
317m3071            VIA   -    MD0100PA00X+054097Y+087836X0200Y         S0      
327m3071            R3408 -1          A01X+065327Y+076714X0198Y0197     S1      
317m3071            VIA   -    M      A01X+058310Y+076714X0200Y         S2      
017m3071            VIA   -    M      A18X+058310Y+076714X0260Y         S2      
017m3071                  -    MD0100PA00X+058310Y+076714                       
327m3072            U67   -13         A18X+099055Y+088323X0140Y0610R180 S2      
317m3072            VIA   -    M      A01X+115323Y+084858X0200Y         S2      
017m3072            VIA   -    M      A18X+115323Y+084858X0260Y         S2      
017m3072                  -    MD0100PA00X+115323Y+084858                       
327m3072            R3397 -1          A01X+115548Y+084222X0198Y0197R270 S1      
327m3073            R3407 -1          A01X+065327Y+077914X0198Y0197     S1      
317m3073            VIA   -    M      A01X+058591Y+077847X0200Y         S2      
017m3073            VIA   -    M      A18X+058591Y+077847X0260Y         S2      
017m3073                  -    MD0100PA00X+058591Y+077847                       
327m3073            U66   -6          A18X+053847Y+090483X0140Y0610R180 S2      
317m3073            VIA   -    MD0100PA00X+053728Y+089794X0200Y         S0      
327m3074            R3394 -1          A01X+118348Y+084222X0198Y0197R270 S1      
317m3074            VIA   -    M      A01X+118552Y+084425X0200Y         S2      
017m3074            VIA   -    M      A18X+118552Y+084425X0260Y         S2      
017m3074                  -    MD0100PA00X+118552Y+084425                       
327m3074            U67   -3          A18X+098805Y+090483X0140Y0610R180 S2      
327m3075            U66   -3          A18X+053097Y+090483X0140Y0610R180 S2      
317m3075            VIA   -    MD0100PA00X+052898Y+089835X0200Y         S0      
317m3075            VIA   -    M      A01X+058866Y+079034X0200Y    R090 S2      
017m3075            VIA   -    M      A18X+058866Y+079034X0260Y    R090 S2      
017m3075                  -    MD0100PA00X+058866Y+079034                       
327m3075            R3406 -1          A01X+065327Y+078714X0198Y0197     S1      
317m3076            VIA   -    MD0080PA01X+122382Y+123228X0160Y    R270 S0      
317m3076            VIA   -    MD0100PA01X+110367Y+134819X0180Y         S0      
327m3076            PEX2  -G45        A01X+122382Y+123228X0180Y         S1      
327m3076            C2351 -1          A01X+110357Y+135309X0120Y0150R090 S1      
327m3077            U67   -6          A18X+099555Y+090483X0140Y0610R180 S2      
317m3077            VIA   -    M      A01X+116358Y+085077X0200Y         S2      
017m3077            VIA   -    M      A18X+116358Y+085077X0260Y         S2      
017m3077                  -    MD0100PA00X+116358Y+085077                       
327m3077            R3395 -1          A01X+117148Y+084222X0198Y0197R270 S1      
327m3078            U66   -13         A18X+053347Y+088323X0140Y0610R180 S2      
317m3078            VIA   -    MD0100PA00X+053347Y+087853X0200Y         S0      
327m3078            R3409 -1          A01X+065327Y+076314X0198Y0197     S1      
317m3078            VIA   -    M      A01X+057827Y+076356X0200Y         S2      
017m3078            VIA   -    M      A18X+057827Y+076356X0260Y         S2      
017m3078                  -    MD0100PA00X+057827Y+076356                       
327PWRGD_P3V3       PU21  -8          A01X+045461Y+049569X0110Y0240R270 S1      
317PWRGD_P3V3       VIA   -    M      A01X+045995Y+049684X0200Y         S2      
017PWRGD_P3V3       VIA   -    M      A18X+045995Y+049684X0260Y         S2      
017PWRGD_P3V3             -    MD0100PA00X+045995Y+049684                       
327PWRGD_P3V3       R4440 -1          A01X+046283Y+049967X0198Y0197     S1      
327PWRGD_P3V3       R852  -2   M      A01X+046283Y+049567X0198Y0197R180 S1      
327P3V3_SS          PU21  -7          A01X+045461Y+049372X0110Y0240R270 S1      
317P3V3_SS          VIA   -    M      A01X+045993Y+049167X0200Y         S2      
017P3V3_SS          VIA   -    M      A18X+045993Y+049167X0260Y         S2      
017P3V3_SS                -    MD0100PA00X+045993Y+049167                       
327P3V3_SS          PC303 -1          A01X+046283Y+049167X0198Y0197     S1      
327P3V3_OCP         PU21  -9          A01X+045461Y+049766X0110Y0240R270 S1      
317P3V3_OCP         VIA   -    M      A01X+046054Y+050190X0200Y         S2      
017P3V3_OCP         VIA   -    M      A18X+046054Y+050190X0260Y         S2      
017P3V3_OCP               -    MD0100PA00X+046054Y+050190                       
327P3V3_OCP         PR190 -1          A01X+046283Y+050367X0198Y0197     S1      
327m3079            C2359 -1          A01X+112805Y+140149X0120Y0150R090 S1      
317m3079            VIA   -    MD0100PA01X+112815Y+139658X0180Y         S0      
317m3079            VIA   -    MD0080PA01X+123504Y+122854X0160Y    R270 S0      
327m3079            PEX2  -H48        A01X+123504Y+122854X0180Y         S1      
327PWRGD_P3V3_R     R5826 -2          A01X+048148Y+043749X0198Y0197R090 S1      
317PWRGD_P3V3_R     VIA   -    M      A01X+048148Y+043990X0200Y         S2      
017PWRGD_P3V3_R     VIA   -    M      A18X+048148Y+043990X0260Y         S2      
017PWRGD_P3V3_R           -    MD0100PA00X+048148Y+043990                       
317PWRGD_P3V3_R     VIA   -    MD0100PA00X+046856Y+049967X0200Y         S0      
327PWRGD_P3V3_R     R4440 -2          A01X+046598Y+049967X0198Y0197     S1      
317PWRGD_P3V3_R     VIA   -    MD0100PA00X+047365Y+082123X0200Y         S0      
327PWRGD_P3V3_R     U6    -E4         A01X+132478Y+088499X0160Y         S1      
317PWRGD_P3V3_R     VIA   -    MD0100PA00X+132320Y+088656X0180Y         S0      
327m3080            VIA   -    M      A01X+115948Y+082064X0300Y         S1      
327m3080            R3368 -2          A01X+115948Y+082557X0198Y0197R270 S1      
327m3080            U63   -6          A01X+116105Y+080834X0140Y0630R180 S1      
327m3081            VIA   -    M      A01X+116048Y+077564X0300Y         S1      
327m3081            R3392 -2          A01X+116048Y+077072X0198Y0197R090 S1      
327m3081            U63   -12         A01X+116361Y+078629X0140Y0630R180 S1      
317m3082            VIA   -    MD0080PA01X+121260Y+122480X0160Y    R270 S0      
317m3082            VIA   -    MD0100PA01X+107919Y+134819X0180Y         S0      
327m3082            C2345 -1          A01X+107909Y+135309X0120Y0150R090 S1      
327m3082            PEX2  -J42        A01X+121260Y+122480X0180Y         S1      
327m3083            VIA   -    M      A01X+118348Y+082064X0300Y         S1      
327m3083            U63   -3          A01X+116872Y+080834X0140Y0630R180 S1      
327m3083            R3365 -2          A01X+118348Y+082557X0198Y0197R270 S1      
327m3084            VIA   -    M      A01X+116498Y+077914X0300Y         S1      
327m3084            R3391 -2          A01X+116448Y+077072X0198Y0197R090 S1      
327m3084            U63   -13         A01X+116617Y+078629X0140Y0630R180 S1      
327m3085            VIA   -    M      A01X+117548Y+082014X0300Y         S1      
327m3085            U63   -4          A01X+116617Y+080834X0140Y0630R180 S1      
327m3085            R3366 -2          A01X+117548Y+082557X0198Y0197R270 S1      
327m3086            VIA   -    M      A01X+116898Y+077564X0300Y         S1      
327m3086            U63   -14         A01X+116872Y+078629X0140Y0630R180 S1      
327m3086            R3390 -2          A01X+116848Y+077058X0198Y0197R090 S1      
317m3087            VIA   -    MD0080PA01X+121634Y+123228X0160Y    R270 S0      
317m3087            VIA   -    MD0100PA01X+107919Y+139658X0180Y    R180 S0      
327m3087            C2347 -1          A01X+107909Y+140149X0120Y0150R090 S1      
327m3087            PEX2  -G43        A01X+121634Y+123228X0180Y         S1      
327m3088            VIA   -    M      A01X+116748Y+082064X0300Y         S1      
327m3088            R3367 -2          A01X+116748Y+082557X0198Y0197R270 S1      
327m3088            U63   -5          A01X+116361Y+080834X0140Y0630R180 S1      
327m3089            R3393 -1          A01X+115648Y+077072X0198Y0197R270 S1      
327m3089            VIA   -    M      A01X+115648Y+077914X0300Y         S1      
327m3089            U63   -11         A01X+116105Y+078629X0140Y0630R180 S1      
327m3090            VIA   -    M      A01X+116748Y+083414X0300Y         S1      
327m3090            R3396 -2          A01X+116348Y+083907X0198Y0197R270 S1      
327m3090            R3400 -2   M      A01X+116748Y+083907X0198Y0197R270 S1      
327m3090            R3367 -1          A01X+116748Y+082872X0198Y0197R270 S1      
317m3091            VIA   -    MD0080PA01X+121634Y+123602X0160Y    R270 S0      
317m3091            VIA   -    MD0100PA01X+108259Y+139658X0180Y    R180 S0      
327m3091            PEX2  -F43        A01X+121634Y+123602X0180Y         S1      
327m3091            C2348 -1          A01X+108269Y+140149X0120Y0150R090 S1      
327m3092            VIA   -    M      A01X+117548Y+083364X0300Y         S1      
327m3092            R3395 -2          A01X+117148Y+083907X0198Y0197R270 S1      
327m3092            R3399 -2   M      A01X+117548Y+083907X0198Y0197R270 S1      
327m3092            R3366 -1          A01X+117548Y+082872X0198Y0197R270 S1      
317m3093            VIA   -    MD0100PA01X+111931Y+137238X0180Y         S0      
327m3093            C2356 -1          A01X+111941Y+137729X0120Y0150R090 S1      
317m3093            VIA   -    MD0080PA01X+123130Y+123602X0160Y    R270 S0      
327m3093            PEX2  -F47        A01X+123130Y+123602X0180Y         S1      
327m3094            VIA   -    M      A01X+115948Y+083414X0300Y         S1      
327m3094            R3397 -2          A01X+115548Y+083907X0198Y0197R270 S1      
327m3094            R3401 -2   M      A01X+115948Y+083907X0198Y0197R270 S1      
327m3094            R3368 -1          A01X+115948Y+082872X0198Y0197R270 S1      
327m3095            C2368 -1          A01X+116837Y+137729X0120Y0150R090 S1      
317m3095            VIA   -    MD0100PA01X+116827Y+137238X0180Y         S0      
317m3095            VIA   -    MD0080PA01X+121260Y+120610X0160Y    R270 S0      
327m3095            PEX2  -P42        A01X+121260Y+120610X0180Y         S1      
327m3096            VIA   -    M      A01X+118348Y+083414X0300Y         S1      
327m3096            R3398 -2          A01X+117948Y+083907X0198Y0197R270 S1      
327m3096            R3394 -2   M      A01X+118348Y+083907X0198Y0197R270 S1      
327m3096            R3365 -1          A01X+118348Y+082872X0198Y0197R270 S1      
317m3097            VIA   -    MD0080PA01X+122382Y+123602X0160Y    R270 S0      
317m3097            VIA   -    MD0100PA01X+110707Y+134819X0180Y         S0      
327m3097            PEX2  -F45        A01X+122382Y+123602X0180Y         S1      
327m3097            C2352 -1          A01X+110717Y+135309X0120Y0150R090 S1      
317m3098            VIA   -    MD0080PA01X+120512Y+122480X0160Y    R270 S0      
317m3098            VIA   -    MD0100PA01X+105471Y+134819X0180Y         S0      
327m3098            C2341 -1          A01X+105461Y+135309X0120Y0150R090 S1      
327m3098            PEX2  -J40        A01X+120512Y+122480X0180Y         S1      
317m3099            VIA   -    MD0080PA01X+122756Y+122480X0160Y    R270 S0      
317m3099            VIA   -    MD0100PA01X+110367Y+139658X0180Y         S0      
327m3099            PEX2  -J46        A01X+122756Y+122480X0180Y         S1      
327m3099            C2353 -1          A01X+110357Y+140149X0120Y0150R090 S1      
317VDDA_SENSE       VIA   -    MD0080PA00X+110974Y+114065X0160Y         S0      
317VDDA_SENSE       VIA   -    MD0080PA00X+156683Y+114065X0160Y         S0      
317VDDA_SENSE       VIA   -    MD0080PA00X+019557Y+114065X0160Y         S0      
317VDDA_SENSE       VIA   -    MD0080PA00X+065266Y+114065X0160Y         S0      
317VDDA_SENSE       VIA   -    MD0100PA00X+107991Y+104526X0200Y         S0      
317VDDA_SENSE       VIA   -    M      A01X+153196Y+105085X0200Y         S2      
017VDDA_SENSE       VIA   -    M      A18X+153196Y+105085X0260Y         S2      
017VDDA_SENSE             -    MD0100PA00X+153196Y+105085                       
327VDDA_SENSE       PEX0  -AL15       A01X+019744Y+114252X0180Y         S1      
317VDDA_SENSE       VIA   -    MD0100PA00X+016063Y+105356X0200Y         S0      
327VDDA_SENSE       PEX1  -AL15       A01X+065453Y+114252X0180Y         S1      
317VDDA_SENSE       VIA   -    MD0100PA00X+062148Y+103048X0200Y         S0      
327VDDA_SENSE       PEX2  -AL15       A01X+111161Y+114252X0180Y         S1      
327VDDA_SENSE       PEX3  -AL15       A01X+156870Y+114252X0180Y         S1      
327m3100            C2366 -1          A01X+115613Y+140149X0120Y0150R090 S1      
317m3100            VIA   -    MD0100PA01X+115603Y+139658X0180Y         S0      
317m3100            VIA   -    MD0080PA01X+122008Y+120984X0160Y    R270 S0      
327m3100            PEX2  -N44        A01X+122008Y+120984X0180Y         S1      
317m3101            VIA   -    MD0080PA01X+120512Y+122854X0160Y    R270 S0      
317m3101            VIA   -    MD0100PA01X+105811Y+134819X0180Y         S0      
327m3101            PEX2  -H40        A01X+120512Y+122854X0180Y         S1      
327m3101            C2342 -1          A01X+105821Y+135309X0120Y0150R090 S1      
317m3102            VIA   -    MD0080PA01X+120886Y+123228X0160Y    R270 S0      
317m3102            VIA   -    MD0100PA01X+106695Y+137238X0180Y         S0      
327m3102            C2343 -1          A01X+106685Y+137729X0120Y0150R090 S1      
327m3102            PEX2  -G41        A01X+120886Y+123228X0180Y         S1      
317m3103            VIA   -    MD0080PA01X+122008Y+120236X0160Y    R270 S0      
317m3103            VIA   -    MD0100PA01X+118051Y+134819X0180Y         S0      
327m3103            PEX2  -R44        A01X+122008Y+120236X0180Y         S1      
327m3103            C2370 -1          A01X+118061Y+135309X0120Y0150R090 S1      
317m3104            VIA   -    MD0100PA01X+014955Y+140850X0180Y         S0      
317m3104            J3    -X2   D0122PA01X+011854Y+146295X0282Y    R180 S3      
327m3104            C2170 -2          A01X+014945Y+140359X0120Y0150R090 S1      
317m3105            VIA   -    MD0080PA01X+122756Y+122854X0160Y    R270 S0      
317m3105            VIA   -    MD0100PA01X+110707Y+139658X0180Y         S0      
327m3105            PEX2  -H46        A01X+122756Y+122854X0180Y         S1      
327m3105            C2354 -1          A01X+110717Y+140149X0120Y0150R090 S1      
317m3106            VIA   -    MD0100PA01X+010399Y+140850X0180Y         S0      
317m3106            J3    -K4   D0122PA01X+013587Y+157043X0282Y    R180 S3      
327m3106            C2159 -2          A01X+010409Y+140359X0120Y0150R090 S1      
317m3107            J3    -R1   D0122PA01X+010988Y+149445X0282Y    R180 S3      
317m3107            VIA   -    MD0080PA01X+032461Y+124724X0160Y    R270 S0      
327m3107            PEX0  -C49        A01X+032461Y+124724X0180Y         S1      
327m3108            C2360 -1          A01X+113165Y+140149X0120Y0150R090 S1      
317m3108            VIA   -    MD0100PA01X+113155Y+139658X0180Y         S0      
317m3108            VIA   -    MD0080PA01X+123878Y+122854X0160Y    R270 S0      
327m3108            PEX2  -H49        A01X+123878Y+122854X0180Y         S1      
317m3109            J3    -Q6   D0122PA01X+015319Y+149878X0282Y    R180 S3      
317m3109            VIA   -    MD0080PA01X+032461Y+120610X0160Y    R270 S0      
327m3109            PEX0  -P49        A01X+032461Y+120610X0180Y         S1      
317m3110            VIA   -    MD0080PA01X+121260Y+122854X0160Y    R270 S0      
317m3110            VIA   -    MD0100PA01X+108259Y+134819X0180Y         S0      
327m3110            C2346 -1          A01X+108269Y+135309X0120Y0150R090 S1      
327m3110            PEX2  -H42        A01X+121260Y+122854X0180Y         S1      
327m3111            U64   -1          A18X+116091Y+077224X0240Y0420     S2      
317m3111            VIA   -    MD0100PA00X+114896Y+074725X0200Y         S0      
317m3111            VIA   -    MD0100PA00X+102692Y+071977X0200Y         S0      
317m3111            VIA   -    M      A01X+083608Y+070962X0200Y         S2      
017m3111            VIA   -    M      A18X+083608Y+070962X0260Y         S2      
017m3111                  -    MD0100PA00X+083608Y+070962                       
327m3111            R5299 -2          A01X+083929Y+071342X0198Y0197R270 S1      
327m3111            R5420 -1   M      A01X+083929Y+070962X0198Y0197R270 S1      
327m3111            U67   -1          A18X+098305Y+090483X0140Y0610R180 S2      
317m3111            VIA   -    MD0100PA00X+098278Y+091000X0200Y         S0      
317m3112            J3    -Q2   D0122PA01X+011854Y+149878X0282Y    R180 S3      
317m3112            VIA   -    MD0080PA01X+032461Y+122106X0160Y    R090 S0      
327m3112            PEX0  -K49        A01X+032461Y+122106X0180Y         S1      
317m3113            VIA   -    MD0080PA01X+121634Y+120236X0160Y    R270 S0      
317m3113            VIA   -    MD0100PA01X+117711Y+134819X0180Y         S0      
327m3113            C2369 -1          A01X+117701Y+135309X0120Y0150R090 S1      
327m3113            PEX2  -R43        A01X+121634Y+120236X0180Y         S1      
317m3114            J3    -F4   D0122PA01X+013587Y+159602X0282Y    R180 S3      
317m3114            VIA   -    MD0080PA01X+030216Y+125098X0160Y         S0      
327m3114            PEX0  -B43        A01X+030216Y+125098X0180Y         S1      
317m3115            VIA   -    MD0080PA01X+122008Y+122480X0160Y    R270 S0      
317m3115            VIA   -    MD0100PA01X+109143Y+137238X0180Y         S0      
327m3115            C2349 -1          A01X+109133Y+137729X0120Y0150R090 S1      
327m3115            PEX2  -J44        A01X+122008Y+122480X0180Y         S1      
317m3116            VIA   -    MD0100PA01X+009175Y+138430X0180Y         S0      
317m3116            J3    -K2   D0122PA01X+011854Y+157043X0282Y    R180 S3      
327m3116            C2155 -2          A01X+009185Y+137939X0120Y0150R090 S1      
327m3117            C2371 -1          A01X+117701Y+140149X0120Y0150R090 S1      
317m3117            VIA   -    MD0100PA01X+117711Y+139658X0180Y         S0      
317m3117            VIA   -    MD0080PA01X+120886Y+119862X0160Y    R270 S0      
327m3117            PEX2  -T41        A01X+120886Y+119862X0180Y         S1      
317m3118            VIA   -    MD0100PA01X+011623Y+138430X0180Y         S0      
317m3118            J3    -L5   D0122PA01X+014453Y+156610X0282Y    R180 S3      
327m3118            C2161 -2          A01X+011633Y+137939X0120Y0150R090 S1      
317m3119            J3    -E4   D0122PA01X+013587Y+160114X0282Y    R180 S3      
317m3119            VIA   -    MD0080PA01X+030216Y+125472X0160Y         S0      
327m3119            PEX0  -A43        A01X+030216Y+125472X0180Y         S1      
327m3120            PU54  -8          A01X+003008Y+022506X0110Y0240     S1      
317m3120            VIA   -    M      A01X+003160Y+022782X0200Y    R090 S2      
017m3120            VIA   -    M      A18X+003160Y+022782X0260Y    R090 S2      
017m3120                  -    MD0100PA00X+003160Y+022782                       
327m3120            R4482 -1          A01X+003075Y+024168X0198Y0197     S1      
327m3120            R886  -2   M      A01X+003220Y+023298X0198Y0197R270 S1      
317m3121            J3    -G7   D0122PA01X+016185Y+159169X0282Y    R180 S3      
317m3121            VIA   -    MD0080PA01X+031338Y+124350X0160Y         S0      
327m3121            PEX0  -D46        A01X+031338Y+124350X0180Y         S1      
317m3122            VIA   -    MD0100PA01X+011623Y+137238X0180Y         S0      
317m3122            VIA   -    MD0080PA01X+030590Y+122854X0160Y    R270 S0      
327m3122            PEX0  -H44        A01X+030590Y+122854X0180Y         S1      
327m3122            C2161 -1          A01X+011633Y+137729X0120Y0150R090 S1      
327P3V3_SSD0_SS     PU54  -7          A01X+003205Y+022506X0110Y0240     S1      
317P3V3_SSD0_SS     VIA   -    M      A01X+003618Y+023012X0200Y    R090 S2      
017P3V3_SSD0_SS     VIA   -    M      A18X+003618Y+023012X0260Y    R090 S2      
017P3V3_SSD0_SS           -    MD0100PA00X+003618Y+023012                       
327P3V3_SSD0_SS     PC506 -1          A01X+003620Y+023298X0198Y0197R090 S1      
317m3123            VIA   -    MD0100PA01X+017403Y+140850X0180Y         S0      
317m3123            J3    -Y5   D0122PA01X+014453Y+145862X0282Y    R180 S3      
327m3123            C2176 -2          A01X+017393Y+140359X0120Y0150R090 S1      
317m3124            VIA   -    MD0100PA01X+012847Y+134819X0180Y         S0      
317m3124            VIA   -    MD0080PA01X+030964Y+123602X0160Y    R270 S0      
327m3124            PEX0  -F45        A01X+030964Y+123602X0180Y         S1      
327m3124            C2163 -1          A01X+012857Y+135309X0120Y0150R090 S1      
327m3125            C2372 -1          A01X+118061Y+140149X0120Y0150R090 S1      
317m3125            VIA   -    MD0100PA01X+118051Y+139658X0180Y         S0      
317m3125            VIA   -    MD0080PA01X+121260Y+119862X0160Y    R270 S0      
327m3125            PEX2  -T42        A01X+121260Y+119862X0180Y         S1      
327P3V3_SSD0_OCP    PU54  -9          A01X+002811Y+022506X0110Y0240     S1      
317P3V3_SSD0_OCP    VIA   -    M      A01X+002734Y+023056X0200Y    R090 S2      
017P3V3_SSD0_OCP    VIA   -    M      A18X+002734Y+023056X0260Y    R090 S2      
017P3V3_SSD0_OCP          -    MD0100PA00X+002734Y+023056                       
327P3V3_SSD0_OCP    PR257 -1          A01X+002797Y+023296X0198Y0197R090 S1      
317m3126            J3    -G1   D0122PA01X+010988Y+159169X0282Y    R180 S3      
317m3126            VIA   -    MD0080PA01X+029094Y+124350X0160Y         S0      
327m3126            PEX0  -D40        A01X+029094Y+124350X0180Y         S1      
317m3127            J3    -F5   D0122PA01X+014453Y+159681X0282Y    R180 S3      
317m3127            VIA   -    MD0080PA01X+030590Y+124724X0160Y         S0      
327m3127            PEX0  -C44        A01X+030590Y+124724X0180Y         S1      
317m3128            VIA   -    MD0100PA01X+012507Y+139658X0180Y         S0      
317m3128            VIA   -    MD0080PA01X+031338Y+122480X0160Y    R270 S0      
327m3128            PEX0  -J46        A01X+031338Y+122480X0180Y         S1      
327m3128            C2164 -1          A01X+012497Y+140149X0120Y0150R090 S1      
327m3129            C2362 -1          A01X+114389Y+137729X0120Y0150R090 S1      
317m3129            VIA   -    MD0100PA01X+114379Y+137238X0180Y         S0      
317m3129            VIA   -    MD0080PA01X+122008Y+121732X0160Y    R270 S0      
327m3129            PEX2  -L44        A01X+122008Y+121732X0180Y         S1      
317m3130            VIA   -    MD0100PA00X+133895Y+088341X0180Y         S0      
327m3130            U6    -F9         A01X+134053Y+088184X0160Y         S1      
317m3130            VIA   -    MD0100PA00X+001372Y+025938X0200Y         S0      
317m3130            VIA   -    M      A01X+001550Y+028854X0200Y         S2      
017m3130            VIA   -    M      A18X+001550Y+028854X0260Y         S2      
017m3130                  -    MD0100PA00X+001550Y+028854                       
317m3130            VIA   -    MD0100PA00X+003390Y+024430X0200Y    R090 S0      
317m3130            VIA   -    MD0100PA00X+011350Y+079686X0200Y         S0      
327m3130            R4482 -2          A01X+003390Y+024168X0198Y0197     S1      
327m3130            U383  -1          A01X+001908Y+028704X0240Y0240     S1      
327m3130            R5870 -2          A01X+001372Y+026208X0198Y0197R180 S1      
317m3131            VIA   -    MD0100PA01X+020191Y+136010X0180Y         S0      
317m3131            J3    -X7   D0122PA01X+016185Y+146374X0282Y    R180 S3      
327m3131            C2181 -2          A01X+020201Y+135519X0120Y0150R090 S1      
327m3132            C2358 -1          A01X+113165Y+135309X0120Y0150R090 S1      
317m3132            VIA   -    MD0100PA01X+113155Y+134819X0180Y         S0      
317m3132            VIA   -    MD0080PA01X+123878Y+123976X0160Y         S0      
327m3132            PEX2  -E49        A01X+123878Y+123976X0180Y         S1      
327m3133            R3446 -1          A18X+009496Y+087139X0198Y0197R090 S2      
317m3133            VIA   -    M      A01X+009000Y+087139X0200Y         S2      
017m3133            VIA   -    M      A18X+009000Y+087139X0260Y         S2      
017m3133                  -    MD0100PA00X+009000Y+087139                       
317m3133            VIA   -    MD0100PA00X+016055Y+104928X0200Y         S0      
327m3133            R3434 -1          A18X+015630Y+113533X0198Y0197R270 S2      
317m3134            VIA   -    MD0100PA01X+008835Y+138430X0180Y         S0      
317m3134            J3    -L2   D0122PA01X+011854Y+156532X0282Y    R180 S3      
327m3134            C2154 -2          A01X+008825Y+137939X0120Y0150R090 S1      
327m3135            C2172 -1          A01X+016169Y+137729X0120Y0150R090 S1      
317m3135            VIA   -    MD0100PA01X+016179Y+137238X0180Y         S0      
317m3135            VIA   -    MD0080PA01X+030216Y+121732X0160Y    R270 S0      
327m3135            PEX0  -L43        A01X+030216Y+121732X0180Y         S1      
317m3136            VIA   -    MD0100PA01X+111591Y+137238X0180Y         S0      
327m3136            C2355 -1          A01X+111581Y+137729X0120Y0150R090 S1      
317m3136            VIA   -    MD0080PA01X+123130Y+123228X0160Y    R270 S0      
327m3136            PEX2  -G47        A01X+123130Y+123228X0180Y         S1      
317m3137            VIA   -    M      A01X+005996Y+091025X0200Y         S2      
017m3137            VIA   -    M      A18X+005996Y+091025X0260Y         S2      
017m3137                  -    MD0100PA00X+005996Y+091025                       
317m3137            VIA   -    MD0100PA00X+014660Y+105346X0200Y         S0      
327m3137            R3435 -1          A18X+015637Y+116065X0198Y0197R180 S2      
327m3137            R3448 -1          A18X+005996Y+090550X0198Y0197     S2      
317m3138            J3    -R4   D0122PA01X+013587Y+149366X0282Y    R180 S3      
317m3138            VIA   -    MD0080PA01X+032087Y+121358X0160Y    R270 S0      
327m3138            PEX0  -M48        A01X+032087Y+121358X0180Y         S1      
317m3139            VIA   -    MD0080PA01X+032087Y+123976X0160Y         S0      
327m3139            PEX0  -E48        A01X+032087Y+123976X0180Y         S1      
327m3139            C2168 -1          A01X+014945Y+135309X0120Y0150R090 S1      
317m3139            VIA   -    MD0100PA01X+014955Y+134819X0180Y         S0      
317m3140            VIA   -    MD0100PA01X+019851Y+136010X0180Y         S0      
317m3140            J3    -Y7   D0122PA01X+016185Y+145862X0282Y    R180 S3      
327m3140            C2180 -2          A01X+019841Y+135519X0120Y0150R090 S1      
317m3141            J3    -R6   D0122PA01X+015319Y+149366X0282Y    R180 S3      
317m3141            VIA   -    MD0080PA01X+032087Y+120610X0160Y         S0      
327m3141            PEX0  -P48        A01X+032087Y+120610X0180Y         S1      
317m3142            J3    -R7   D0122PA01X+016185Y+149445X0282Y    R180 S3      
317m3142            VIA   -    MD0080PA01X+031712Y+120236X0160Y    R270 S0      
327m3142            PEX0  -R47        A01X+031712Y+120236X0180Y         S1      
317m3143            VIA   -    MD0100PA01X+010399Y+134819X0180Y         S0      
317m3143            VIA   -    MD0080PA01X+029842Y+122854X0160Y    R270 S0      
327m3143            PEX0  -H42        A01X+029842Y+122854X0180Y         S1      
327m3143            C2157 -1          A01X+010409Y+135309X0120Y0150R090 S1      
317m3144            J3    -Q8   D0122PA01X+017051Y+149878X0282Y    R180 S3      
317m3144            VIA   -    MD0080PA01X+032461Y+119862X0160Y    R270 S0      
327m3144            PEX0  -T49        A01X+032461Y+119862X0180Y         S1      
317m3145            VIA   -    M      A01X+143504Y+087469X0200Y         S2      
017m3145            VIA   -    M      A18X+143504Y+087469X0260Y         S2      
017m3145                  -    MD0100PA00X+143504Y+087469                       
327m3145            JPEX3 -15  M      A01X+143025Y+087530X0200Y0600R090 S1      
327m3145            U321  -15         A01X+142962Y+087530X0320Y0750R270 S1      
327m3145            R3502 -2          A18X+144700Y+087486X0198Y0197     S2      
317m3146            VIA   -    MD0100PA01X+013731Y+138430X0180Y         S0      
317m3146            J3    -L8   D0122PA01X+017051Y+156532X0282Y    R180 S3      
327m3146            C2166 -2          A01X+013721Y+137939X0120Y0150R090 S1      
317m3147            J7    -F6   D0122PA01X+117516Y+159602X0282Y    R180 S3      
317m3147            VIA   -    MD0080PA01X+122382Y+125098X0160Y         S0      
327m3147            PEX2  -B45        A01X+122382Y+125098X0180Y         S1      
317m3148            VIA   -    MD0100PA01X+015295Y+136010X0180Y         S0      
317m3148            J3    -X1   D0122PA01X+010988Y+146374X0282Y    R180 S3      
327m3148            C2169 -2          A01X+015305Y+135519X0120Y0150R090 S1      
327m3149            C2179 -1          A01X+018977Y+137729X0120Y0150R090 S1      
317m3149            VIA   -    MD0100PA01X+018967Y+137238X0180Y         S0      
317m3149            VIA   -    MD0080PA01X+029842Y+120610X0160Y    R270 S0      
327m3149            PEX0  -P42        A01X+029842Y+120610X0180Y         S1      
317m3150            VIA   -    MD0100PA01X+118051Y+136010X0180Y         S0      
317m3150            J7    -X7   D0122PA01X+118382Y+146374X0282Y    R180 S3      
327m3150            C2370 -2          A01X+118061Y+135519X0120Y0150R090 S1      
317m3151            J3    -F1   D0122PA01X+010988Y+159681X0282Y    R180 S3      
317m3151            VIA   -    MD0080PA01X+029094Y+124724X0160Y         S0      
327m3151            PEX0  -C40        A01X+029094Y+124724X0180Y         S1      
317m3152            VIA   -    MD0100PA01X+007951Y+134819X0180Y         S0      
317m3152            VIA   -    MD0080PA01X+029094Y+122854X0160Y    R270 S0      
327m3152            PEX0  -H40        A01X+029094Y+122854X0180Y         S1      
327m3152            C2153 -1          A01X+007961Y+135309X0120Y0150R090 S1      
317m3153            J7    -F1   D0122PA01X+113185Y+159681X0282Y    R180 S3      
317m3153            VIA   -    MD0080PA01X+120512Y+124724X0160Y         S0      
327m3153            PEX2  -C40        A01X+120512Y+124724X0180Y         S1      
317m3154            J3    -S7   D0122PA01X+016185Y+148933X0282Y    R180 S3      
317m3154            VIA   -    MD0080PA01X+031338Y+120236X0160Y    R270 S0      
327m3154            PEX0  -R46        A01X+031338Y+120236X0180Y         S1      
317m3155            VIA   -    MD0080PA01X+123504Y+122106X0160Y    R090 S0      
327m3155            PEX2  -K48        A01X+123504Y+122106X0180Y         S1      
317m3155            J7    -R2   D0122PA01X+114051Y+149366X0282Y    R180 S3      
317m3156            VIA   -    MD0100PA01X+016519Y+138430X0180Y         S0      
317m3156            J3    -X3   D0122PA01X+012720Y+146374X0282Y    R180 S3      
327m3156            C2173 -2          A01X+016529Y+137939X0120Y0150R090 S1      
317m3157            VIA   -    MD0100PA01X+008835Y+137238X0180Y         S0      
317m3157            VIA   -    MD0080PA01X+029468Y+123228X0160Y    R270 S0      
327m3157            PEX0  -G41        A01X+029468Y+123228X0180Y         S1      
327m3157            C2154 -1          A01X+008825Y+137729X0120Y0150R090 S1      
317m3158            J7    -E2   D0122PA01X+114051Y+160114X0282Y    R180 S3      
317m3158            VIA   -    MD0080PA01X+120886Y+125472X0160Y         S0      
327m3158            PEX2  -A41        A01X+120886Y+125472X0180Y         S1      
317m3159            VIA   -    MD0100PA01X+012507Y+136010X0180Y         S0      
317m3159            J3    -L6   D0122PA01X+015319Y+156532X0282Y    R180 S3      
327m3159            C2162 -2          A01X+012497Y+135519X0120Y0150R090 S1      
317m3160            VIA   -    MD0100PA01X+106695Y+138430X0180Y         S0      
317m3160            J7    -L2   D0122PA01X+114051Y+156532X0282Y    R180 S3      
327m3160            C2343 -2          A01X+106685Y+137939X0120Y0150R090 S1      
317m3161            J3    -G5   D0122PA01X+014453Y+159169X0282Y    R180 S3      
317m3161            VIA   -    MD0080PA01X+030590Y+124350X0160Y         S0      
327m3161            PEX0  -D44        A01X+030590Y+124350X0180Y         S1      
317m3162            VIA   -    MD0100PA01X+010059Y+134819X0180Y         S0      
317m3162            VIA   -    MD0080PA01X+029842Y+122480X0160Y    R270 S0      
327m3162            PEX0  -J42        A01X+029842Y+122480X0180Y         S1      
327m3162            C2156 -1          A01X+010049Y+135309X0120Y0150R090 S1      
317m3163            VIA   -    MD0100PA01X+116487Y+138430X0180Y         S0      
317m3163            J7    -X6   D0122PA01X+117516Y+146295X0282Y    R180 S3      
327m3163            C2367 -2          A01X+116477Y+137939X0120Y0150R090 S1      
317m3164            VIA   -    MD0100PA01X+010399Y+136010X0180Y         S0      
317m3164            J3    -L3   D0122PA01X+012720Y+156610X0282Y    R180 S3      
327m3164            C2157 -2          A01X+010409Y+135519X0120Y0150R090 S1      
327m3165            C2182 -1          A01X+019841Y+140149X0120Y0150R090 S1      
317m3165            VIA   -    MD0100PA01X+019851Y+139658X0180Y         S0      
317m3165            VIA   -    MD0080PA01X+029468Y+119862X0160Y    R270 S0      
327m3165            PEX0  -T41        A01X+029468Y+119862X0180Y         S1      
317m3166            J7    -Q4   D0122PA01X+115783Y+149878X0282Y    R180 S3      
317m3166            VIA   -    MD0080PA01X+123878Y+121358X0160Y    R270 S0      
327m3166            PEX2  -M49        A01X+123878Y+121358X0180Y         S1      
317m3167            VIA   -    MD0100PA01X+011283Y+138430X0180Y         S0      
317m3167            J3    -M5   D0122PA01X+014453Y+156098X0282Y    R180 S3      
327m3167            C2160 -2          A01X+011273Y+137939X0120Y0150R090 S1      
317m3168            J7    -Q8   D0122PA01X+119248Y+149878X0282Y    R180 S3      
317m3168            VIA   -    MD0080PA01X+123878Y+119862X0160Y    R270 S0      
327m3168            PEX2  -T49        A01X+123878Y+119862X0180Y         S1      
317m3169            VIA   -    MD0100PA01X+010059Y+140850X0180Y         S0      
317m3169            J3    -L4   D0122PA01X+013587Y+156532X0282Y    R180 S3      
327m3169            C2158 -2          A01X+010049Y+140359X0120Y0150R090 S1      
317m3170            VIA   -    MD0100PA01X+007611Y+134819X0180Y         S0      
317m3170            VIA   -    MD0080PA01X+029094Y+122480X0160Y    R270 S0      
327m3170            PEX0  -J40        A01X+029094Y+122480X0180Y         S1      
327m3170            C2152 -1          A01X+007601Y+135309X0120Y0150R090 S1      
317m3171            VIA   -    MD0100PA01X+112815Y+140850X0180Y         S0      
317m3171            J7    -X2   D0122PA01X+114051Y+146295X0282Y    R180 S3      
327m3171            C2359 -2          A01X+112805Y+140359X0120Y0150R090 S1      
327m3172            VIA   -    M      A01X+115248Y+077564X0300Y         S1      
327m3172            U63   -9          A01X+115593Y+078629X0140Y0630R180 S1      
327m3172            R3369 -2          A01X+115248Y+077072X0198Y0197R090 S1      
317m3173            J3    -G3   D0122PA01X+012720Y+159169X0282Y    R180 S3      
317m3173            VIA   -    MD0080PA01X+029842Y+124350X0160Y         S0      
327m3173            PEX0  -D42        A01X+029842Y+124350X0180Y         S1      
317m3174            J7    -F3   D0122PA01X+114917Y+159681X0282Y    R180 S3      
317m3174            VIA   -    MD0080PA01X+121260Y+124724X0160Y         S0      
327m3174            PEX2  -C42        A01X+121260Y+124724X0180Y         S1      
317m3175            VIA   -    M      A01X+115248Y+076455X0200Y         S2      
017m3175            VIA   -    M      A18X+115248Y+076455X0260Y         S2      
017m3175                  -    MD0100PA00X+115248Y+076455                       
327m3175            R3369 -1          A01X+115248Y+076757X0198Y0197R090 S1      
327m3175            Q241  -D          A18X+113174Y+077917X0320Y0360R090 S2      
327m3175            R6658 -1   M      A18X+113175Y+076886X0198Y0197     S2      
317m3176            J3    -F6   D0122PA01X+015319Y+159602X0282Y    R180 S3      
317m3176            VIA   -    MD0080PA01X+030964Y+125098X0160Y         S0      
327m3176            PEX0  -B45        A01X+030964Y+125098X0180Y         S1      
317m3177            VIA   -    MD0100PA01X+109143Y+138430X0180Y         S0      
317m3177            J7    -M5   D0122PA01X+116650Y+156098X0282Y    R180 S3      
327m3177            C2349 -2          A01X+109133Y+137939X0120Y0150R090 S1      
317m3178            J3    -R8   D0122PA01X+017051Y+149366X0282Y    R180 S3      
317m3178            VIA   -    MD0080PA01X+032087Y+119862X0160Y    R270 S0      
327m3178            PEX0  -T48        A01X+032087Y+119862X0180Y         S1      
317m3179            J7    -G1   D0122PA01X+113185Y+159169X0282Y    R180 S3      
317m3179            VIA   -    MD0080PA01X+120512Y+124350X0160Y         S0      
327m3179            PEX2  -D40        A01X+120512Y+124350X0180Y         S1      
317m3180            VIA   -    MD0100PA01X+018967Y+138430X0180Y         S0      
317m3180            J3    -W6   D0122PA01X+015319Y+146807X0282Y    R180 S3      
327m3180            C2179 -2          A01X+018977Y+137939X0120Y0150R090 S1      
327m3181            C2176 -1          A01X+017393Y+140149X0120Y0150R090 S1      
317m3181            VIA   -    MD0100PA01X+017403Y+139658X0180Y         S0      
317m3181            VIA   -    MD0080PA01X+030216Y+120984X0160Y    R270 S0      
327m3181            PEX0  -N43        A01X+030216Y+120984X0180Y         S1      
317m3182            J7    -R1   D0122PA01X+113185Y+149445X0282Y    R180 S3      
317m3182            VIA   -    MD0080PA01X+123878Y+124724X0160Y    R270 S0      
327m3182            PEX2  -C49        A01X+123878Y+124724X0180Y         S1      
317m3183            J3    -S5   D0122PA01X+014453Y+148933X0282Y    R180 S3      
317m3183            VIA   -    MD0080PA01X+031338Y+120984X0160Y    R270 S0      
327m3183            PEX0  -N46        A01X+031338Y+120984X0180Y         S1      
327m3184            C2173 -1          A01X+016529Y+137729X0120Y0150R090 S1      
317m3184            VIA   -    MD0100PA01X+016519Y+137238X0180Y         S0      
317m3184            VIA   -    MD0080PA01X+030590Y+121732X0160Y    R270 S0      
327m3184            PEX0  -L44        A01X+030590Y+121732X0180Y         S1      
317m3185            VIA   -    MD0100PA01X+108259Y+136010X0180Y         S0      
317m3185            J7    -L3   D0122PA01X+114917Y+156610X0282Y    R180 S3      
327m3185            C2346 -2          A01X+108269Y+135519X0120Y0150R090 S1      
317m3186            VIA   -    MD0100PA01X+014071Y+138430X0180Y         S0      
317m3186            J3    -K8   D0122PA01X+017051Y+157043X0282Y    R180 S3      
327m3186            C2167 -2          A01X+014081Y+137939X0120Y0150R090 S1      
317m3187            VIA   -    MD0100PA01X+110367Y+140850X0180Y         S0      
317m3187            J7    -M7   D0122PA01X+118382Y+156098X0282Y    R180 S3      
327m3187            C2353 -2          A01X+110357Y+140359X0120Y0150R090 S1      
317m3188            J3    -F8   D0122PA01X+017051Y+159602X0282Y    R180 S3      
317m3188            VIA   -    MD0080PA01X+031712Y+125098X0160Y         S0      
327m3188            PEX0  -B47        A01X+031712Y+125098X0180Y         S1      
317m3189            VIA   -    MD0100PA01X+110707Y+140850X0180Y         S0      
317m3189            J7    -L7   D0122PA01X+118382Y+156610X0282Y    R180 S3      
327m3189            C2354 -2          A01X+110717Y+140359X0120Y0150R090 S1      
317m3190            VIA   -    MD0100PA01X+007951Y+136010X0180Y         S0      
317m3190            J3    -L1   D0122PA01X+010988Y+156610X0282Y    R180 S3      
327m3190            C2153 -2          A01X+007961Y+135519X0120Y0150R090 S1      
317m3191            J7    -R7   D0122PA01X+118382Y+149445X0282Y    R180 S3      
317m3191            VIA   -    MD0080PA01X+123130Y+120236X0160Y    R270 S0      
327m3191            PEX2  -R47        A01X+123130Y+120236X0180Y         S1      
317m3192            J3    -S1   D0122PA01X+010988Y+148933X0282Y    R180 S3      
317m3192            VIA   -    MD0080PA01X+032087Y+124724X0160Y    R270 S0      
327m3192            PEX0  -C48        A01X+032087Y+124724X0180Y         S1      
327m3193            C2180 -1          A01X+019841Y+135309X0120Y0150R090 S1      
317m3193            VIA   -    MD0100PA01X+019851Y+134819X0180Y         S0      
317m3193            VIA   -    MD0080PA01X+030216Y+120236X0160Y    R270 S0      
327m3193            PEX0  -R43        A01X+030216Y+120236X0180Y         S1      
317m3194            J7    -S5   D0122PA01X+116650Y+148933X0282Y    R180 S3      
317m3194            VIA   -    MD0080PA01X+122756Y+120984X0160Y    R270 S0      
327m3194            PEX2  -N46        A01X+122756Y+120984X0180Y         S1      
317m3195            J3    -F7   D0122PA01X+016185Y+159681X0282Y    R180 S3      
317m3195            VIA   -    MD0080PA01X+031338Y+124724X0160Y         S0      
327m3195            PEX0  -C46        A01X+031338Y+124724X0180Y         S1      
317m3196            J7    -Q6   D0122PA01X+117516Y+149878X0282Y    R180 S3      
317m3196            VIA   -    MD0080PA01X+123878Y+120610X0160Y    R270 S0      
327m3196            PEX2  -P49        A01X+123878Y+120610X0180Y         S1      
317m3197            J3    -F3   D0122PA01X+012720Y+159681X0282Y    R180 S3      
317m3197            VIA   -    MD0080PA01X+029842Y+124724X0160Y         S0      
327m3197            PEX0  -C42        A01X+029842Y+124724X0180Y         S1      
317m3198            J7    -E6   D0122PA01X+117516Y+160114X0282Y    R180 S3      
317m3198            VIA   -    MD0080PA01X+122382Y+125472X0160Y         S0      
327m3198            PEX2  -A45        A01X+122382Y+125472X0180Y         S1      
317m3199            J3    -R2   D0122PA01X+011854Y+149366X0282Y    R180 S3      
317m3199            VIA   -    MD0080PA01X+032087Y+122106X0160Y    R090 S0      
327m3199            PEX0  -K48        A01X+032087Y+122106X0180Y         S1      
317m3200            VIA   -    MD0100PA01X+009175Y+137238X0180Y         S0      
317m3200            VIA   -    MD0080PA01X+029468Y+123602X0160Y    R270 S0      
327m3200            PEX0  -F41        A01X+029468Y+123602X0180Y         S1      
327m3200            C2155 -1          A01X+009185Y+137729X0120Y0150R090 S1      
317m3201            J7    -E8   D0122PA01X+119248Y+160114X0282Y    R180 S3      
317m3201            VIA   -    MD0080PA01X+123130Y+125472X0160Y         S0      
327m3201            PEX2  -A47        A01X+123130Y+125472X0180Y         S1      
317m3202            VIA   -    MD0100PA01X+012847Y+136010X0180Y         S0      
317m3202            J3    -K6   D0122PA01X+015319Y+157043X0282Y    R180 S3      
327m3202            C2163 -2          A01X+012857Y+135519X0120Y0150R090 S1      
317m3203            VIA   -    MD0100PA01X+113155Y+136010X0180Y         S0      
317m3203            J7    -X1   D0122PA01X+113185Y+146374X0282Y    R180 S3      
327m3203            C2358 -2          A01X+113165Y+135519X0120Y0150R090 S1      
317m3204            J3    -Q4   D0122PA01X+013587Y+149878X0282Y    R180 S3      
317m3204            VIA   -    MD0080PA01X+032461Y+121358X0160Y    R270 S0      
327m3204            PEX0  -M49        A01X+032461Y+121358X0180Y         S1      
317m3205            VIA   -    MD0100PA01X+014071Y+137238X0180Y         S0      
317m3205            VIA   -    MD0080PA01X+031712Y+123602X0160Y    R270 S0      
327m3205            PEX0  -F47        A01X+031712Y+123602X0180Y         S1      
327m3205            C2167 -1          A01X+014081Y+137729X0120Y0150R090 S1      
317m3206            VIA   -    MD0100PA01X+105471Y+136010X0180Y         S0      
317m3206            J7    -M1   D0122PA01X+113185Y+156098X0282Y    R180 S3      
327m3206            C2341 -2          A01X+105461Y+135519X0120Y0150R090 S1      
317m3207            VIA   -    MD0100PA01X+007611Y+136010X0180Y         S0      
317m3207            J3    -M1   D0122PA01X+010988Y+156098X0282Y    R180 S3      
327m3207            C2152 -2          A01X+007601Y+135519X0120Y0150R090 S1      
317m3208            VIA   -    MD0100PA01X+115263Y+140850X0180Y         S0      
317m3208            J7    -Y5   D0122PA01X+116650Y+145862X0282Y    R180 S3      
327m3208            C2365 -2          A01X+115253Y+140359X0120Y0150R090 S1      
317m3209            J3    -R5   D0122PA01X+014453Y+149445X0282Y    R180 S3      
317m3209            VIA   -    MD0080PA01X+031712Y+120984X0160Y    R270 S0      
327m3209            PEX0  -N47        A01X+031712Y+120984X0180Y         S1      
317m3210            J7    -G5   D0122PA01X+116650Y+159169X0282Y    R180 S3      
317m3210            VIA   -    MD0080PA01X+122008Y+124350X0160Y         S0      
327m3210            PEX2  -D44        A01X+122008Y+124350X0180Y         S1      
317m3211            VIA   -    MD0100PA01X+017403Y+136010X0180Y         S0      
317m3211            J3    -X4   D0122PA01X+013587Y+146295X0282Y    R180 S3      
327m3211            C2174 -2          A01X+017393Y+135519X0120Y0150R090 S1      
317m3212            VIA   -    MD0080PA01X+032461Y+123976X0160Y         S0      
327m3212            PEX0  -E49        A01X+032461Y+123976X0180Y         S1      
327m3212            C2169 -1          A01X+015305Y+135309X0120Y0150R090 S1      
317m3212            VIA   -    MD0100PA01X+015295Y+134819X0180Y         S0      
317m3213            VIA   -    MD0100PA01X+111931Y+138430X0180Y         S0      
317m3213            J7    -K8   D0122PA01X+119248Y+157043X0282Y    R180 S3      
327m3213            C2356 -2          A01X+111941Y+137939X0120Y0150R090 S1      
317m3214            VIA   -    MD0100PA01X+017743Y+140850X0180Y         S0      
317m3214            J3    -X5   D0122PA01X+014453Y+146374X0282Y    R180 S3      
327m3214            C2177 -2          A01X+017753Y+140359X0120Y0150R090 S1      
327m3215            C2174 -1          A01X+017393Y+135309X0120Y0150R090 S1      
317m3215            VIA   -    MD0100PA01X+017403Y+134819X0180Y         S0      
317m3215            VIA   -    MD0080PA01X+029468Y+121358X0160Y    R270 S0      
327m3215            PEX0  -M41        A01X+029468Y+121358X0180Y         S1      
317m3216            J7    -R5   D0122PA01X+116650Y+149445X0282Y    R180 S3      
317m3216            VIA   -    MD0080PA01X+123130Y+120984X0160Y    R270 S0      
327m3216            PEX2  -N47        A01X+123130Y+120984X0180Y         S1      
317m3217            J3    -R3   D0122PA01X+012720Y+149445X0282Y    R180 S3      
317m3217            VIA   -    MD0080PA01X+031712Y+121732X0160Y    R270 S0      
327m3217            PEX0  -L47        A01X+031712Y+121732X0180Y         S1      
317m3218            VIA   -    MD0100PA01X+109483Y+138430X0180Y         S0      
317m3218            J7    -L5   D0122PA01X+116650Y+156610X0282Y    R180 S3      
327m3218            C2350 -2          A01X+109493Y+137939X0120Y0150R090 S1      
317m3219            J3    -F2   D0122PA01X+011854Y+159602X0282Y    R180 S3      
317m3219            VIA   -    MD0080PA01X+029468Y+125098X0160Y         S0      
327m3219            PEX0  -B41        A01X+029468Y+125098X0180Y         S1      
327m3220            C2177 -1          A01X+017753Y+140149X0120Y0150R090 S1      
317m3220            VIA   -    MD0100PA01X+017743Y+139658X0180Y         S0      
317m3220            VIA   -    MD0080PA01X+030590Y+120984X0160Y    R270 S0      
327m3220            PEX0  -N44        A01X+030590Y+120984X0180Y         S1      
317m3221            J7    -F5   D0122PA01X+116650Y+159681X0282Y    R180 S3      
317m3221            VIA   -    MD0080PA01X+122008Y+124724X0160Y         S0      
327m3221            PEX2  -C44        A01X+122008Y+124724X0180Y         S1      
317m3222            J3    -E6   D0122PA01X+015319Y+160114X0282Y    R180 S3      
317m3222            VIA   -    MD0080PA01X+030964Y+125472X0160Y         S0      
327m3222            PEX0  -A45        A01X+030964Y+125472X0180Y         S1      
327m3223            C2181 -1          A01X+020201Y+135309X0120Y0150R090 S1      
317m3223            VIA   -    MD0100PA01X+020191Y+134819X0180Y         S0      
317m3223            VIA   -    MD0080PA01X+030590Y+120236X0160Y    R270 S0      
327m3223            PEX0  -R44        A01X+030590Y+120236X0180Y         S1      
317m3224            VIA   -    MD0100PA01X+105811Y+136010X0180Y         S0      
317m3224            J7    -L1   D0122PA01X+113185Y+156610X0282Y    R180 S3      
327m3224            C2342 -2          A01X+105821Y+135519X0120Y0150R090 S1      
317m3225            VIA   -    MD0100PA01X+012847Y+140850X0180Y         S0      
317m3225            J3    -L7   D0122PA01X+016185Y+156610X0282Y    R180 S3      
327m3225            C2165 -2          A01X+012857Y+140359X0120Y0150R090 S1      
317m3226            J7    -G3   D0122PA01X+114917Y+159169X0282Y    R180 S3      
317m3226            VIA   -    MD0080PA01X+121260Y+124350X0160Y         S0      
327m3226            PEX2  -D42        A01X+121260Y+124350X0180Y         S1      
317m3227            VIA   -    MD0100PA01X+012507Y+140850X0180Y         S0      
317m3227            J3    -M7   D0122PA01X+016185Y+156098X0282Y    R180 S3      
327m3227            C2164 -2          A01X+012497Y+140359X0120Y0150R090 S1      
317m3228            VIA   -    MD0100PA01X+114039Y+138430X0180Y         S0      
317m3228            J7    -Y3   D0122PA01X+114917Y+145862X0282Y    R180 S3      
327m3228            C2361 -2          A01X+114029Y+137939X0120Y0150R090 S1      
317m3229            J3    -E8   D0122PA01X+017051Y+160114X0282Y    R180 S3      
317m3229            VIA   -    MD0080PA01X+031712Y+125472X0160Y         S0      
327m3229            PEX0  -A47        A01X+031712Y+125472X0180Y         S1      
327m3230            C2183 -1          A01X+020201Y+140149X0120Y0150R090 S1      
317m3230            VIA   -    MD0100PA01X+020191Y+139658X0180Y         S0      
317m3230            VIA   -    MD0080PA01X+029842Y+119862X0160Y    R270 S0      
327m3230            PEX0  -T42        A01X+029842Y+119862X0180Y         S1      
317m3231            VIA   -    MD0080PA01X+123878Y+122106X0160Y    R090 S0      
327m3231            PEX2  -K49        A01X+123878Y+122106X0180Y         S1      
317m3231            J7    -Q2   D0122PA01X+114051Y+149878X0282Y    R180 S3      
317m3232            VIA   -    MD0100PA01X+016179Y+138430X0180Y         S0      
317m3232            J3    -Y3   D0122PA01X+012720Y+145862X0282Y    R180 S3      
327m3232            C2172 -2          A01X+016169Y+137939X0120Y0150R090 S1      
317m3233            VIA   -    MD0100PA01X+012507Y+134819X0180Y         S0      
317m3233            VIA   -    MD0080PA01X+030964Y+123228X0160Y    R270 S0      
327m3233            PEX0  -G45        A01X+030964Y+123228X0180Y         S1      
327m3233            C2162 -1          A01X+012497Y+135309X0120Y0150R090 S1      
317m3234            J7    -F7   D0122PA01X+118382Y+159681X0282Y    R180 S3      
317m3234            VIA   -    MD0080PA01X+122756Y+124724X0160Y         S0      
327m3234            PEX2  -C46        A01X+122756Y+124724X0180Y         S1      
317m3235            VIA   -    MD0100PA01X+014955Y+136010X0180Y         S0      
317m3235            J3    -Y1   D0122PA01X+010988Y+145862X0282Y    R180 S3      
327m3235            C2168 -2          A01X+014945Y+135519X0120Y0150R090 S1      
317m3236            VIA   -    MD0100PA01X+117711Y+136010X0180Y         S0      
317m3236            J7    -Y7   D0122PA01X+118382Y+145862X0282Y    R180 S3      
327m3236            C2369 -2          A01X+117701Y+135519X0120Y0150R090 S1      
317m3237            VIA   -    MD0100PA01X+018627Y+138430X0180Y         S0      
317m3237            J3    -X6   D0122PA01X+015319Y+146295X0282Y    R180 S3      
327m3237            C2178 -2          A01X+018617Y+137939X0120Y0150R090 S1      
317m3238            VIA   -    MD0100PA01X+010059Y+139658X0180Y    R180 S0      
317m3238            VIA   -    MD0080PA01X+030216Y+123228X0160Y    R270 S0      
327m3238            PEX0  -G43        A01X+030216Y+123228X0180Y         S1      
327m3238            C2158 -1          A01X+010049Y+140149X0120Y0150R090 S1      
317m3239            VIA   -    MD0100PA01X+110367Y+136010X0180Y         S0      
317m3239            J7    -L6   D0122PA01X+117516Y+156532X0282Y    R180 S3      
327m3239            C2351 -2          A01X+110357Y+135519X0120Y0150R090 S1      
317m3240            VIA   -    MD0100PA01X+020191Y+140850X0180Y         S0      
317m3240            J3    -W8   D0122PA01X+017051Y+146807X0282Y    R180 S3      
327m3240            C2183 -2          A01X+020201Y+140359X0120Y0150R090 S1      
327m3241            C2175 -1          A01X+017753Y+135309X0120Y0150R090 S1      
317m3241            VIA   -    MD0100PA01X+017743Y+134819X0180Y         S0      
317m3241            VIA   -    MD0080PA01X+029842Y+121358X0160Y    R270 S0      
327m3241            PEX0  -M42        A01X+029842Y+121358X0180Y         S1      
317m3242            J7    -R4   D0122PA01X+115783Y+149366X0282Y    R180 S3      
317m3242            VIA   -    MD0080PA01X+123504Y+121358X0160Y    R270 S0      
327m3242            PEX2  -M48        A01X+123504Y+121358X0180Y         S1      
317m3243            J3    -E2   D0122PA01X+011854Y+160114X0282Y    R180 S3      
317m3243            VIA   -    MD0080PA01X+029468Y+125472X0160Y         S0      
327m3243            PEX0  -A41        A01X+029468Y+125472X0180Y         S1      
317m3244            VIA   -    MD0100PA01X+116827Y+138430X0180Y         S0      
317m3244            J7    -W6   D0122PA01X+117516Y+146807X0282Y    R180 S3      
327m3244            C2368 -2          A01X+116837Y+137939X0120Y0150R090 S1      
327P3V3             R1121 -2          A18X+053702Y+071832X0198Y0197R270 S2      
317P3V3             VIA   -    MD0100PA00X+054038Y+071978X0200Y         S0      
327P3V3             R1120 -2          A18X+050579Y+072049X0198Y0197R270 S2      
317P3V3             VIA   -    MD0100PA00X+050283Y+072049X0200Y         S0      
317P3V3             VIA   -    MD0100PA00X+051542Y+075346X0200Y         S0      
327P3V3             R6675 -2          A01X+051563Y+074944X0198Y0197R180 S1      
317P3V3             VIA   -    MD0100PA00X+050910Y+075307X0200Y         S0      
327P3V3             R6676 -2          A01X+050910Y+075572X0198Y0197R270 S1      
327P3V3             R6674 -2          A01X+057450Y+075346X0198Y0197R090 S1      
317P3V3             VIA   -    MD0100PA00X+057004Y+075234X0200Y         S0      
327P3V3             R6673 -2          A01X+056846Y+075490X0198Y0197R270 S1      
327P3V3             R1124 -2          A18X+050331Y+070876X0198Y0197     S2      
317P3V3             VIA   -    MD0100PA00X+050071Y+070876X0200Y         S0      
317P3V3             VIA   -    MD0100PA00X+039169Y+132672X0200Y         S0      
317P3V3             VIA   -    MD0100PA00X+038642Y+132164X0200Y         S0      
327P3V3             L16   -1   M      A18X+039169Y+132164X0440Y0540     S2      
317P3V3             VIA   -    MD0100PA00X+039858Y+131344X0200Y         S0      
327P3V3             R4228 -2          A18X+040143Y+131344X0198Y0197     S2      
317P3V3             VIA   -    MD0100PA00X+045130Y+129704X0200Y         S0      
327P3V3             R1221 -2          A18X+044848Y+129704X0198Y0197R180 S2      
317P3V3             VIA   -    MD0100PA00X+043943Y+132237X0200Y         S0      
327P3V3             R1220 -1          A18X+043648Y+132237X0198Y0197R090 S2      
317P3V3             VIA   -    MD0100PA00X+039996Y+135215X0200Y    R270 S0      
327P3V3             R6370 -2          A18X+039996Y+135498X0198Y0197R090 S2      
317P3V3             VIA   -    MD0100PA00X+042528Y+136402X0200Y    R270 S0      
327P3V3             R6369 -1          A18X+042528Y+136697X0198Y0197     S2      
317P3V3             VIA   -    MD0100PA00X+041910Y+140220X0200Y    R270 S0      
327P3V3             R6368 -2          A18X+041636Y+140202X0198Y0197R270 S2      
317P3V3             VIA   -    MD0100PA00X+042130Y+141540X0200Y    R270 S0      
327P3V3             L149  -1          A18X+042456Y+141177X0440Y0540R270 S2      
317P3V3             VIA   -    MD0100PA00X+042120Y+141790X0200Y    R270 S0      
317P3V3             VIA   -    MD0100PA00X+036589Y+071033X0200Y         S0      
317P3V3             VIA   -    MD0100PA00X+036302Y+071036X0200Y         S0      
317P3V3             VIA   -    MD0100PA00X+038026Y+112969X0200Y         S0      
317P3V3             VIA   -    MD0100PA00X+037841Y+113157X0200Y         S0      
327P3V3             L12   -1          A18X+054704Y+068154X0280Y0320     S2      
317P3V3             VIA   -    MD0100PA00X+054728Y+067552X0200Y         S0      
317P3V3             VIA   -    MD0100PA00X+054723Y+067830X0200Y         S0      
327P3V3             R6672 -2          A01X+072026Y+069970X0198Y0197R090 S1      
317P3V3             VIA   -    MD0100PA00X+071662Y+070246X0200Y         S0      
327P3V3             R6671 -2          A01X+071338Y+070216X0198Y0197R270 S1      
317P3V3             VIA   -    MD0100PA00X+050497Y+067810X0200Y         S0      
317P3V3             VIA   -    MD0100PA00X+051042Y+068325X0200Y         S0      
327P3V3             L11   -1          A18X+050721Y+068148X0280Y0320R090 S2      
317P3V3             VIA   -    MD0100PA00X+050276Y+065769X0200Y         S0      
327P3V3             R6669 -2          A01X+050276Y+065515X0198Y0197     S1      
317P3V3             VIA   -    MD0100PA00X+048116Y+064604X0200Y         S0      
327P3V3             R6670 -2          A01X+048198Y+064897X0198Y0197     S1      
317P3V3             VIA   -    MD0100PA00X+092595Y+060886X0200Y    R090 S0      
317P3V3             VIA   -    MD0100PA00X+092595Y+061236X0200Y    R090 S0      
327P3V3             L79   -1          A18X+092145Y+061060X0440Y0540R270 S2      
327P3V3             R4196 -2          A01X+089193Y+061574X0198Y0197R090 S1      
317P3V3             VIA   -    MD0100PA00X+089193Y+061814X0200Y    R090 S0      
317P3V3             VIA   -    MD0100PA00X+087635Y+060502X0200Y    R090 S0      
317P3V3             VIA   -    MD0100PA00X+087635Y+060852X0200Y    R090 S0      
327P3V3             L81   -1          A18X+088095Y+060660X0440Y0540R270 S2      
327P3V3             R4223 -2          A01X+092923Y+057358X0198Y0197     S1      
317P3V3             VIA   -    MD0100PA00X+093163Y+057358X0200Y         S0      
327P3V3             R4222 -2          A01X+092923Y+057758X0198Y0197     S1      
317P3V3             VIA   -    MD0100PA00X+093163Y+057758X0200Y         S0      
327P3V3             R4221 -2          A01X+092923Y+058158X0198Y0197     S1      
317P3V3             VIA   -    MD0100PA00X+093163Y+058158X0200Y         S0      
327P3V3             R4193 -2          A01X+086949Y+057470X0198Y0197R180 S1      
317P3V3             VIA   -    MD0100PA00X+086709Y+057470X0200Y    R180 S0      
327P3V3             R4192 -2          A01X+086949Y+058683X0198Y0197R180 S1      
317P3V3             VIA   -    MD0100PA00X+086709Y+058683X0200Y    R180 S0      
327P3V3             R4194 -2          A01X+092923Y+056958X0198Y0197     S1      
317P3V3             VIA   -    MD0100PA00X+093163Y+056958X0200Y         S0      
327P3V3             R4195 -2          A01X+092923Y+055764X0198Y0197     S1      
317P3V3             VIA   -    MD0100PA00X+093163Y+055764X0200Y         S0      
317P3V3             VIA   -    MD0100PA00X+089395Y+054736X0200Y    R270 S0      
317P3V3             VIA   -    MD0100PA00X+089145Y+054736X0200Y    R270 S0      
327P3V3             L80   -1          A18X+089771Y+054586X0440Y0540     S2      
327P3V3             R4219 -1          A01X+086934Y+054977X0198Y0197     S1      
317P3V3             VIA   -    MD0100PA00X+086694Y+054977X0200Y    R180 S0      
327P3V3             R4197 -2          A01X+086949Y+055470X0198Y0197R180 S1      
317P3V3             VIA   -    MD0100PA00X+086709Y+055470X0200Y    R180 S0      
327P3V3             R4191 -2          A01X+089993Y+053649X0198Y0197R270 S1      
317P3V3             VIA   -    MD0100PA00X+089993Y+053409X0200Y    R270 S0      
327P3V3             R4190 -2          A01X+089293Y+053649X0198Y0197R270 S1      
317P3V3             VIA   -    MD0100PA00X+089293Y+053409X0200Y    R270 S0      
327P3V3             R852  -1          A01X+046598Y+049567X0198Y0197R180 S1      
317P3V3             VIA   -    MD0100PA00X+046856Y+049567X0200Y         S0      
327P3V3             PU70  -6_7        A01X+046682Y+047200X0295Y0354     S1      
317P3V3             VIA   -    MD0100PA00X+046485Y+047654X0200Y    R090 S0      
317P3V3             VIA   -    MD0100PA00X+046785Y+047654X0200Y    R090 S0      
327P3V3             PC595 -1          A01X+046477Y+048080X0400Y0500R180 S1      
317P3V3             VIA   -    MD0100PA00X+041428Y+049497X0200Y    R090 S0      
317P3V3             VIA   -    MD0100PA00X+042473Y+050020X0200Y    R090 S0      
317P3V3             VIA   -    MD0100PA00X+042473Y+049520X0200Y    R090 S0      
317P3V3             VIA   -    MD0100PA00X+042473Y+049770X0200Y    R090 S0      
317P3V3             VIA   -    M      A01X+042769Y+049894X0200Y         S2      
017P3V3             VIA   -    M      A18X+042769Y+049894X0260Y         S2      
017P3V3                   -    MD0100PA00X+042769Y+049894                       
317P3V3             VIA   -    MD0100PA00X+041428Y+049997X0200Y    R090 S0      
317P3V3             VIA   -    MD0100PA00X+041428Y+049747X0200Y    R090 S0      
317P3V3             VIA   -    MD0100PA00X+042473Y+049270X0200Y    R090 S0      
317P3V3             VIA   -    MD0100PA00X+041428Y+049247X0200Y    R090 S0      
327P3V3             PD3   -C          A01X+041939Y+049624X0670Y0990     S1      
317P3V3             VIA   -    MD0100PA00X+043864Y+050046X0200Y    R090 S0      
317P3V3             VIA   -    MD0100PA00X+043583Y+049892X0200Y         S0      
317P3V3             VIA   -    MD0100PA00X+042757Y+050200X0200Y         S0      
317P3V3             VIA   -    MD0100PA00X+043579Y+050152X0200Y    R090 S0      
327P3V3             PC300 -1          A01X+043816Y+050303X0198Y0197R090 S1      
327P3V3             PC301 -1          A01X+043176Y+050065X0400Y0500R270 S1      
327P3V3             PU21  -1          A01X+044280Y+050356X0110Y0240R270 S1      
327P3V3             PU21  -5          A01X+044280Y+049569X0110Y0240R270 S1      
327P3V3             PU21  -4          A01X+044280Y+049766X0110Y0240R270 S1      
327P3V3             PU21  -3          A01X+044280Y+049962X0110Y0240R270 S1      
327P3V3             PU21  -2          A01X+044280Y+050159X0110Y0240R270 S1      
327P3V3             R479  -1          A01X+095278Y+083336X0198Y0197R270 S1      
317P3V3             VIA   -    MD0100PA00X+095470Y+083770X0200Y         S0      
317P3V3             VIA   -    MD0100PA00X+101219Y+044342X0200Y         S0      
327P3V3             R5828 -1          A01X+048948Y+043749X0198Y0197R270 S1      
317P3V3             VIA   -    MD0100PA00X+048948Y+043990X0200Y    R180 S0      
327P3V3             R5825 -1          A01X+048548Y+043749X0198Y0197R270 S1      
317P3V3             VIA   -    MD0100PA00X+048548Y+043990X0200Y    R180 S0      
327P3V3             R1131 -1          A01X+042042Y+036523X0198Y0197R270 S1      
317P3V3             VIA   -    MD0100PA00X+042042Y+036786X0200Y         S0      
327P3V3             R1130 -1          A01X+041232Y+036522X0198Y0197R270 S1      
317P3V3             VIA   -    MD0100PA00X+041232Y+036790X0200Y         S0      
317P3V3             VIA   -    MD0100PA00X+040334Y+031516X0200Y         S0      
317P3V3             VIA   -    MD0100PA00X+040584Y+031516X0200Y         S0      
327P3V3             L13   -1          A18X+040493Y+031858X0280Y0320     S2      
327P3V3             R1050 -2          A01X+105880Y+031057X0198Y0197     S1      
317P3V3             VIA   -    M      A01X+107657Y+031057X0200Y         S2      
017P3V3             VIA   -    M      A18X+107657Y+031057X0260Y         S2      
017P3V3                   -    MD0100PA00X+107657Y+031057                       
327P3V3             R6266 -2   M      A01X+161987Y+034025X0198Y0197     S1      
327P3V3             R6267 -2          A01X+161987Y+034425X0198Y0197     S1      
327P3V3             R6259 -2          A01X+129542Y+032650X0198Y0197R180 S1      
327P3V3             R6260 -2          A01X+129542Y+033700X0198Y0197R180 S1      
317P3V3             VIA   -    MD0100PA00X+132501Y+037095X0200Y    R270 S0      
327P3V3             R3509 -1          A01X+132501Y+036832X0198Y0197R270 S1      
317P3V3             VIA   -    MD0100PA00X+131017Y+036796X0200Y    R270 S0      
327P3V3             R3508 -1          A01X+131690Y+036832X0198Y0197R270 S1      
317P3V3             VIA   -    MD0100PA00X+162930Y+033440X0200Y         S0      
317P3V3             VIA   -    MD0100PA00X+160795Y+033233X0200Y         S0      
327P3V3             U421  -1          A01X+159956Y+033546X0240Y0460R270 S1      
327P3V3             C3995 -2   M      A01X+160872Y+033625X0198Y0197R180 S1      
317P3V3             VIA   -    MD0100PA00X+129300Y+033850X0200Y         S0      
327P3V3             L14   -1          A18X+130752Y+032167X0280Y0320     S2      
317P3V3             VIA   -    MD0100PA00X+130843Y+031825X0200Y         S0      
317P3V3             VIA   -    MD0100PA00X+130593Y+031825X0200Y         S0      
317P3V3             VIA   -    MD0100PA00X+129400Y+032400X0200Y         S0      
327P3V3             U420  -1          A01X+128542Y+032780X0240Y0460R270 S1      
327P3V3             C3993 -2   M      A01X+129150Y+032458X0198Y0197R090 S1      
327P3V3             L9    -1          A18X+098892Y+033419X0440Y0540R270 S2      
327P3V3             L10   -1          A18X+104966Y+035095X0440Y0540R180 S2      
327P3V3             L8    -1          A18X+105366Y+031045X0440Y0540R180 S2      
317P3V3             VIA   -    MD0100PA00X+097715Y+033897X0200Y    R180 S0      
327P3V3             R1051 -2          A01X+097955Y+033897X0198Y0197R180 S1      
317P3V3             VIA   -    MD0100PA00X+097715Y+033197X0200Y    R180 S0      
327P3V3             R1052 -2          A01X+097955Y+033197X0198Y0197R180 S1      
317P3V3             VIA   -    MD0100PA00X+098004Y+036656X0200Y    R090 S0      
327P3V3             R1058 -2          A01X+098004Y+036416X0198Y0197R090 S1      
327P3V3             R1077 -1          A18X+098008Y+036346X0198Y0197R090 S2      
317P3V3             VIA   -    MD0100PA00X+099042Y+033795X0200Y    R180 S0      
317P3V3             VIA   -    MD0100PA00X+099042Y+034045X0200Y    R180 S0      
317P3V3             VIA   -    MD0100PA00X+100070Y+030028X0200Y    R270 S0      
327P3V3             R1056 -2          A01X+100070Y+030268X0198Y0197R270 S1      
317P3V3             VIA   -    MD0100PA00X+102064Y+030028X0200Y    R270 S0      
327P3V3             R1080 -2          A01X+102064Y+030268X0198Y0197R270 S1      
317P3V3             VIA   -    MD0100PA00X+102575Y+030028X0200Y    R270 S0      
327P3V3             R1079 -2          A01X+102575Y+030268X0198Y0197R270 S1      
317P3V3             VIA   -    MD0100PA00X+101264Y+030028X0200Y    R270 S0      
327P3V3             R1055 -2          A01X+101264Y+030268X0198Y0197R270 S1      
317P3V3             VIA   -    MD0100PA00X+101664Y+030028X0200Y    R270 S0      
327P3V3             R1081 -2          A01X+101664Y+030268X0198Y0197R270 S1      
317P3V3             VIA   -    MD0100PA00X+102964Y+030014X0200Y    R270 S0      
327P3V3             R1078 -2          A01X+102964Y+030268X0198Y0197R270 S1      
317P3V3             VIA   -    M      A01X+104565Y+030009X0200Y    R270 S2      
017P3V3             VIA   -    M      A18X+104565Y+030009X0260Y    R270 S2      
017P3V3                   -    MD0100PA00X+104565Y+030009                       
317P3V3             VIA   -    M      A01X+106139Y+034351X0200Y         S2      
017P3V3             VIA   -    M      A18X+106139Y+034351X0260Y         S2      
017P3V3                   -    MD0100PA00X+106139Y+034351                       
327P3V3             R1057 -2          A01X+105869Y+034351X0198Y0197     S1      
317P3V3             VIA   -    MD0100PA00X+105008Y+030551X0200Y         S0      
317P3V3             VIA   -    MD0100PA00X+105016Y+030275X0200Y         S0      
317P3V3             VIA   -    M      A01X+106068Y+035615X0200Y         S2      
017P3V3             VIA   -    M      A18X+106068Y+035615X0260Y         S2      
017P3V3                   -    MD0100PA00X+106068Y+035615                       
327P3V3             R1053 -2          A01X+105828Y+035615X0198Y0197     S1      
317P3V3             VIA   -    MD0100PA00X+106068Y+036828X0200Y         S0      
327P3V3             R1054 -2          A01X+105828Y+036828X0198Y0197     S1      
327P3V3             R1049 -2          A01X+104565Y+030268X0198Y0197R270 S1      
317SPI_PEX3_SDIO3   VIA   -    MD0080PA00X+154065Y+115187X0160Y         S0      
327SPI_PEX3_SDIO3   VIA   -    M      A18X+152756Y+114339X0260Y         S2      
327SPI_PEX3_SDIO3   R3490 -2          A18X+152756Y+113848X0198Y0197R270 S2      
327SPI_PEX3_SDIO3   PEX3  -AH8        A01X+154252Y+115374X0180Y         S1      
327m3245            VIA   -    M      A18X+088005Y+076936X0260Y         S2      
327m3245            R464  -2          A18X+088005Y+077397X0198Y0197R090 S2      
327m3245            R468  -1          A18X+088005Y+076441X0198Y0197R090 S2      
327m3246            VIA   -    M      A18X+087485Y+076902X0260Y         S2      
327m3246            R463  -2          A18X+087485Y+077398X0198Y0197R090 S2      
327m3246            R467  -1          A18X+087485Y+076441X0198Y0197R090 S2      
327m3247            VIA   -    M      A18X+088661Y+076942X0260Y         S2      
327m3247            R462  -2          A18X+088511Y+077397X0198Y0197R090 S2      
327m3247            R466  -1          A18X+088661Y+076441X0198Y0197R090 S2      
327m3248            VIA   -    M      A18X+008606Y+087486X0260Y         S2      
327m3248            R3449 -1          A18X+007904Y+087486X0198Y0197     S2      
327m3248            U65   -9          A18X+008653Y+088323X0140Y0610R180 S2      
327m3249            VIA   -    M      A18X+009128Y+089282X0260Y         S2      
327m3249            U65   -12         A18X+007903Y+088323X0140Y0610R180 S2      
327m3249            R3445 -2          A18X+009139Y+089742X0198Y0197R090 S2      
327SPI_BIC1_CS0_N   VIA   -    M      A01X+090494Y+082136X0300Y    R270 S1      
327SPI_BIC1_CS0_N   U5    -A7         A01X+090814Y+083742X0160Y    R180 S1      
327SPI_BIC1_CS0_N   R458  -1          A01X+090392Y+080646X0198Y0197R270 S1      
327SPI_BIC1_CS0_N   R1506 -1   M      A01X+090392Y+081662X0198Y0197R270 S1      
327m3250            VIA   -    M      A18X+088489Y+078478X0260Y         S2      
327m3250            R461  -2          A18X+088489Y+078970X0198Y0197R090 S2      
327m3250            R464  -1   M      A18X+088005Y+077712X0198Y0197R090 S2      
327m3250            R1025 -1          A18X+088005Y+077712X0198Y0197R270 S2      
327SPI_BIC1_CLK_R   VIA   -    M      A18X+089072Y+077712X0260Y         S2      
327SPI_BIC1_CLK_R   R459  -2          A18X+089412Y+078970X0198Y0197R090 S2      
327SPI_BIC1_CLK_R   R462  -1   M      A18X+088511Y+077712X0198Y0197R090 S2      
327SPI_BIC1_CLK_R   R1023 -1          A18X+088511Y+077712X0198Y0197R270 S2      
327m3251            VIA   -    M      A01X+071985Y+075614X0300Y    R090 S1      
327m3251            U50   -9          A01X+070919Y+075958X0140Y0630R270 S1      
327m3251            R3291 -2          A01X+072477Y+075614X0198Y0197R180 S1      
327m3252            VIA   -    M      A01X+072690Y+075056X0300Y         S1      
327m3252            R3291 -1          A01X+072792Y+075614X0198Y0197R180 S1      
327m3252            R6657 -1          A01X+070702Y+072805X0198Y0197     S1      
327m3252            Q240  -D   M      A01X+070706Y+073817X0320Y0360R090 S1      
327SPI_BIC1_MISO    R461  -1          A18X+088489Y+079285X0198Y0197R090 S2      
317SPI_BIC1_MISO    VIA   -    M      A01X+088952Y+079285X0200Y         S2      
017SPI_BIC1_MISO    VIA   -    M      A18X+088952Y+079285X0260Y         S2      
017SPI_BIC1_MISO          -    MD0100PA00X+088952Y+079285                       
327SPI_BIC1_MISO    R5534 -2          A01X+092379Y+080646X0198Y0197R090 S1      
327SPI_BIC1_MISO    R5535 -2   M      A01X+091966Y+080646X0198Y0197R090 S1      
327SPI_BIC1_MISO    U5    -B5         A01X+091444Y+084057X0160Y    R180 S1      
317SPI_BIC1_MISO    VIA   -    MD0100PA00X+091780Y+081136X0200Y    R090 S0      
317SPI_BIC1_MOSI    VIA   -    MD0100PA00X+090788Y+082987X0200Y         S0      
327SPI_BIC1_MOSI    U5    -A6         A01X+091129Y+083742X0160Y    R180 S1      
327SPI_BIC1_MOSI    R460  -1          A18X+087510Y+079285X0198Y0197R090 S2      
317SPI_BIC1_MOSI    VIA   -    M      A01X+088004Y+079285X0200Y         S2      
017SPI_BIC1_MOSI    VIA   -    M      A18X+088004Y+079285X0260Y         S2      
017SPI_BIC1_MOSI          -    MD0100PA00X+088004Y+079285                       
327PWRGD_P5V_AUX    R502  -1          A01X+007491Y+068759X0198Y0197R270 S1      
327PWRGD_P5V_AUX    PU4   -6          A01X+007836Y+067871X0110Y0320     S1      
327PWRGD_P5V_AUX    R501  -2          A01X+007874Y+068611X0198Y0197R180 S1      
317PWRGD_P5V_AUX    VIA   -    M      A01X+007874Y+068343X0200Y    R090 S2      
017PWRGD_P5V_AUX    VIA   -    M      A18X+007874Y+068343X0260Y    R090 S2      
017PWRGD_P5V_AUX          -    MD0100PA00X+007874Y+068343                       
327PWRGD_P5V_AUX    R4429 -1          A18X+008704Y+068180X0198Y0197R180 S2      
327P5V_AUX_FB       PU4   -5          A01X+008032Y+067871X0110Y0320     S1      
327P5V_AUX_FB       PR57  -1          A01X+008454Y+067811X0198Y0197     S1      
327P5V_AUX_FB       PR58  -1          A01X+008454Y+068211X0198Y0197     S1      
317P5V_AUX_FB       VIA   -           A01X+008256Y+068004X0200Y         S2      
017P5V_AUX_FB       VIA   -           A18X+008256Y+068004X0260Y         S2      
017P5V_AUX_FB             -     D0100PA00X+008256Y+068004                       
327SPI_BIC1_CLK     R5513 -2          A01X+091142Y+080646X0198Y0197R090 S1      
327SPI_BIC1_CLK     R5529 -2   M      A01X+091572Y+080646X0198Y0197R090 S1      
327SPI_BIC1_CLK     U5    -A5         A01X+091444Y+083742X0160Y    R180 S1      
317SPI_BIC1_CLK     VIA   -    MD0100PA00X+091372Y+081195X0200Y    R090 S0      
327SPI_BIC1_CLK     R459  -1          A18X+089412Y+079285X0198Y0197R090 S2      
317SPI_BIC1_CLK     VIA   -    M      A01X+089874Y+079229X0200Y         S2      
017SPI_BIC1_CLK     VIA   -    M      A18X+089874Y+079229X0260Y         S2      
017SPI_BIC1_CLK           -    MD0100PA00X+089874Y+079229                       
327SH_P5V_AUX_FB    PR57  -2          A01X+008769Y+067811X0198Y0197     S1      
327SH_P5V_AUX_FB    VIA   -           A01X+009703Y+067943X0300Y         S1      
327SH_P5V_AUX_FB    PJ2   -1   M      A01X+009184Y+067943X0200Y0400R180 S1      
327m3253            PU4   -2          A01X+007639Y+067084X0110Y0320     S1      
327m3253            PC17  -1          A01X+007811Y+066257X0198Y0197R270 S1      
327m3253            PL1   -2          A01X+008272Y+065699X0280Y0320R090 S1      
327m3253            PC16  -1          A01X+008352Y+066410X0400Y0500R180 S1      
317m3253            VIA   -           A01X+008484Y+065986X0200Y         S2      
017m3253            VIA   -           A18X+008484Y+065986X0260Y         S2      
017m3253                  -     D0100PA00X+008484Y+065986                       
327SW_P5V_AUX_BT    PU4   -3          A01X+007836Y+067084X0110Y0320     S1      
327SW_P5V_AUX_BT    PC19  -1          A01X+007397Y+066252X0198Y0197R090 S1      
317SW_P5V_AUX_BT    VIA   -    MD0100PA00X+007904Y+066739X0200Y    R090 S0      
317SW_P5V_AUX_BT    VIA   -    M      A01X+007391Y+066011X0200Y         S2      
017SW_P5V_AUX_BT    VIA   -    M      A18X+007391Y+066011X0260Y         S2      
017SW_P5V_AUX_BT          -    MD0100PA00X+007391Y+066011                       
327P5V_AUX_EN       PU4   -4          A01X+008032Y+067084X0110Y0320     S1      
317P5V_AUX_EN       VIA   -    M      A01X+008265Y+067068X0200Y         S2      
017P5V_AUX_EN       VIA   -    M      A18X+008265Y+067068X0260Y         S2      
017P5V_AUX_EN             -    MD0100PA00X+008265Y+067068                       
327P5V_AUX_EN       R503  -2          A18X+008561Y+066444X0198Y0197     S2      
327SW_P5V_AUX_PH    PU4   -1          A01X+007442Y+067084X0110Y0320     S1      
327SW_P5V_AUX_PH    PC19  -2          A01X+007397Y+066567X0198Y0197R090 S1      
327SW_P5V_AUX_PH    PL2   -1          A01X+006686Y+067178X0730Y1380R180 S1      
317SH_P3V3_AUX_FB   VIA   -    M      A01X+045355Y+063178X0200Y         S2      
017SH_P3V3_AUX_FB   VIA   -    M      A18X+045355Y+063178X0260Y         S2      
017SH_P3V3_AUX_FB         -    MD0100PA00X+045355Y+063178                       
327SH_P3V3_AUX_FB   PJ3   -1          A01X+045429Y+062904X0200Y0400     S1      
327SH_P3V3_AUX_FB   PR61  -1          A01X+045355Y+063828X0198Y0197R180 S1      
327SH_P3V3_AUX_FB   PC39  -2   M      A01X+045355Y+063428X0198Y0197     S1      
327m3254            PU5   -21         A01X+043376Y+062784X0120Y0790R180 S1      
327m3254            PU5   -10         A01X+043376Y+063808X0120Y0790R180 S1      
327m3254            PL3   -2          A01X+043434Y+069151X0420Y0990R270 S1      
327m3254            PC25  -1          A01X+044323Y+067304X0630Y1380R270 S1      
327m3254            PC24  -1          A01X+042673Y+067304X0630Y1380R090 S1      
327m3254            PC27  -1          A01X+043823Y+065454X0400Y0500R180 S1      
327m3254            PC29  -1          A01X+043823Y+064773X0400Y0500R180 S1      
327m3254            PC28  -1          A01X+042873Y+065454X0400Y0500     S1      
327m3254            PC26  -1          A01X+042873Y+064773X0400Y0500     S1      
327m3254            PC30  -1          A01X+043452Y+062046X0198Y0197     S1      
327P3V3_AUX_VCC     PU5   -19         A01X+042706Y+062627X0120Y0320R090 S1      
327P3V3_AUX_VCC     PC40  -1          A01X+042146Y+062575X0198Y0197R090 S1      
317P3V3_AUX_VCC     VIA   -    MD0100PA00X+042396Y+062578X0200Y    R270 S0      
327P3V3_AUX_VCC     VIA   -    M      A18X+046478Y+063651X0260Y         S2      
327P3V3_AUX_VCC     R823  -1          A18X+046478Y+064409X0198Y0197     S2      
327SW_P3V3_AUX_BT   PU5   -1          A01X+043789Y+062627X0120Y0360R270 S1      
327SW_P3V3_AUX_BT   PC31  -1          A01X+044306Y+062046X0198Y0197     S1      
327P3V3_AUX_REF     PU5   -5          A01X+043809Y+063296X0070Y0320R270 S1      
317P3V3_AUX_REF     VIA   -    M      A01X+044792Y+063079X0200Y         S2      
017P3V3_AUX_REF     VIA   -    M      A18X+044792Y+063079X0260Y         S2      
017P3V3_AUX_REF           -    MD0100PA00X+044792Y+063079                       
327P3V3_AUX_REF     PC42  -1          A01X+044974Y+062864X0198Y0197R270 S1      
327P3V3_AUX_EN      PU5   -8          A01X+043809Y+063768X0070Y0320R270 S1      
317P3V3_AUX_EN      VIA   -    M      A01X+044116Y+063831X0200Y    R270 S2      
017P3V3_AUX_EN      VIA   -    M      A18X+044116Y+063831X0260Y    R270 S2      
017P3V3_AUX_EN            -    MD0100PA00X+044116Y+063831                       
327P3V3_AUX_EN      R824  -1          A01X+044343Y+064088X0198Y0197     S1      
327P3V3_AUX_FB      PU5   -7          A01X+043809Y+063611X0070Y0320R270 S1      
317P3V3_AUX_FB      VIA   -    M      A01X+044728Y+063703X0200Y         S2      
017P3V3_AUX_FB      VIA   -    M      A18X+044728Y+063703X0260Y         S2      
017P3V3_AUX_FB            -    MD0100PA00X+044728Y+063703                       
327P3V3_AUX_FB      PC39  -1          A01X+045040Y+063428X0198Y0197     S1      
327P3V3_AUX_FB      PR61  -2   M      A01X+045040Y+063828X0198Y0197R180 S1      
327P3V3_AUX_FB      PR63  -2   M      A01X+044478Y+063703X0198Y0197R090 S1      
327SW_P3V3_AUX_PH   PU5   -20         A01X+043139Y+062784X0120Y0790R180 S1      
327SW_P3V3_AUX_PH   PC31  -2          A01X+044621Y+062046X0198Y0197     S1      
327SW_P3V3_AUX_PH   PL4   -1          A01X+043600Y+061055X1300Y1692R270 S1      
327PWRGD_P3V3_AUX   PU5   -9          A01X+043809Y+063965X0120Y0320R270 S1      
327PWRGD_P3V3_AUX   VIA   -    M      A18X+046163Y+064883X0260Y         S2      
327PWRGD_P3V3_AUX   R823  -2          A18X+046163Y+064409X0198Y0197     S2      
317PWRGD_P3V3_AUX   VIA   -    MD0100PA00X+044699Y+064336X0200Y         S0      
327PWRGD_P3V3_AUX   R4430 -1          A01X+045040Y+064259X0198Y0197     S1      
327P3V3_AUX_CS      PU5   -3          A01X+043809Y+062981X0070Y0320R270 S1      
317P3V3_AUX_CS      VIA   -    M      A01X+044314Y+062867X0200Y         S2      
017P3V3_AUX_CS      VIA   -    M      A18X+044314Y+062867X0260Y         S2      
017P3V3_AUX_CS            -    MD0100PA00X+044314Y+062867                       
327P3V3_AUX_CS      PR62  -1          A01X+044574Y+062864X0198Y0197R270 S1      
327P1V8_PEX_REF     PU20  -5          A01X+041094Y+087680X0070Y0320R090 S1      
327P1V8_PEX_REF     PC296 -1          A01X+039905Y+088120X0198Y0197R090 S1      
317P1V8_PEX_REF     VIA   -    M      A01X+040111Y+087849X0200Y         S2      
017P1V8_PEX_REF     VIA   -    M      A18X+040111Y+087849X0260Y         S2      
017P1V8_PEX_REF           -    MD0100PA00X+040111Y+087849                       
327P1V8_PEX_FB      PU20  -7          A01X+041094Y+087365X0070Y0320R090 S1      
317P1V8_PEX_FB      VIA   -           A01X+039743Y+087065X0200Y         S2      
017P1V8_PEX_FB      VIA   -           A18X+039743Y+087065X0260Y         S2      
017P1V8_PEX_FB            -     D0100PA00X+039743Y+087065                       
327P1V8_PEX_FB      PR186 -2   M      A01X+039937Y+087269X0198Y0197R270 S1      
327P1V8_PEX_FB      PR188 -2   M      A01X+040348Y+087269X0198Y0197R270 S1      
327P1V8_PEX_FB      PC297 -1          A01X+039539Y+087270X0198Y0197R090 S1      
317P1V8_PEX         VIA   -    MD0100PA00X+101285Y+072242X0200Y         S0      
317P1V8_PEX         VIA   -    MD0100PA00X+101464Y+072444X0200Y         S0      
317P1V8_PEX         VIA   -    MD0100PA00X+100956Y+072244X0200Y         S0      
317P1V8_PEX         VIA   -    MD0100PA00X+101118Y+072452X0200Y         S0      
327P1V8_PEX         R1038 -2          A18X+116420Y+079434X0198Y0197R090 S2      
317P1V8_PEX         VIA   -    MD0100PA00X+116492Y+079161X0200Y         S0      
327P1V8_PEX         R1037 -2          A18X+116970Y+079434X0198Y0197R090 S2      
317P1V8_PEX         VIA   -    MD0100PA00X+116970Y+079194X0200Y         S0      
327P1V8_PEX         C2108 -2   M      A01X+118072Y+078204X0198Y0197R090 S1      
327P1V8_PEX         U63   -16         A01X+117384Y+078629X0140Y0630R180 S1      
317P1V8_PEX         VIA   -    MD0100PA00X+117650Y+078493X0200Y         S0      
327P1V8_PEX         R1040 -2          A18X+114591Y+080664X0198Y0197     S2      
327P1V8_PEX         R1039 -2          A18X+114591Y+080064X0198Y0197     S2      
317P1V8_PEX         VIA   -    MD0100PA00X+114591Y+080364X0200Y         S0      
327P1V8_PEX         R6658 -2          A18X+112860Y+076886X0198Y0197     S2      
317P1V8_PEX         VIA   -    MD0100PA00X+008571Y+099851X0200Y         S0      
327P1V8_PEX         R6153 -2          A01X+008470Y+100139X0198Y0197R270 S1      
317P1V8_PEX         VIA   -    MD0100PA00X+006463Y+090150X0200Y         S0      
327P1V8_PEX         R3437 -1          A18X+005996Y+090150X0198Y0197     S2      
317P1V8_PEX         VIA   -    MD0100PA00X+012289Y+088800X0200Y         S0      
327P1V8_PEX         R6163 -2          A18X+011867Y+088884X0198Y0197R180 S2      
317P1V8_PEX         VIA   -    MD0100PA00X+010232Y+089104X0200Y         S0      
327P1V8_PEX         R3439 -1          A18X+009644Y+089030X0198Y0197R270 S2      
327P1V8_PEX         C2217 -2          A18X+009886Y+087519X0198Y0197R180 S2      
327P1V8_PEX         C2755 -2          A18X+009886Y+087919X0198Y0197R180 S2      
317P1V8_PEX         VIA   -    MD0100PA00X+010295Y+087720X0200Y         S0      
317P1V8_PEX         VIA   -    MD0100PA00X+010236Y+087427X0200Y         S0      
327P1V8_PEX         U317  -2   M      A01X+009693Y+087530X0320Y0750R090 S1      
327P1V8_PEX         JPEX0 -2   M      A01X+009693Y+087530X0200Y0600R090 S1      
327P1V8_PEX         R3438 -1          A18X+009906Y+087136X0198Y0197R090 S2      
327P1V8_PEX         C3173 -1          A18X+064060Y+118534X0120Y0150     S2      
327P1V8_PEX         C3176 -1          A18X+073202Y+113691X0120Y0150R180 S2      
327P1V8_PEX         C3177 -1          A18X+073202Y+114065X0120Y0150R180 S2      
327P1V8_PEX         C3167 -1          A18X+073202Y+114439X0120Y0150R180 S2      
327P1V8_PEX         C3168 -1          A18X+073038Y+118553X0120Y0150     S2      
327P1V8_PEX         C3166 -1          A18X+073038Y+118927X0120Y0150     S2      
327P1V8_PEX         C3165 -1          A18X+073038Y+119301X0120Y0150     S2      
327P1V8_PEX         C3352 -1          A18X+109022Y+116496X0120Y0150     S2      
327P1V8_PEX         C3348 -1          A18X+109022Y+116122X0120Y0150     S2      
327P1V8_PEX         C3335 -1          A18X+109022Y+115748X0120Y0150     S2      
327P1V8_PEX         C3354 -1          A18X+109022Y+115374X0120Y0150     S2      
327P1V8_PEX         C3349 -1          A18X+109022Y+115000X0120Y0150     S2      
327P1V8_PEX         VIA   -           A18X+108914Y+114252X0260Y         S2      
327P1V8_PEX         R6159 -2          A18X+107795Y+113533X0198Y0197R090 S2      
327P1V8_PEX         C3338 -1          A18X+108622Y+112541X0280Y0320R090 S2      
327P1V8_PEX         C3347 -1          A18X+109772Y+118520X0120Y0150     S2      
327P1V8_PEX         C3351 -1          A18X+118911Y+113691X0120Y0150R180 S2      
327P1V8_PEX         C3350 -1          A18X+118911Y+114065X0120Y0150R180 S2      
327P1V8_PEX         C3341 -1          A18X+118911Y+114439X0120Y0150R180 S2      
327P1V8_PEX         C3339 -1          A18X+118747Y+118553X0120Y0150     S2      
327P1V8_PEX         C3340 -1          A18X+118747Y+118927X0120Y0150     S2      
327P1V8_PEX         C3342 -1          A18X+118747Y+119301X0120Y0150     S2      
327P1V8_PEX         C3528 -1          A18X+164619Y+114065X0120Y0150R180 S2      
327P1V8_PEX         C3526 -1          A18X+164619Y+113691X0120Y0150R180 S2      
327P1V8_PEX         C3514 -1          A18X+164619Y+114439X0120Y0150R180 S2      
327P1V8_PEX         C3515 -1          A18X+164455Y+118553X0120Y0150     S2      
327P1V8_PEX         C3516 -1          A18X+164455Y+118927X0120Y0150     S2      
327P1V8_PEX         C3513 -1          A18X+164455Y+119301X0120Y0150     S2      
327P1V8_PEX         C3353 -1   M      A18X+109770Y+114258X0120Y0150     S2      
327P1V8_PEX         C3521 -1          A18X+155481Y+118520X0120Y0150     S2      
327P1V8_PEX         C3527 -1          A18X+154731Y+116496X0120Y0150     S2      
327P1V8_PEX         C3524 -1          A18X+154731Y+116122X0120Y0150     S2      
327P1V8_PEX         C3509 -1          A18X+154731Y+115748X0120Y0150     S2      
317P1V8_PEX         VIA   -    MD0080PA00X+155561Y+118553X0160Y         S0      
317P1V8_PEX         VIA   -    MD0080PA00X+154813Y+115935X0160Y         S0      
317P1V8_PEX         VIA   -    MD0080PA00X+154813Y+116683X0160Y         S0      
317P1V8_PEX         VIA   -    MD0080PA00X+154813Y+114439X0160Y         S0      
317P1V8_PEX         VIA   -    MD0080PA00X+154813Y+114813X0160Y         S0      
317P1V8_PEX         VIA   -    MD0080PA00X+154813Y+115187X0160Y         S0      
317P1V8_PEX         VIA   -    MD0080PA00X+155561Y+114439X0160Y         S0      
317P1V8_PEX         VIA   -    MD0080PA00X+164537Y+119301X0160Y         S0      
317P1V8_PEX         VIA   -    MD0080PA00X+164537Y+118927X0160Y         S0      
317P1V8_PEX         VIA   -    MD0080PA00X+164537Y+118553X0160Y         S0      
317P1V8_PEX         VIA   -    MD0080PA00X+164537Y+114439X0160Y         S0      
317P1V8_PEX         VIA   -    MD0080PA00X+164537Y+114065X0160Y         S0      
317P1V8_PEX         VIA   -    MD0080PA00X+164537Y+113691X0160Y         S0      
327P1V8_PEX         PEX3  -AK10       A01X+155000Y+114626X0180Y         S1      
327P1V8_PEX         PEX3  -AJ10       A01X+155000Y+115000X0180Y         S1      
327P1V8_PEX         PEX3  -AH10       A01X+155000Y+115374X0180Y         S1      
327P1V8_PEX         PEX3  -AK12       A01X+155748Y+114626X0180Y         S1      
327P1V8_PEX         PEX3  -AF10       A01X+155000Y+116122X0180Y         S1      
327P1V8_PEX         PEX3  -AE10       A01X+155000Y+116496X0180Y         S1      
327P1V8_PEX         PEX3  -AK35       A01X+164350Y+114626X0180Y         S1      
327P1V8_PEX         PEX3  -AM35M      A01X+164350Y+113878X0180Y         S1      
327P1V8_PEX         PEX3  -AL35M      A01X+164350Y+114252X0180Y         S1      
327P1V8_PEX         PEX3  -Y12        A01X+155748Y+118366X0180Y         S1      
327P1V8_PEX         PEX3  -W35        A01X+164350Y+118740X0180Y         S1      
327P1V8_PEX         PEX3  -Y35        A01X+164350Y+118366X0180Y         S1      
327P1V8_PEX         PEX3  -V35        A01X+164350Y+119114X0180Y         S1      
327P1V8_PEX         C3522 -1          A18X+154731Y+115374X0120Y0150     S2      
327P1V8_PEX         C3525 -1          A18X+154731Y+115000X0120Y0150     S2      
327P1V8_PEX         C3523 -1          A18X+155479Y+114439X0120Y0150     S2      
327P1V8_PEX         VIA   -           A18X+154622Y+114252X0260Y         S2      
327P1V8_PEX         R6160 -2          A18X+153504Y+113533X0198Y0197R090 S2      
327P1V8_PEX         C3512 -1          A18X+154331Y+112541X0280Y0320R090 S2      
327P1V8_PEX         C3002 -1          A18X+027493Y+113691X0120Y0150R180 S2      
327P1V8_PEX         C3003 -1          A18X+027493Y+114065X0120Y0150R180 S2      
327P1V8_PEX         C2994 -1          A18X+027493Y+114439X0120Y0150R180 S2      
327P1V8_PEX         C3001 -1          A18X+018355Y+118520X0120Y0150     S2      
327P1V8_PEX         C2993 -1          A18X+027329Y+119301X0120Y0150     S2      
327P1V8_PEX         C2992 -1          A18X+027329Y+118927X0120Y0150     S2      
327P1V8_PEX         C2991 -1          A18X+027329Y+118553X0120Y0150     S2      
327P1V8_PEX         PEX0  -V35        A01X+027224Y+119114X0180Y         S1      
317P1V8_PEX         VIA   -    MD0080PA00X+027411Y+119301X0160Y         S0      
327P1V8_PEX         PEX0  -Y35        A01X+027224Y+118366X0180Y         S1      
327P1V8_PEX         PEX0  -W35        A01X+027224Y+118740X0180Y         S1      
317P1V8_PEX         VIA   -    MD0080PA00X+027411Y+118927X0160Y         S0      
317P1V8_PEX         VIA   -    MD0080PA00X+027411Y+118553X0160Y         S0      
327P1V8_PEX         PEX0  -Y12        A01X+018622Y+118366X0180Y         S1      
317P1V8_PEX         VIA   -    MD0080PA00X+018435Y+118553X0160Y         S0      
327P1V8_PEX         PEX0  -AK35       A01X+027224Y+114626X0180Y         S1      
327P1V8_PEX         PEX0  -AL35M      A01X+027224Y+114252X0180Y         S1      
327P1V8_PEX         PEX0  -AM35M      A01X+027224Y+113878X0180Y         S1      
317P1V8_PEX         VIA   -    MD0080PA00X+027411Y+113691X0160Y         S0      
317P1V8_PEX         VIA   -    MD0080PA00X+027411Y+114065X0160Y         S0      
317P1V8_PEX         VIA   -    MD0080PA00X+027411Y+114439X0160Y         S0      
317P1V8_PEX         VIA   -    MD0080PA00X+107608Y+111821X0160Y    R090 S0      
317P1V8_PEX         VIA   -    MD0080PA00X+107608Y+112195X0160Y    R090 S0      
317P1V8_PEX         VIA   -    MD0080PA00X+109104Y+114439X0160Y         S0      
317P1V8_PEX         VIA   -    MD0080PA00X+109104Y+114813X0160Y         S0      
317P1V8_PEX         VIA   -    MD0080PA00X+109104Y+115187X0160Y         S0      
317P1V8_PEX         VIA   -    MD0080PA00X+107982Y+111821X0160Y    R090 S0      
317P1V8_PEX         VIA   -    MD0080PA00X+109104Y+115935X0160Y         S0      
317P1V8_PEX         VIA   -    MD0080PA00X+109104Y+116683X0160Y         S0      
317P1V8_PEX         VIA   -    MD0080PA00X+109852Y+114439X0160Y         S0      
317P1V8_PEX         VIA   -    MD0080PA00X+109852Y+118553X0160Y         S0      
317P1V8_PEX         VIA   -    MD0080PA00X+118829Y+114439X0160Y         S0      
317P1V8_PEX         VIA   -    MD0080PA00X+118829Y+114065X0160Y         S0      
317P1V8_PEX         VIA   -    MD0080PA00X+118829Y+113691X0160Y         S0      
317P1V8_PEX         VIA   -    MD0080PA00X+118829Y+119301X0160Y         S0      
317P1V8_PEX         VIA   -    MD0080PA00X+118829Y+118927X0160Y         S0      
317P1V8_PEX         VIA   -    MD0080PA00X+118829Y+118553X0160Y         S0      
317P1V8_PEX         VIA   -    MD0080PA00X+119577Y+111821X0160Y    R270 S0      
317P1V8_PEX         VIA   -    MD0080PA00X+119951Y+111821X0160Y    R270 S0      
317P1V8_PEX         VIA   -    MD0080PA00X+153317Y+112195X0160Y    R090 S0      
317P1V8_PEX         VIA   -    MD0080PA00X+153317Y+111821X0160Y    R090 S0      
317P1V8_PEX         VIA   -    MD0080PA00X+153691Y+111821X0160Y    R090 S0      
317P1V8_PEX         VIA   -    MD0080PA00X+165285Y+111821X0160Y    R270 S0      
317P1V8_PEX         VIA   -    MD0080PA00X+165659Y+111821X0160Y    R270 S0      
317P1V8_PEX         VIA   -    MD0080PA00X+016191Y+112195X0160Y         S0      
317P1V8_PEX         VIA   -    MD0080PA00X+016191Y+111821X0160Y         S0      
317P1V8_PEX         VIA   -    MD0080PA00X+017687Y+115935X0160Y         S0      
317P1V8_PEX         VIA   -    MD0080PA00X+017687Y+116683X0160Y         S0      
317P1V8_PEX         VIA   -    MD0080PA00X+017687Y+114439X0160Y         S0      
317P1V8_PEX         VIA   -    MD0080PA00X+017687Y+114813X0160Y         S0      
317P1V8_PEX         VIA   -    MD0080PA00X+017687Y+115187X0160Y         S0      
317P1V8_PEX         VIA   -    MD0080PA00X+018435Y+114439X0160Y         S0      
317P1V8_PEX         VIA   -    MD0080PA00X+028159Y+111821X0160Y    R270 S0      
317P1V8_PEX         VIA   -    MD0080PA00X+028533Y+111821X0160Y    R270 S0      
317P1V8_PEX         VIA   -    MD0080PA00X+061900Y+112195X0160Y    R090 S0      
317P1V8_PEX         VIA   -    MD0080PA00X+061900Y+111821X0160Y    R090 S0      
317P1V8_PEX         VIA   -    MD0080PA00X+063396Y+115935X0160Y         S0      
317P1V8_PEX         VIA   -    MD0080PA00X+063396Y+116683X0160Y         S0      
317P1V8_PEX         VIA   -    MD0080PA00X+063396Y+114439X0160Y         S0      
317P1V8_PEX         VIA   -    MD0080PA00X+063396Y+114813X0160Y         S0      
317P1V8_PEX         VIA   -    MD0080PA00X+063396Y+115187X0160Y         S0      
317P1V8_PEX         VIA   -    MD0080PA00X+062274Y+111821X0160Y    R090 S0      
317P1V8_PEX         VIA   -    MD0080PA00X+064144Y+118553X0160Y         S0      
317P1V8_PEX         VIA   -    MD0080PA00X+064144Y+114439X0160Y         S0      
317P1V8_PEX         VIA   -    MD0080PA00X+073120Y+114439X0160Y         S0      
317P1V8_PEX         VIA   -    MD0080PA00X+073120Y+114065X0160Y         S0      
317P1V8_PEX         VIA   -    MD0080PA00X+073120Y+113691X0160Y         S0      
317P1V8_PEX         VIA   -    MD0080PA00X+073120Y+119301X0160Y         S0      
317P1V8_PEX         VIA   -    MD0080PA00X+073120Y+118553X0160Y         S0      
317P1V8_PEX         VIA   -    MD0080PA00X+073120Y+118927X0160Y         S0      
317P1V8_PEX         VIA   -    MD0080PA00X+074242Y+111821X0160Y    R270 S0      
317P1V8_PEX         VIA   -    MD0080PA00X+073868Y+111821X0160Y    R270 S0      
327P1V8_PEX         R6657 -2          A01X+071016Y+072805X0198Y0197     S1      
327P1V8_PEX         VIA   -    M      A01X+072114Y+073073X0300Y         S1      
317P1V8_PEX         VIA   -    MD0100PA00X+072567Y+073216X0200Y         S0      
327P1V8_PEX         C4185 -2   M      A01X+033763Y+117575X0198Y0197R270 S1      
327P1V8_PEX         U425  -8          A01X+033871Y+116781X0140Y0520     S1      
317P1V8_PEX         VIA   -    MD0100PA00X+033080Y+117450X0200Y         S0      
317P1V8_PEX         VIA   -    MD0100PA00X+035706Y+117954X0200Y         S0      
327P1V8_PEX         R4014 -1          A01X+035441Y+117824X0198Y0197R270 S1      
327P1V8_PEX         R4013 -1          A01X+035844Y+117726X0198Y0197R270 S1      
327P1V8_PEX         U320  -2   M      A01X+055387Y+087530X0320Y0750R090 S1      
327P1V8_PEX         R6154 -2          A01X+053672Y+100625X0198Y0197R270 S1      
317P1V8_PEX         VIA   -    MD0100PA00X+128069Y+120899X0200Y         S0      
327P1V8_PEX         R1369 -2          A01X+126713Y+122925X0198Y0197R135 S1      
327P1V8_PEX         R1374 -2   M      A01X+126430Y+122642X0198Y0197R135 S1      
327P1V8_PEX         R1372 -2   M      A01X+126147Y+122359X0198Y0197R135 S1      
327P1V8_PEX         R1377 -2   M      A01X+125864Y+122076X0198Y0197R135 S1      
327P1V8_PEX         R1370 -2   M      A01X+126458Y+120659X0198Y0197R090 S1      
327P1V8_PEX         R1371 -2   M      A01X+126858Y+120659X0198Y0197R090 S1      
327P1V8_PEX         R4181 -2   M      A01X+128058Y+120659X0198Y0197R090 S1      
327P1V8_PEX         R1373 -2   M      A01X+127258Y+120659X0198Y0197R090 S1      
327P1V8_PEX         R1376 -2   M      A01X+127658Y+120659X0198Y0197R090 S1      
327P1V8_PEX         R3945 -2          A01X+127605Y+122124X0198Y0197R315 S1      
317P1V8_PEX         VIA   -    MD0100PA00X+127125Y+117824X0200Y         S0      
327P1V8_PEX         R4018 -1          A01X+126859Y+117824X0198Y0197R270 S1      
327P1V8_PEX         R4017 -1          A01X+127391Y+117829X0198Y0197R270 S1      
327P1V8_PEX         C4187 -2   M      A01X+125180Y+117575X0198Y0197R270 S1      
317P1V8_PEX         VIA   -    MD0100PA00X+124936Y+117306X0200Y         S0      
327P1V8_PEX         U427  -8          A01X+125288Y+116781X0140Y0520     S1      
317P1V8_PEX         VIA   -    MD0100PA00X+128031Y+117077X0200Y         S0      
327P1V8_PEX         C2782 -2   M      A01X+128031Y+116837X0198Y0197R090 S1      
327P1V8_PEX         U315  -1          A01X+127516Y+116397X0240Y0460     S1      
317P1V8_PEX         VIA   -           A01X+081942Y+123026X0200Y         S2      
017P1V8_PEX         VIA   -           A18X+081942Y+123026X0260Y         S2      
017P1V8_PEX               -     D0100PA00X+081942Y+123026                       
317P1V8_PEX         VIA   -    MD0100PA00X+082361Y+120899X0200Y         S0      
327P1V8_PEX         R1305 -2   M      A01X+080438Y+122359X0198Y0197R135 S1      
327P1V8_PEX         R1304 -2   M      A01X+081149Y+120659X0198Y0197R090 S1      
327P1V8_PEX         R1306 -2   M      A01X+081549Y+120659X0198Y0197R090 S1      
327P1V8_PEX         R3944 -2          A01X+081897Y+122124X0198Y0197R315 S1      
327P1V8_PEX         R1309 -2   M      A01X+081949Y+120659X0198Y0197R090 S1      
327P1V8_PEX         R4177 -2   M      A01X+082349Y+120659X0198Y0197R090 S1      
327P1V8_PEX         R1310 -2   M      A01X+080155Y+122076X0198Y0197R135 S1      
327P1V8_PEX         R1303 -2   M      A01X+080749Y+120659X0198Y0197R090 S1      
327P1V8_PEX         R1302 -2   M      A01X+081004Y+122925X0198Y0197R135 S1      
327P1V8_PEX         R1307 -2   M      A01X+080721Y+122642X0198Y0197R135 S1      
317P1V8_PEX         VIA   -    MD0100PA00X+081416Y+117824X0200Y         S0      
327P1V8_PEX         R4016 -1          A01X+081150Y+117824X0198Y0197R270 S1      
327P1V8_PEX         R4015 -1          A01X+081683Y+117829X0198Y0197R270 S1      
317P1V8_PEX         VIA   -    MD0100PA00X+082322Y+117077X0200Y         S0      
327P1V8_PEX         C2757 -2   M      A01X+082322Y+116837X0198Y0197R090 S1      
327P1V8_PEX         U314  -1          A01X+081807Y+116397X0240Y0460     S1      
317P1V8_PEX         VIA   -    MD0100PA00X+078905Y+102615X0200Y         S0      
327P1V8_PEX         R6336 -1          A18X+078366Y+102249X0198Y0197R090 S2      
317P1V8_PEX         VIA   -    MD0100PA00X+079563Y+102544X0200Y         S0      
327P1V8_PEX         R6337 -1          A18X+079563Y+102249X0198Y0197R090 S2      
317P1V8_PEX         VIA   -    MD0100PA00X+080367Y+102544X0200Y         S0      
327P1V8_PEX         R6349 -1          A18X+083167Y+102249X0198Y0197R090 S2      
327P1V8_PEX         R6348 -1   M      A18X+082767Y+102249X0198Y0197R090 S2      
327P1V8_PEX         R6347 -1   M      A18X+082367Y+102249X0198Y0197R090 S2      
327P1V8_PEX         R6346 -1   M      A18X+081967Y+102249X0198Y0197R090 S2      
327P1V8_PEX         R6345 -1   M      A18X+081567Y+102249X0198Y0197R090 S2      
327P1V8_PEX         R6344 -1   M      A18X+081167Y+102249X0198Y0197R090 S2      
327P1V8_PEX         R6343 -1   M      A18X+080767Y+102249X0198Y0197R090 S2      
327P1V8_PEX         R6342 -1   M      A18X+080367Y+102249X0198Y0197R090 S2      
327P1V8_PEX         U316  -1          A01X+173224Y+116397X0240Y0460     S1      
327P1V8_PEX         U313  -1          A01X+036098Y+116397X0240Y0460     S1      
317P1V8_PEX         VIA   -    MD0100PA00X+007102Y+122432X0200Y         S0      
327P1V8_PEX         R1257 -2   M      A01X+011803Y+122332X0198Y0197R225 S1      
327P1V8_PEX         R1111 -2          A01X+012085Y+122050X0198Y0197R225 S1      
327P1V8_PEX         R1259 -2   M      A01X+012651Y+121484X0198Y0197R225 S1      
327P1V8_PEX         R1118 -2          A01X+012934Y+121201X0198Y0197R225 S1      
327P1V8_PEX         R1241 -2   M      A01X+011519Y+120222X0198Y0197R225 S1      
327P1V8_PEX         R1086 -2   M      A01X+010671Y+121071X0198Y0197R225 S1      
327P1V8_PEX         R4360 -1   M      A01X+010353Y+121389X0198Y0197R045 S1      
327P1V8_PEX         R1093 -2   M      A01X+010960Y+122345X0198Y0197R270 S1      
327P1V8_PEX         R1258 -2   M      A01X+010560Y+122345X0198Y0197R270 S1      
317P1V8_PEX         VIA   -    MD0100PA00X+010276Y+109623X0200Y         S0      
327P1V8_PEX         PEX2  -AH10       A01X+109291Y+115374X0180Y         S1      
327P1V8_PEX         PEX2  -AJ10       A01X+109291Y+115000X0180Y         S1      
327P1V8_PEX         PEX2  -AK10       A01X+109291Y+114626X0180Y         S1      
327P1V8_PEX         PEX2  -AK12       A01X+110039Y+114626X0180Y         S1      
327P1V8_PEX         PEX2  -AE10       A01X+109291Y+116496X0180Y         S1      
327P1V8_PEX         PEX2  -AF10       A01X+109291Y+116122X0180Y         S1      
327P1V8_PEX         PEX2  -AM35M      A01X+118642Y+113878X0180Y         S1      
327P1V8_PEX         PEX2  -AL35M      A01X+118642Y+114252X0180Y         S1      
327P1V8_PEX         PEX2  -AK35       A01X+118642Y+114626X0180Y         S1      
327P1V8_PEX         PEX2  -Y12        A01X+110039Y+118366X0180Y         S1      
327P1V8_PEX         PEX2  -Y35        A01X+118642Y+118366X0180Y         S1      
327P1V8_PEX         PEX2  -W35        A01X+118642Y+118740X0180Y         S1      
327P1V8_PEX         PEX2  -V35        A01X+118642Y+119114X0180Y         S1      
317P1V8_PEX         VIA   -    MD0100PA00X+129589Y+112218X0200Y         S0      
317P1V8_PEX         VIA   -    MD0100PA00X+129582Y+112494X0200Y         S0      
327P1V8_PEX         C2761 -2   M      A01X+173739Y+116837X0198Y0197R090 S1      
317P1V8_PEX         VIA   -    MD0100PA00X+173739Y+117077X0200Y         S0      
327P1V8_PEX         R4020 -1          A01X+172567Y+117824X0198Y0197R270 S1      
327P1V8_PEX         R4019 -1          A01X+173100Y+117829X0198Y0197R270 S1      
317P1V8_PEX         VIA   -    MD0100PA00X+172833Y+117824X0200Y         S0      
327P1V8_PEX         R1443 -2   M      A01X+172138Y+122642X0198Y0197R135 S1      
327P1V8_PEX         R1438 -2          A01X+172421Y+122925X0198Y0197R135 S1      
327P1V8_PEX         R1446 -2   M      A01X+171573Y+122076X0198Y0197R135 S1      
327P1V8_PEX         R1441 -2   M      A01X+171856Y+122359X0198Y0197R135 S1      
327P1V8_PEX         R1439 -2   M      A01X+172166Y+120659X0198Y0197R090 S1      
327P1V8_PEX         R4183 -2   M      A01X+173766Y+120659X0198Y0197R090 S1      
327P1V8_PEX         R3946 -2          A01X+173314Y+122124X0198Y0197R315 S1      
327P1V8_PEX         R1445 -2   M      A01X+173366Y+120659X0198Y0197R090 S1      
327P1V8_PEX         R1442 -2   M      A01X+172966Y+120659X0198Y0197R090 S1      
327P1V8_PEX         R1440 -2   M      A01X+172566Y+120659X0198Y0197R090 S1      
317P1V8_PEX         VIA   -    MD0100PA00X+173778Y+120899X0200Y         S0      
327P1V8_PEX         R1444 -2   M      A01X+148645Y+120222X0198Y0197R225 S1      
327P1V8_PEX         R1460 -2   M      A01X+148929Y+122332X0198Y0197R225 S1      
327P1V8_PEX         R1462 -2   M      A01X+149777Y+121484X0198Y0197R225 S1      
327P1V8_PEX         R1401 -2          A01X+150060Y+121201X0198Y0197R225 S1      
327P1V8_PEX         R1400 -2          A01X+149211Y+122050X0198Y0197R225 S1      
327P1V8_PEX         R1398 -2   M      A01X+147797Y+121071X0198Y0197R225 S1      
327P1V8_PEX         R1461 -2   M      A01X+147686Y+122345X0198Y0197R270 S1      
327P1V8_PEX         R4363 -1   M      A01X+147479Y+121389X0198Y0197R045 S1      
327P1V8_PEX         R1399 -2   M      A01X+148086Y+122345X0198Y0197R270 S1      
317P1V8_PEX         VIA   -    MD0100PA00X+148270Y+120000X0200Y         S0      
317P1V8_PEX         VIA   -    MD0100PA00X+147137Y+111865X0200Y         S0      
327P1V8_PEX         PEX1  -V35        A01X+072933Y+119114X0180Y         S1      
327P1V8_PEX         PEX1  -W35        A01X+072933Y+118740X0180Y         S1      
327P1V8_PEX         PEX1  -Y35        A01X+072933Y+118366X0180Y         S1      
327P1V8_PEX         PEX1  -Y12        A01X+064331Y+118366X0180Y         S1      
327P1V8_PEX         PEX1  -AK35       A01X+072933Y+114626X0180Y         S1      
327P1V8_PEX         PEX1  -AL35M      A01X+072933Y+114252X0180Y         S1      
327P1V8_PEX         PEX1  -AM35M      A01X+072933Y+113878X0180Y         S1      
327P1V8_PEX         C2987 -1          A18X+017605Y+115748X0120Y0150     S2      
327P1V8_PEX         C3005 -1          A18X+017605Y+116122X0120Y0150     S2      
327P1V8_PEX         C3000 -1          A18X+017605Y+116496X0120Y0150     S2      
327P1V8_PEX         PEX0  -AE10       A01X+017874Y+116496X0180Y         S1      
327P1V8_PEX         PEX0  -AF10       A01X+017874Y+116122X0180Y         S1      
327P1V8_PEX         C3006 -1          A18X+018353Y+114439X0120Y0150     S2      
327P1V8_PEX         PEX0  -AK12       A01X+018622Y+114626X0180Y         S1      
327P1V8_PEX         C3004 -1          A18X+017605Y+115374X0120Y0150     S2      
327P1V8_PEX         C2999 -1          A18X+017605Y+115000X0120Y0150     S2      
327P1V8_PEX         PEX0  -AH10       A01X+017874Y+115374X0180Y         S1      
327P1V8_PEX         PEX0  -AJ10       A01X+017874Y+115000X0180Y         S1      
327P1V8_PEX         PEX0  -AK10       A01X+017874Y+114626X0180Y         S1      
327P1V8_PEX         C2990 -1          A18X+017205Y+112541X0280Y0320R090 S2      
327P1V8_PEX         VIA   -           A18X+017869Y+113504X0260Y         S2      
327P1V8_PEX         R6157 -2          A18X+016354Y+113533X0198Y0197R090 S2      
327P1V8_PEX         C3162 -1          A18X+063314Y+115748X0120Y0150     S2      
327P1V8_PEX         C3179 -1          A18X+063314Y+116122X0120Y0150     S2      
327P1V8_PEX         C3175 -1          A18X+063314Y+116496X0120Y0150     S2      
327P1V8_PEX         PEX1  -AE10       A01X+063583Y+116496X0180Y         S1      
327P1V8_PEX         PEX1  -AF10       A01X+063583Y+116122X0180Y         S1      
327P1V8_PEX         PEX1  -AK12       A01X+064331Y+114626X0180Y         S1      
327P1V8_PEX         C3180 -1          A18X+064062Y+114439X0120Y0150     S2      
327P1V8_PEX         C3174 -1          A18X+063314Y+115000X0120Y0150     S2      
327P1V8_PEX         C3178 -1          A18X+063314Y+115374X0120Y0150     S2      
327P1V8_PEX         PEX1  -AH10       A01X+063583Y+115374X0180Y         S1      
327P1V8_PEX         PEX1  -AJ10       A01X+063583Y+115000X0180Y         S1      
327P1V8_PEX         PEX1  -AK10       A01X+063583Y+114626X0180Y         S1      
327P1V8_PEX         C3161 -1          A18X+063095Y+112606X0280Y0320R090 S2      
327P1V8_PEX         VIA   -           A18X+063207Y+114249X0260Y         S2      
327P1V8_PEX         R6158 -2          A18X+062087Y+113533X0198Y0197R090 S2      
317P1V8_PEX         VIA   -    MD0100PA00X+037250Y+112370X0200Y         S0      
327P1V8_PEX         C2781 -2   M      A01X+036613Y+116837X0198Y0197R090 S1      
317P1V8_PEX         VIA   -    MD0100PA00X+036613Y+117077X0200Y         S0      
317P1V8_PEX         VIA   -    MD0100PA00X+056853Y+120000X0200Y         S0      
327P1V8_PEX         R1263 -2   M      A01X+056669Y+122345X0198Y0197R270 S1      
327P1V8_PEX         R4361 -1   M      A01X+056061Y+121389X0198Y0197R045 S1      
327P1V8_PEX         R1325 -2   M      A01X+056269Y+122345X0198Y0197R270 S1      
327P1V8_PEX         R1262 -2   M      A01X+056380Y+121071X0198Y0197R225 S1      
327P1V8_PEX         R1308 -2   M      A01X+057228Y+120222X0198Y0197R225 S1      
327P1V8_PEX         R1264 -2          A01X+057794Y+122050X0198Y0197R225 S1      
327P1V8_PEX         R1324 -2   M      A01X+057511Y+122332X0198Y0197R225 S1      
327P1V8_PEX         R1265 -2          A01X+058643Y+121201X0198Y0197R225 S1      
327P1V8_PEX         R1326 -2   M      A01X+058360Y+121484X0198Y0197R225 S1      
317P1V8_PEX         VIA   -    MD0100PA00X+055649Y+111835X0200Y         S0      
327P1V8_PEX         R1240 -2   M      A01X+035012Y+122642X0198Y0197R135 S1      
327P1V8_PEX         R1235 -2   M      A01X+035295Y+122925X0198Y0197R135 S1      
327P1V8_PEX         R1238 -2   M      A01X+034730Y+122359X0198Y0197R135 S1      
327P1V8_PEX         R1237 -2   M      A01X+035440Y+120659X0198Y0197R090 S1      
327P1V8_PEX         R1236 -2   M      A01X+035040Y+120659X0198Y0197R090 S1      
327P1V8_PEX         R3943 -2          A01X+036188Y+122124X0198Y0197R315 S1      
327P1V8_PEX         R4179 -2   M      A01X+036640Y+120659X0198Y0197R090 S1      
327P1V8_PEX         R1242 -2   M      A01X+036240Y+120659X0198Y0197R090 S1      
327P1V8_PEX         R1239 -2   M      A01X+035840Y+120659X0198Y0197R090 S1      
327P1V8_PEX         R1243 -2   M      A01X+034447Y+122076X0198Y0197R135 S1      
317P1V8_PEX         VIA   -    MD0100PA00X+036652Y+120899X0200Y         S0      
317P1V8_PEX         VIA   -           A01X+036233Y+123026X0200Y         S2      
017P1V8_PEX         VIA   -           A18X+036233Y+123026X0260Y         S2      
017P1V8_PEX               -     D0100PA00X+036233Y+123026                       
317P1V8_PEX         VIA   -    MD0100PA00X+103950Y+109876X0200Y         S0      
327P1V8_PEX         R1330 -2   M      A01X+102377Y+122345X0198Y0197R270 S1      
327P1V8_PEX         R1394 -2   M      A01X+101977Y+122345X0198Y0197R270 S1      
327P1V8_PEX         R1393 -2   M      A01X+103220Y+122332X0198Y0197R225 S1      
327P1V8_PEX         R1331 -2          A01X+103503Y+122050X0198Y0197R225 S1      
327P1V8_PEX         R1375 -2   M      A01X+102937Y+120222X0198Y0197R225 S1      
327P1V8_PEX         R1395 -2   M      A01X+104068Y+121484X0198Y0197R225 S1      
327P1V8_PEX         R1332 -2          A01X+104351Y+121201X0198Y0197R225 S1      
327P1V8_PEX         R1329 -2   M      A01X+102088Y+121071X0198Y0197R225 S1      
327P1V8_PEX         R4362 -1   M      A01X+101770Y+121389X0198Y0197R045 S1      
317P1V8_PEX         VIA   -    MD0100PA00X+102980Y+122092X0200Y    R315 S0      
317P1V8_PEX         VIA   -    MD0100PA00X+133397Y+103348X0200Y         S0      
327P1V8_PEX         R4385 -2          A01X+129408Y+091950X0198Y0197     S1      
317P1V8_PEX         VIA   -    MD0100PA00X+129408Y+091700X0200Y         S0      
327P1V8_PEX         R6156 -2          A01X+145596Y+100139X0198Y0197R270 S1      
317P1V8_PEX         VIA   -    MD0100PA00X+145697Y+099851X0200Y         S0      
317P1V8_PEX         VIA   -    MD0100PA00X+061888Y+101191X0200Y         S0      
327P1V8_PEX         R1269 -2   M      A01X+057692Y+098296X0198Y0197R270 S1      
327P1V8_PEX         R1272 -2   M      A01X+057292Y+098296X0198Y0197R270 S1      
327P1V8_PEX         R1277 -2   M      A01X+058492Y+098296X0198Y0197R270 S1      
327P1V8_PEX         R1273 -2   M      A01X+058092Y+098296X0198Y0197R270 S1      
327P1V8_PEX         R1280 -2   M      A01X+059292Y+098296X0198Y0197R270 S1      
327P1V8_PEX         R1266 -2   M      A01X+058892Y+098296X0198Y0197R270 S1      
327P1V8_PEX         R1268 -2   M      A01X+060892Y+098296X0198Y0197R270 S1      
327P1V8_PEX         R1279 -2   M      A01X+060492Y+098296X0198Y0197R270 S1      
327P1V8_PEX         R1270 -2          A01X+061692Y+098296X0198Y0197R270 S1      
327P1V8_PEX         R3961 -2          A01X+061292Y+099196X0198Y0197R270 S1      
327P1V8_PEX         R1275 -2   M      A01X+060092Y+098296X0198Y0197R270 S1      
327P1V8_PEX         R1281 -2   M      A01X+059692Y+098296X0198Y0197R270 S1      
327P1V8_PEX         R1267 -2   M      A01X+056892Y+098296X0198Y0197R270 S1      
327P1V8_PEX         R1274 -2   M      A01X+056492Y+098296X0198Y0197R270 S1      
327P1V8_PEX         R1271 -2   M      A01X+056092Y+098296X0198Y0197R270 S1      
327P1V8_PEX         R1276 -2   M      A01X+055692Y+098296X0198Y0197R270 S1      
327P1V8_PEX         R1278 -2          A01X+055292Y+098296X0198Y0197R270 S1      
317P1V8_PEX         VIA   -    MD0100PA00X+055692Y+098052X0200Y         S0      
317P1V8_PEX         VIA   -    MD0100PA00X+056092Y+098044X0200Y         S0      
317P1V8_PEX         VIA   -    MD0100PA00X+054279Y+099851X0200Y         S0      
317P1V8_PEX         VIA   -    MD0100PA00X+041716Y+096226X0200Y    R270 S0      
317P1V8_PEX         VIA   -    MD0100PA00X+041456Y+096226X0200Y    R270 S0      
317P1V8_PEX         VIA   -    MD0100PA00X+041196Y+096226X0200Y    R270 S0      
317P1V8_PEX         VIA   -    MD0100PA00X+041388Y+097811X0200Y    R270 S0      
317P1V8_PEX         VIA   -    MD0100PA00X+041648Y+097811X0200Y    R270 S0      
317P1V8_PEX         VIA   -    MD0100PA00X+041128Y+097811X0200Y    R270 S0      
317P1V8_PEX         VIA   -    MD0100PA00X+040418Y+097248X0200Y    R180 S0      
317P1V8_PEX         VIA   -    MD0100PA00X+040418Y+096998X0200Y    R180 S0      
317P1V8_PEX         VIA   -    MD0100PA00X+040418Y+097508X0200Y    R180 S0      
317P1V8_PEX         VIA   -    MD0100PA00X+040418Y+097768X0200Y    R180 S0      
317P1V8_PEX         VIA   -    MD0100PA00X+040435Y+098297X0200Y    R270 S0      
317P1V8_PEX         VIA   -    MD0100PA00X+040955Y+098297X0200Y    R270 S0      
317P1V8_PEX         VIA   -    MD0100PA00X+040695Y+098297X0200Y    R270 S0      
317P1V8_PEX         VIA   -    MD0100PA00X+010397Y+097761X0200Y         S0      
327P1V8_PEX         R1155 -2   M      A01X+011584Y+098296X0198Y0197R270 S1      
327P1V8_PEX         R1126 -2   M      A01X+011184Y+098296X0198Y0197R270 S1      
327P1V8_PEX         R1157 -2   M      A01X+010784Y+098296X0198Y0197R270 S1      
327P1V8_PEX         R1154 -2   M      A01X+010384Y+098296X0198Y0197R270 S1      
327P1V8_PEX         R1119 -2   M      A01X+013184Y+098296X0198Y0197R270 S1      
327P1V8_PEX         R1160 -2   M      A01X+012784Y+098296X0198Y0197R270 S1      
327P1V8_PEX         R1156 -2   M      A01X+012384Y+098296X0198Y0197R270 S1      
327P1V8_PEX         R1152 -2   M      A01X+011984Y+098296X0198Y0197R270 S1      
327P1V8_PEX         R1153 -2          A01X+015984Y+098296X0198Y0197R270 S1      
327P1V8_PEX         R3954 -2          A01X+015584Y+099196X0198Y0197R270 S1      
327P1V8_PEX         R1127 -2   M      A01X+015184Y+098296X0198Y0197R270 S1      
327P1V8_PEX         R1164 -2   M      A01X+014784Y+098296X0198Y0197R270 S1      
327P1V8_PEX         R1158 -2   M      A01X+014384Y+098296X0198Y0197R270 S1      
327P1V8_PEX         R1166 -2   M      A01X+013984Y+098296X0198Y0197R270 S1      
327P1V8_PEX         R1165 -2   M      A01X+013584Y+098296X0198Y0197R270 S1      
327P1V8_PEX         R1159 -2   M      A01X+009984Y+098296X0198Y0197R270 S1      
327P1V8_PEX         R1161 -2          A01X+009584Y+098296X0198Y0197R270 S1      
317P1V8_PEX         VIA   -    MD0100PA00X+010384Y+098033X0200Y         S0      
317P1V8_PEX         VIA   -    MD0100PA00X+010006Y+097765X0200Y         S0      
317P1V8_PEX         VIA   -    MD0100PA00X+009984Y+098033X0200Y         S0      
327P1V8_PEX         R822  -1          A01X+040404Y+096748X0198Y0197R270 S1      
327P1V8_PEX         R815  -1          A01X+041481Y+096979X1150Y1380R270 S1      
317P1V8_PEX         VIA   -    MD0100PA00X+009045Y+103354X0200Y         S0      
317P1V8_PEX         VIA   -    MD0100PA00X+078789Y+117450X0200Y         S0      
327P1V8_PEX         U426  -8          A01X+079579Y+116781X0140Y0520     S1      
327P1V8_PEX         C4186 -2   M      A01X+079472Y+117575X0198Y0197R270 S1      
317P1V8_PEX         VIA   -    MD0100PA00X+170340Y+117440X0200Y         S0      
327P1V8_PEX         U428  -8          A01X+170997Y+116781X0140Y0520     S1      
327P1V8_PEX         C4188 -2   M      A01X+170889Y+117575X0198Y0197R270 S1      
327P1V8_PEX         R3965 -2          A01X+152710Y+099196X0198Y0197R270 S1      
327P1V8_PEX         R1406 -2          A01X+153110Y+098296X0198Y0197R270 S1      
327P1V8_PEX         R1404 -2   M      A01X+152310Y+098296X0198Y0197R270 S1      
327P1V8_PEX         R1411 -2   M      A01X+151510Y+098296X0198Y0197R270 S1      
327P1V8_PEX         R1415 -2   M      A01X+151910Y+098296X0198Y0197R270 S1      
327P1V8_PEX         R1416 -2   M      A01X+150710Y+098296X0198Y0197R270 S1      
327P1V8_PEX         R1417 -2   M      A01X+151110Y+098296X0198Y0197R270 S1      
327P1V8_PEX         R1402 -2   M      A01X+150310Y+098296X0198Y0197R270 S1      
327P1V8_PEX         R1413 -2   M      A01X+149910Y+098296X0198Y0197R270 S1      
327P1V8_PEX         R1409 -2   M      A01X+149510Y+098296X0198Y0197R270 S1      
327P1V8_PEX         R1405 -2   M      A01X+149110Y+098296X0198Y0197R270 S1      
327P1V8_PEX         R1408 -2   M      A01X+148710Y+098296X0198Y0197R270 S1      
327P1V8_PEX         R1403 -2   M      A01X+148310Y+098296X0198Y0197R270 S1      
327P1V8_PEX         R1407 -2   M      A01X+147510Y+098296X0198Y0197R270 S1      
327P1V8_PEX         R1412 -2   M      A01X+147110Y+098296X0198Y0197R270 S1      
327P1V8_PEX         R1414 -2          A01X+146710Y+098296X0198Y0197R270 S1      
327P1V8_PEX         R1410 -2   M      A01X+147910Y+098296X0198Y0197R270 S1      
317P1V8_PEX         VIA   -    MD0100PA00X+147110Y+098033X0200Y         S0      
317P1V8_PEX         VIA   -    MD0100PA00X+147510Y+098033X0200Y         S0      
327P1V8_PEX         R937  -2          A18X+153324Y+097150X0198Y0197R090 S2      
317P1V8_PEX         VIA   -    MD0100PA00X+153077Y+097298X0200Y         S0      
327P1V8_PEX         R938  -2          A18X+151342Y+097209X0198Y0197R090 S2      
317P1V8_PEX         VIA   -    MD0100PA00X+151100Y+097050X0200Y         S0      
327P1V8_PEX         C2607 -2          A01X+147408Y+097200X0198Y0197     S1      
327P1V8_PEX         U103  -5          A18X+147258Y+097418X0140Y0440R270 S2      
317P1V8_PEX         VIA   -    MD0100PA00X+147650Y+097400X0200Y         S0      
327P1V8_PEX         C2605 -2   M      A18X+147944Y+095901X0198Y0197     S2      
327P1V8_PEX         U101  -5          A18X+147390Y+096038X0140Y0440R270 S2      
317P1V8_PEX         VIA   -    MD0100PA00X+147944Y+096194X0200Y         S0      
327P1V8_PEX         R3504 -1          A18X+143108Y+090150X0198Y0197     S2      
317P1V8_PEX         VIA   -    MD0100PA00X+143574Y+090150X0200Y         S0      
327P1V8_PEX         R3506 -1          A18X+146756Y+089030X0198Y0197R270 S2      
317P1V8_PEX         VIA   -    MD0100PA00X+147343Y+089104X0200Y         S0      
327P1V8_PEX         R926  -2          A18X+148499Y+087034X0198Y0197     S2      
317P1V8_PEX         VIA   -    MD0100PA00X+148239Y+087294X0200Y         S0      
327P1V8_PEX         U321  -2   M      A01X+146804Y+087530X0320Y0750R090 S1      
327P1V8_PEX         JPEX3 -2   M      A01X+146804Y+087530X0200Y0600R090 S1      
317P1V8_PEX         VIA   -    MD0100PA00X+147347Y+087427X0200Y         S0      
317P1V8_PEX         VIA   -    MD0100PA00X+147406Y+087720X0200Y         S0      
327P1V8_PEX         C2784 -2          A18X+146998Y+087519X0198Y0197R180 S2      
327P1V8_PEX         C2504 -2          A18X+146998Y+087919X0198Y0197R180 S2      
327P1V8_PEX         R3505 -1          A18X+147017Y+087136X0198Y0197R090 S2      
327P1V8_PEX         R6172 -2          A18X+148711Y+088462X0198Y0197R090 S2      
327P1V8_PEX         R925  -2   M      A18X+148499Y+088084X0198Y0197     S2      
317P1V8_PEX         VIA   -    MD0100PA00X+148257Y+088215X0200Y         S0      
327P1V8_PEX         R4619 -2          A01X+144058Y+084650X0198Y0197     S1      
317P1V8_PEX         VIA   -    MD0100PA00X+144300Y+084650X0200Y         S0      
327P1V8_PEX         R4685 -2          A01X+144058Y+080250X0198Y0197     S1      
317P1V8_PEX         VIA   -    MD0100PA00X+144300Y+080250X0200Y         S0      
317P1V8_PEX         VIA   -    MD0100PA00X+133500Y+073250X0200Y         S0      
317P1V8_PEX         VIA   -    MD0100PA00X+133500Y+064100X0200Y         S0      
317P1V8_PEX         VIA   -    MD0100PA00X+133500Y+059450X0200Y         S0      
327P1V8_PEX         R4830 -2          A01X+133258Y+059450X0198Y0197     S1      
327P1V8_PEX         R4810 -2          A01X+133258Y+064100X0198Y0197     S1      
317P1V8_PEX         VIA   -    MD0100PA00X+133500Y+068550X0200Y         S0      
327P1V8_PEX         R4767 -2          A01X+133258Y+068550X0198Y0197     S1      
317P1V8_PEX         VIA   -    MD0100PA00X+142600Y+071700X0200Y         S0      
327P1V8_PEX         R4703 -2          A01X+142358Y+071700X0198Y0197     S1      
317P1V8_PEX         VIA   -    MD0100PA00X+142600Y+076100X0200Y         S0      
327P1V8_PEX         R4638 -2          A01X+142358Y+076100X0198Y0197     S1      
327P1V8_PEX         R4748 -2          A01X+133258Y+073250X0198Y0197     S1      
317P1V8_PEX         VIA   -    MD0100PA00X+052157Y+090150X0200Y         S0      
327P1V8_PEX         R3466 -1          A18X+051690Y+090150X0198Y0197     S2      
327P1V8_PEX         R6166 -2          A18X+057561Y+088884X0198Y0197R180 S2      
317P1V8_PEX         VIA   -    MD0100PA00X+057983Y+088800X0200Y         S0      
317P1V8_PEX         VIA   -    MD0100PA00X+055926Y+089104X0200Y         S0      
327P1V8_PEX         R3468 -1          A18X+055338Y+089030X0198Y0197R270 S2      
327P1V8_PEX         R3467 -1          A18X+055600Y+087136X0198Y0197R090 S2      
327P1V8_PEX         C2783 -2          A18X+055580Y+087919X0198Y0197R180 S2      
327P1V8_PEX         C2308 -2          A18X+055580Y+087519X0198Y0197R180 S2      
327P1V8_PEX         JPEX1 -2   M      A01X+055387Y+087530X0200Y0600R090 S1      
317P1V8_PEX         VIA   -    MD0100PA00X+055989Y+087720X0200Y         S0      
317P1V8_PEX         VIA   -    MD0100PA00X+055930Y+087427X0200Y         S0      
317P1V8_PEX         VIA   -    MD0100PA00X+056899Y+084472X0200Y         S0      
327P1V8_PEX         R988  -2          A18X+056623Y+084472X0198Y0197R090 S2      
317P1V8_PEX         VIA   -    MD0100PA00X+054624Y+084315X0200Y         S0      
327P1V8_PEX         R989  -2          A18X+054866Y+084474X0198Y0197R090 S2      
317P1V8_PEX         VIA   -    MD0100PA00X+051174Y+084665X0200Y         S0      
327P1V8_PEX         C2609 -2          A01X+050932Y+084465X0198Y0197     S1      
327P1V8_PEX         U107  -5          A18X+050782Y+084683X0140Y0440R270 S2      
317P1V8_PEX         VIA   -    MD0100PA00X+051468Y+083459X0200Y         S0      
327P1V8_PEX         C2611 -2   M      A18X+051468Y+083166X0198Y0197     S2      
327P1V8_PEX         U105  -5          A18X+050914Y+083303X0140Y0440R270 S2      
317P1V8_PEX         VIA   -    MD0100PA00X+058800Y+082962X0200Y    R270 S0      
327P1V8_PEX         R971  -2          A18X+058800Y+082662X0198Y0197R270 S2      
317P1V8_PEX         VIA   -    MD0100PA00X+057750Y+082907X0200Y    R270 S0      
327P1V8_PEX         R972  -2          A18X+057750Y+082662X0198Y0197R270 S2      
317P1V8_PEX         VIA   -    MD0100PA00X+071028Y+078613X0200Y    R090 S0      
327P1V8_PEX         U50   -16         A01X+070919Y+077750X0140Y0630R270 S1      
327P1V8_PEX         C2095 -2   M      A01X+071028Y+078345X0198Y0197R180 S1      
317P1V8_PEX         VIA   -    MD0100PA00X+070268Y+077516X0200Y         S0      
327P1V8_PEX         R1030 -2          A18X+070008Y+077516X0198Y0197R180 S2      
317P1V8_PEX         VIA   -    MD0100PA00X+070268Y+078066X0200Y         S0      
327P1V8_PEX         R1029 -2          A18X+070008Y+078066X0198Y0197R180 S2      
317P1V8_PEX         VIA   -    MD0100PA00X+070269Y+075697X0200Y         S0      
327P1V8_PEX         R1032 -2          A18X+070009Y+075697X0198Y0197R180 S2      
317P1V8_PEX         VIA   -    MD0100PA00X+070269Y+076297X0200Y         S0      
327P1V8_PEX         R1031 -2          A18X+070009Y+076297X0198Y0197R180 S2      
317P1V8_PEX         VIA   -    MD0100PA00X+058823Y+080152X0200Y         S0      
317P1V8_PEX         VIA   -    MD0100PA00X+058827Y+080460X0200Y         S0      
317P1V8_PEX         VIA   -    MD0100PA00X+058838Y+080754X0200Y         S0      
317P1V8_PEX         VIA   -    MD0100PA00X+058834Y+079803X0200Y         S0      
327P1V8_PEX         R6169 -2          A18X+103269Y+088884X0198Y0197R180 S2      
317P1V8_PEX         VIA   -    MD0100PA00X+103771Y+088621X0200Y         S0      
327P1V8_PEX         U319  -2   M      A01X+101126Y+087530X0320Y0750R090 S1      
327P1V8_PEX         R3486 -1          A18X+101308Y+087136X0198Y0197R090 S2      
327P1V8_PEX         C2759 -2          A18X+101289Y+087519X0198Y0197R180 S2      
317P1V8_PEX         VIA   -    MD0100PA00X+097959Y+090285X0200Y         S0      
327P1V8_PEX         R3485 -1          A18X+097441Y+090150X0198Y0197     S2      
317P1V8_PEX         VIA   -    MD0100PA00X+101680Y+089030X0200Y         S0      
327P1V8_PEX         R3487 -1          A18X+101390Y+089026X0198Y0197R270 S2      
317P1V8_PEX         VIA   -    MD0100PA00X+101657Y+087454X0200Y         S0      
317P1V8_PEX         VIA   -    MD0100PA00X+101697Y+087720X0200Y         S0      
317P1V8_PEX         VIA   -    MD0100PA00X+082355Y+093070X0200Y         S0      
327P1V8_PEX         U123  -1          A01X+083083Y+093578X0240Y0460R180 S1      
327P1V8_PEX         C2708 -2   M      A01X+082355Y+093357X0198Y0197     S1      
317P1V8_PEX         VIA   -    MD0100PA00X+084133Y+092660X0200Y         S0      
317P1V8_PEX         VIA   -    MD0100PA00X+106601Y+098033X0200Y         S0      
317P1V8_PEX         VIA   -    MD0100PA00X+106961Y+098013X0200Y         S0      
317P1V8_PEX         VIA   -    MD0100PA00X+101801Y+098036X0200Y         S0      
317P1V8_PEX         VIA   -    MD0100PA00X+101401Y+098036X0200Y         S0      
327P1V8_PEX         R1345 -2          A01X+101001Y+098296X0198Y0197R270 S1      
327P1V8_PEX         R1343 -2   M      A01X+101401Y+098296X0198Y0197R270 S1      
327P1V8_PEX         R1338 -2   M      A01X+101801Y+098296X0198Y0197R270 S1      
327P1V8_PEX         R1334 -2   M      A01X+102601Y+098296X0198Y0197R270 S1      
327P1V8_PEX         R1341 -2   M      A01X+102201Y+098296X0198Y0197R270 S1      
327P1V8_PEX         R1340 -2   M      A01X+103801Y+098296X0198Y0197R270 S1      
327P1V8_PEX         R1336 -2   M      A01X+103401Y+098296X0198Y0197R270 S1      
327P1V8_PEX         R1339 -2   M      A01X+103001Y+098296X0198Y0197R270 S1      
327P1V8_PEX         R1344 -2   M      A01X+104201Y+098296X0198Y0197R270 S1      
327P1V8_PEX         R1348 -2   M      A01X+105401Y+098296X0198Y0197R270 S1      
327P1V8_PEX         R1347 -2   M      A01X+105001Y+098296X0198Y0197R270 S1      
327P1V8_PEX         R1333 -2   M      A01X+104601Y+098296X0198Y0197R270 S1      
327P1V8_PEX         R1346 -2   M      A01X+106201Y+098296X0198Y0197R270 S1      
327P1V8_PEX         R1342 -2   M      A01X+105801Y+098296X0198Y0197R270 S1      
327P1V8_PEX         R1335 -2   M      A01X+106601Y+098296X0198Y0197R270 S1      
327P1V8_PEX         R1337 -2   M      A01X+107401Y+098296X0198Y0197R270 S1      
317P1V8_PEX         VIA   -    MD0100PA00X+107001Y+098881X0200Y         S0      
327P1V8_PEX         R3963 -2          A01X+107001Y+099196X0198Y0197R270 S1      
317P1V8_PEX         VIA   -    MD0100PA00X+099988Y+099851X0200Y         S0      
327P1V8_PEX         R6155 -2          A01X+099887Y+100139X0198Y0197R270 S1      
327P1V8_PEX         C4007 -1   M      A18X+080007Y+096460X0198Y0197R090 S2      
327P1V8_PEX         U423  -24         A18X+079848Y+098004X0120Y0630R180 S2      
317P1V8_PEX         VIA   -    MD0100PA00X+082417Y+094954X0200Y         S0      
317P1V8_PEX         VIA   -    MD0100PA00X+083242Y+096467X0200Y         S0      
327P1V8_PEX         R6338 -1          A18X+082949Y+096963X0198Y0197R270 S2      
327P1V8_PEX         JPEX2 -2   M      A01X+101063Y+087530X0200Y0600R090 S1      
327P1V8_PEX         C2406 -2          A18X+101289Y+087919X0198Y0197R180 S2      
327P1V8_PEX         R1539 -1          A01X+083483Y+092660X0198Y0197R090 S1      
327P1V8_PEX         R1540 -1   M      A01X+083883Y+092660X0198Y0197R090 S1      
327P1V8_PEX_VCC     PU20  -19         A01X+042196Y+088349X0120Y0320R270 S1      
327P1V8_PEX_VCC     PC295 -1          A01X+042757Y+088401X0198Y0197R270 S1      
317P1V8_PEX_VCC     VIA   -    MD0100PA00X+039631Y+086441X0200Y    R180 S0      
317P1V8_PEX_VCC     VIA   -    M      A01X+042506Y+088398X0200Y    R180 S2      
017P1V8_PEX_VCC     VIA   -    M      A18X+042506Y+088398X0260Y    R180 S2      
017P1V8_PEX_VCC           -    MD0100PA00X+042506Y+088398                       
327P1V8_PEX_VCC     R849  -1          A01X+039883Y+086441X0198Y0197     S1      
327SW_P1V8_PEX_PH   PU20  -20         A01X+041763Y+088192X0120Y0790     S1      
327SW_P1V8_PEX_PH   VIA   -           A01X+042310Y+089221X0300Y         S1      
327SW_P1V8_PEX_PH   PC289 -2          A01X+040281Y+088979X0198Y0197R180 S1      
327SW_P1V8_PEX_PH   PL26  -1          A01X+041275Y+089869X0848Y1300R090 S1      
327P1V8_PEX_CS      PU20  -3          A01X+041094Y+087995X0070Y0320R090 S1      
327P1V8_PEX_CS      PR187 -1          A01X+040297Y+088130X0198Y0197R090 S1      
317P1V8_PEX_CS      VIA   -    M      A01X+040547Y+088130X0200Y    R180 S2      
017P1V8_PEX_CS      VIA   -    M      A18X+040547Y+088130X0260Y    R180 S2      
017P1V8_PEX_CS            -    MD0100PA00X+040547Y+088130                       
327PWRGD_P1V8_PEX   PU20  -9          A01X+041094Y+087010X0120Y0320R090 S1      
317PWRGD_P1V8_PEX   VIA   -    M      A01X+040447Y+086441X0200Y    R180 S2      
017PWRGD_P1V8_PEX   VIA   -    M      A18X+040447Y+086441X0260Y    R180 S2      
017PWRGD_P1V8_PEX         -    MD0100PA00X+040447Y+086441                       
327PWRGD_P1V8_PEX   R4439 -2          A01X+040198Y+086054X0198Y0197     S1      
327PWRGD_P1V8_PEX   R849  -2   M      A01X+040198Y+086441X0198Y0197     S1      
317SH_P1V8_PEX_FB   VIA   -    M      A01X+039258Y+087584X0200Y         S2      
017SH_P1V8_PEX_FB   VIA   -    M      A18X+039258Y+087584X0260Y         S2      
017SH_P1V8_PEX_FB         -    MD0100PA00X+039258Y+087584                       
327SH_P1V8_PEX_FB   PR186 -1          A01X+039937Y+087584X0198Y0197R270 S1      
327SH_P1V8_PEX_FB   PC297 -2   M      A01X+039539Y+087584X0198Y0197R090 S1      
327SH_P1V8_PEX_FB   PJ17  -1          A01X+038963Y+087586X0280Y0740R180 S1      
327P1V8_PEX_EN      PU20  -8          A01X+041094Y+087207X0070Y0320R090 S1      
317P1V8_PEX_EN      VIA   -    M      A01X+040677Y+086977X0200Y    R180 S2      
017P1V8_PEX_EN      VIA   -    M      A18X+040677Y+086977X0260Y    R180 S2      
017P1V8_PEX_EN            -    MD0100PA00X+040677Y+086977                       
327P1V8_PEX_EN      R851  -2          A01X+040193Y+086829X0198Y0197     S1      
327SW_P1V8_PEX_BT   PU20  -1          A01X+041114Y+088349X0120Y0360R090 S1      
327SW_P1V8_PEX_BT   PC289 -1          A01X+040596Y+088979X0198Y0197R180 S1      
327m3255            PU20  -10         A01X+041527Y+087168X0120Y0790     S1      
327m3255            PU20  -21         A01X+041527Y+088192X0120Y0790     S1      
327m3255            VIA   -           A01X+040897Y+085433X0300Y         S1      
327m3255            PC288 -1          A01X+041436Y+088955X0198Y0197R180 S1      
327m3255            PC287 -1          A01X+041624Y+086264X0400Y0500R180 S1      
327m3255            PC286 -1          A01X+041624Y+085464X0400Y0500R180 S1      
327m3255            PC285 -1          A01X+041624Y+084664X0400Y0500R180 S1      
327m3255            PL25  -2          A01X+041204Y+084063X0280Y0320     S1      
327m3255            PC284 -1          A01X+040797Y+084668X0400Y0500     S1      
317m3256            VIA   -    M      A01X+074970Y+160863X0200Y    R090 S2      
017m3256            VIA   -    M      A18X+074970Y+160863X0260Y    R090 S2      
017m3256                  -    MD0100PA00X+074970Y+160863                       
327m3256            U338  -4          A01X+074970Y+160473X0250Y0480R180 S1      
327m3256            R4415 -1          A01X+074492Y+161179X0198Y0197R090 S1      
327m3256            R4419 -2   M      A01X+074892Y+161179X0198Y0197R270 S1      
317m3257            VIA   -    M      A01X+074979Y+159052X0200Y    R090 S2      
017m3257            VIA   -    M      A18X+074979Y+159052X0260Y    R090 S2      
017m3257                  -    MD0100PA00X+074979Y+159052                       
327m3257            R4414 -1          A01X+074714Y+158688X0198Y0197R270 S1      
327m3257            R4418 -2   M      A01X+075114Y+158688X0198Y0197R090 S1      
327m3257            U338  -3          A01X+074970Y+159442X0250Y0480R180 S1      
317m3258            VIA   -    M      A01X+073607Y+161189X0200Y    R090 S2      
017m3258            VIA   -    M      A18X+073607Y+161189X0260Y    R090 S2      
017m3258                  -    MD0100PA00X+073607Y+161189                       
327m3258            R4416 -1          A01X+073598Y+160660X0198Y0197R180 S1      
327m3258            U338  -6          A01X+074222Y+160473X0250Y0480R180 S1      
327m3258            Q125  -G   M      A01X+073936Y+161189X0240Y0320R090 S1      
327m3259            R3390 -1          A01X+116848Y+076744X0198Y0197R090 S1      
317m3259            VIA   -    MD0100PA00X+088976Y+078816X0200Y         S0      
317m3259            VIA   -    M      A01X+095384Y+076302X0200Y         S2      
017m3259            VIA   -    M      A18X+095384Y+076302X0260Y         S2      
017m3259                  -    MD0100PA00X+095384Y+076302                       
327m3259            R465  -2          A01X+089273Y+078970X0198Y0197R270 S1      
317m3259            VIA   -    MD0100PA00X+074199Y+077591X0200Y         S0      
327m3259            R469  -1          A01X+072792Y+077214X0198Y0197R180 S1      
327m3260            R3391 -1          A01X+116448Y+076757X0198Y0197R090 S1      
317m3260            VIA   -    MD0100PA00X+088341Y+075986X0200Y         S0      
317m3260            VIA   -    MD0100PA00X+098188Y+074518X0200Y         S0      
327m3260            R466  -2   M      A18X+088661Y+076126X0198Y0197R090 S2      
327m3260            R1026 -2          A18X+088661Y+076126X0198Y0197R270 S2      
317m3260            VIA   -    M      A01X+074200Y+076814X0200Y         S2      
017m3260            VIA   -    M      A18X+074200Y+076814X0260Y         S2      
017m3260                  -    MD0100PA00X+074200Y+076814                       
327m3260            R470  -1          A01X+072792Y+076814X0198Y0197R180 S1      
327m3261            R472  -2          A01X+072792Y+076014X0198Y0197     S1      
327m3261            R3393 -2          A01X+115648Y+076757X0198Y0197R270 S1      
327m3261            R468  -2   M      A18X+088005Y+076126X0198Y0197R090 S2      
327m3261            R1028 -2          A18X+088005Y+076126X0198Y0197R270 S2      
317m3261            VIA   -    MD0100PA00X+088313Y+076612X0200Y         S0      
317m3261            VIA   -    M      A01X+097345Y+074728X0200Y         S2      
017m3261            VIA   -    M      A18X+097345Y+074728X0260Y         S2      
017m3261                  -    MD0100PA00X+097345Y+074728                       
317m3261            VIA   -    MD0100PA00X+074343Y+077242X0200Y         S0      
327m3262            R3392 -1          A01X+116048Y+076757X0198Y0197R090 S1      
317m3262            VIA   -    MD0100PA00X+086932Y+076126X0200Y         S0      
317m3262            VIA   -    M      A01X+098746Y+074580X0200Y         S2      
017m3262            VIA   -    M      A18X+098746Y+074580X0260Y         S2      
017m3262                  -    MD0100PA00X+098746Y+074580                       
327m3262            R467  -2   M      A18X+087485Y+076126X0198Y0197R090 S2      
327m3262            R1027 -2          A18X+087485Y+076126X0198Y0197R270 S2      
317m3262            VIA   -    MD0100PA00X+074199Y+076348X0200Y         S0      
327m3262            R471  -1          A01X+072792Y+076414X0198Y0197R180 S1      
327m3263            VIA   -    M      A01X+071985Y+077264X0300Y    R090 S1      
327m3263            U50   -14         A01X+070919Y+077238X0140Y0630R270 S1      
327m3263            R469  -2          A01X+072477Y+077214X0198Y0197R180 S1      
327m3264            VIA   -    M      A01X+071635Y+076864X0300Y    R090 S1      
327m3264            R470  -2          A01X+072477Y+076814X0198Y0197R180 S1      
327m3264            U50   -13         A01X+070919Y+076982X0140Y0630R270 S1      
327m3265            VIA   -    M      A01X+071985Y+076414X0300Y    R090 S1      
327m3265            U50   -12         A01X+070919Y+076726X0140Y0630R270 S1      
327m3265            R471  -2          A01X+072477Y+076414X0198Y0197R180 S1      
327m3266            R472  -1          A01X+072477Y+076014X0198Y0197     S1      
327m3266            VIA   -    M      A01X+071635Y+076014X0300Y    R090 S1      
327m3266            U50   -11         A01X+070919Y+076470X0140Y0630R270 S1      
327m3267            VIA   -    M      A01X+066135Y+076314X0300Y    R090 S1      
327m3267            R3405 -2          A01X+065642Y+075914X0198Y0197     S1      
327m3267            R3409 -2   M      A01X+065642Y+076314X0198Y0197     S1      
327m3267            R3290 -1          A01X+066677Y+076314X0198Y0197     S1      
327m3268            VIA   -    M      A01X+066135Y+077114X0300Y    R090 S1      
327m3268            R3408 -2          A01X+065642Y+076714X0198Y0197     S1      
327m3268            R3289 -1          A01X+066677Y+077114X0198Y0197     S1      
327m3268            R3404 -2   M      A01X+065642Y+077114X0198Y0197     S1      
327m3269            VIA   -    M      A01X+066185Y+077914X0300Y    R090 S1      
327m3269            R3403 -2          A01X+065642Y+077514X0198Y0197     S1      
327m3269            R3407 -2   M      A01X+065642Y+077914X0198Y0197     S1      
327m3269            R3288 -1          A01X+066677Y+077914X0198Y0197     S1      
327m3270            VIA   -    M      A01X+066135Y+078714X0300Y    R090 S1      
327m3270            R3402 -2          A01X+065642Y+078314X0198Y0197     S1      
327m3270            R3287 -1          A01X+066677Y+078714X0198Y0197     S1      
327m3270            R3406 -2   M      A01X+065642Y+078714X0198Y0197     S1      
327m3271            VIA   -    M      A01X+067485Y+076314X0300Y    R090 S1      
327m3271            R3290 -2          A01X+066992Y+076314X0198Y0197     S1      
327m3271            U50   -6          A01X+068715Y+076470X0140Y0630R270 S1      
327m3272            VIA   -    M      A01X+067485Y+077114X0300Y    R090 S1      
327m3272            U50   -5          A01X+068715Y+076726X0140Y0630R270 S1      
327m3272            R3289 -2          A01X+066992Y+077114X0198Y0197     S1      
327AGND_HSC         PR36  -1          A01X+092480Y+147210X0198Y0197R180 S1      
317AGND_HSC         VIA   -    MD0100PA00X+092480Y+147474X0200Y         S0      
327AGND_HSC         PR27  -1          A01X+088682Y+147286X0198Y0197R180 S1      
317AGND_HSC         VIA   -    MD0100PA00X+088924Y+147286X0200Y         S0      
327AGND_HSC         PR5   -2          A18X+080200Y+147414X0198Y0197R270 S2      
327AGND_HSC         PC2   -2          A01X+080501Y+147266X0198Y0197R090 S1      
317AGND_HSC         VIA   -    MD0100PA00X+080135Y+147868X0200Y         S0      
317AGND_HSC         VIA   -    MD0100PA00X+092570Y+146011X0200Y         S0      
327AGND_HSC         PC14  -2          A01X+092570Y+145740X0198Y0197R090 S1      
317AGND_HSC         VIA   -    MD0100PA00X+088924Y+146086X0200Y         S0      
327AGND_HSC         PC11  -2          A01X+088682Y+146086X0198Y0197     S1      
317AGND_HSC         VIA   -    MD0100PA00X+088994Y+145796X0200Y         S0      
327AGND_HSC         PU3   -20         A01X+089786Y+145357X0100Y0150R270 S1      
327AGND_HSC         PC13  -2   M      A01X+089184Y+145523X0198Y0197R090 S1      
327AGND_HSC         PR13  -2          A01X+088364Y+145266X0198Y0197R180 S1      
317AGND_HSC         VIA   -    MD0100PA00X+088124Y+145306X0200Y         S0      
327AGND_HSC         PC12  -2          A01X+088367Y+146486X0198Y0197R180 S1      
317AGND_HSC         VIA   -    MD0100PA00X+088124Y+146486X0200Y         S0      
317AGND_HSC         VIA   -    MD0100PA00X+083974Y+145796X0200Y         S0      
327AGND_HSC         PC15  -2          A01X+084217Y+145796X0198Y0197R180 S1      
317AGND_HSC         VIA   -    MD0100PA00X+083768Y+145320X0200Y         S0      
327AGND_HSC         PR11  -2          A01X+083430Y+145452X0198Y0197     S1      
327AGND_HSC         PU2   -20         A01X+085586Y+145357X0100Y0150R270 S1      
317AGND_HSC         VIA   -    MD0100PA00X+084684Y+145433X0200Y         S0      
327AGND_HSC         PC10  -2   M      A01X+084954Y+145433X0198Y0197R090 S1      
327AGND_HSC         PR16  -2          A01X+077478Y+145430X0198Y0197     S1      
327AGND_HSC         PC7   -2          A01X+077843Y+145807X0198Y0197R180 S1      
317AGND_HSC         VIA   -    MD0100PA00X+077843Y+145516X0200Y         S0      
327AGND_HSC         R6250 -2          A18X+077437Y+145102X0198Y0197R090 S2      
327AGND_HSC         PR41  -2          A01X+088367Y+144086X0198Y0197R180 S1      
317AGND_HSC         VIA   -    MD0100PA00X+088124Y+144086X0200Y         S0      
327AGND_HSC         PR42  -2          A01X+088367Y+144886X0198Y0197R180 S1      
317AGND_HSC         VIA   -    MD0100PA00X+088124Y+144886X0200Y         S0      
327AGND_HSC         PR43  -2          A01X+084217Y+144896X0198Y0197R180 S1      
317AGND_HSC         VIA   -    MD0100PA00X+083974Y+144896X0200Y         S0      
317AGND_HSC         VIA   -    MD0100PA00X+083974Y+144086X0200Y         S0      
327AGND_HSC         PR32  -2          A01X+084216Y+144086X0198Y0197R180 S1      
327AGND_HSC         PR34  -2          A01X+084217Y+144496X0198Y0197R180 S1      
317AGND_HSC         VIA   -    MD0100PA00X+083974Y+144496X0200Y         S0      
327AGND_HSC         PR6   -2          A18X+079619Y+143624X0198Y0197     S2      
327AGND_HSC         PC3   -2   M      A01X+079627Y+143656X0198Y0197R180 S1      
317AGND_HSC         VIA   -    MD0100PA00X+079374Y+143716X0200Y         S0      
327AGND_HSC         PU1   -23         A01X+079968Y+144378X0090Y0150     S1      
327AGND_HSC         PR1   -2          A01X+078334Y+144344X0198Y0197     S1      
327AGND_HSC         PC5   -2   M      A01X+078322Y+144958X0198Y0197R270 S1      
327AGND_HSC         PC4   -2          A18X+080108Y+145414X0198Y0197R270 S2      
327AGND_HSC         PU1   -18  M      A01X+079579Y+145170X0090Y0150R270 S1      
317AGND_HSC         VIA   -    MD0100PA00X+080106Y+145802X0200Y    R270 S0      
317AGND_HSC         VIA   -    MD0100PA00X+079906Y+145602X0200Y    R270 S0      
317AGND_HSC         VIA   -    MD0100PA00X+080306Y+145602X0200Y    R270 S0      
327AGND_HSC         PU1   -44  M      A01X+080106Y+145702X0460Y0630R270 S1      
317AGND_HSC         VIA   -    M      A01X+079329Y+145092X0200Y         S2      
017AGND_HSC         VIA   -    M      A18X+079329Y+145092X0260Y         S2      
017AGND_HSC               -    MD0100PA00X+079329Y+145092                       
327AGND_HSC         PC8   -2          A18X+078012Y+144228X0198Y0197     S2      
317AGND_HSC         VIA   -    MD0100PA00X+077775Y+143943X0200Y         S0      
327AGND_HSC         PC9   -2          A01X+078017Y+143943X0198Y0197R180 S1      
327AGND_HSC         PR15  -1          A01X+078017Y+143543X0198Y0197     S1      
317AGND_HSC         VIA   -    MD0100PA00X+077775Y+143543X0200Y         S0      
327AGND_HSC         PR33  -2   M      A01X+078017Y+143143X0198Y0197R180 S1      
327AGND_HSC         PC6   -2          A01X+078017Y+142743X0198Y0197R180 S1      
317AGND_HSC         VIA   -    MD0100PA00X+077775Y+143143X0200Y         S0      
327m3273            VIA   -    M      A01X+067535Y+077914X0300Y    R090 S1      
327m3273            U50   -4          A01X+068715Y+076982X0140Y0630R270 S1      
327m3273            R3288 -2          A01X+066992Y+077914X0198Y0197     S1      
327m3274            VIA   -    M      A01X+067485Y+078714X0300Y    R090 S1      
327m3274            U50   -3          A01X+068715Y+077238X0140Y0630R270 S1      
327m3274            R3287 -2          A01X+066992Y+078714X0198Y0197     S1      
327m3275            U52   -2          A01X+074036Y+073994X0240Y0420R090 S1      
317m3275            VIA   -    MD0100PA00X+055009Y+082984X0200Y         S0      
327m3275            U66   -1          A18X+052597Y+090483X0140Y0610R180 S2      
317m3275            VIA   -    M      A01X+052516Y+091382X0200Y         S2      
017m3275            VIA   -    M      A18X+052516Y+091382X0260Y         S2      
017m3275                  -    MD0100PA00X+052516Y+091382                       
317m3275            VIA   -    MD0100PA00X+084578Y+070809X0200Y         S0      
317m3275            VIA   -    MD0100PA00X+085763Y+078938X0200Y         S0      
327m3275            R5298 -2          A01X+084328Y+071344X0198Y0197R270 S1      
327m3275            R5419 -1   M      A01X+084328Y+070964X0198Y0197R270 S1      
327m3276            VIA   -    M      A18X+143486Y+088776X0260Y         S2      
327m3276            U68   -15         A18X+144264Y+088323X0140Y0610R180 S2      
327m3276            R3497 -1          A18X+143486Y+088322X0198Y0197R090 S2      
327m3277            VIA   -    M      A18X+005910Y+088016X0260Y         S2      
327m3277            R3450 -1          A18X+005910Y+087418X0198Y0197R090 S2      
327m3277            U65   -7          A18X+008403Y+090483X0140Y0610R180 S2      
317SPI_PEX3_SDIO2   VIA   -    M      A01X+154065Y+115561X0200Y         S2      
017SPI_PEX3_SDIO2   VIA   -    M      A18X+154065Y+115561X0260Y         S2      
017SPI_PEX3_SDIO2         -    MD0100PA00X+154065Y+115561                       
327SPI_PEX3_SDIO2   R3492 -2          A18X+153078Y+116065X0198Y0197R180 S2      
327SPI_PEX3_SDIO2   PEX3  -AG8        A01X+154252Y+115748X0180Y         S1      
317SPI_PEX3_SDIO1   VIA   -    MD0080PA00X+154065Y+115935X0160Y         S0      
327SPI_PEX3_SDIO1   VIA   -    M      A18X+154049Y+116338X0260Y         S2      
327SPI_PEX3_SDIO1   R3493 -2          A18X+153100Y+116910X0198Y0197R180 S2      
327SPI_PEX3_SDIO1   PEX3  -AF8        A01X+154252Y+116122X0180Y         S1      
327SPI_PEX3_SDIO0   R3494 -2          A18X+153100Y+116456X0198Y0197R180 S2      
317SPI_PEX3_SDIO0   VIA   -    M      A01X+153691Y+115935X0200Y         S2      
017SPI_PEX3_SDIO0   VIA   -    M      A18X+153691Y+115935X0260Y         S2      
017SPI_PEX3_SDIO0         -    MD0100PA00X+153691Y+115935                       
327SPI_PEX3_SDIO0   PEX3  -AF7        A01X+153878Y+116122X0180Y         S1      
327m3278            VIA   -    M      A18X+087481Y+078476X0260Y         S2      
327m3278            R460  -2          A18X+087510Y+078970X0198Y0197R090 S2      
327m3278            R1024 -1   M      A18X+087485Y+077713X0198Y0197R270 S2      
327m3278            R463  -1          A18X+087485Y+077713X0198Y0197R090 S2      
327m3279            VIA   -    M      A01X+090123Y+079683X0300Y         S1      
327m3279            R465  -1          A01X+089273Y+079285X0198Y0197R270 S1      
327m3279            R458  -2          A01X+090392Y+080332X0198Y0197R270 S1      
317m3280            VIA   -    MD0100PA00X+008308Y+088852X0200Y         S0      
327m3280            R3295 -1          A18X+015659Y+116456X0198Y0197R180 S2      
317m3280            VIA   -    M      A01X+015095Y+104012X0200Y         S2      
017m3280            VIA   -    M      A18X+015095Y+104012X0260Y         S2      
017m3280                  -    MD0100PA00X+015095Y+104012                       
327m3280            U65   -11         A18X+008153Y+088323X0140Y0610R180 S2      
317m3281            VIA   -    MD0100PA00X+007403Y+088906X0200Y         S0      
327m3281            R3294 -1          A18X+015659Y+116910X0198Y0197R180 S2      
317m3281            VIA   -    M      A01X+014464Y+103944X0200Y         S2      
017m3281            VIA   -    M      A18X+014464Y+103944X0260Y         S2      
017m3281                  -    MD0100PA00X+014464Y+103944                       
327m3281            U65   -14         A18X+007403Y+088323X0140Y0610R180 S2      
317SPI_PEX0_CLK_R   VIA   -    MD0100PA00X+007620Y+089791X0200Y         S0      
327SPI_PEX0_CLK_R   U65   -5          A18X+007903Y+090483X0140Y0610R180 S2      
327SPI_PEX0_CLK_R   R3293 -1          A18X+015613Y+114853X0198Y0197R180 S2      
317SPI_PEX0_CLK_R   VIA   -    M      A01X+015369Y+105104X0200Y         S2      
017SPI_PEX0_CLK_R   VIA   -    M      A18X+015369Y+105104X0260Y         S2      
017SPI_PEX0_CLK_R         -    MD0100PA00X+015369Y+105104                       
317m3282            VIA   -    MD0100PA00X+015923Y+106561X0200Y         S0      
327m3282            R3292 -1          A18X+016004Y+113533X0198Y0197R270 S2      
317m3282            VIA   -    M      A01X+007153Y+091319X0200Y         S2      
017m3282            VIA   -    M      A18X+007153Y+091319X0260Y         S2      
017m3282                  -    MD0100PA00X+007153Y+091319                       
327m3282            U65   -2          A18X+007153Y+090483X0140Y0610R180 S2      
317m3283            VIA   -    MD0080PA01X+064331Y+124350X0160Y         S0      
327m3283            PEX1  -D12        A01X+064331Y+124350X0180Y         S1      
317m3283            J12   -J5   D0122PA01X+049098Y+157634X0282Y    R180 S3      
317m3284            VIA   -    MD0080PA01X+064331Y+124724X0160Y         S0      
327m3284            PEX1  -C12        A01X+064331Y+124724X0180Y         S1      
317m3284            J12   -I5   D0122PA01X+049098Y+158146X0282Y    R180 S3      
317m3285            J11   -J5   D0122PA01X+031776Y+157634X0282Y    R180 S3      
317m3285            VIA   -    MD0080PA01X+018622Y+124350X0160Y         S0      
327m3285            PEX0  -D12        A01X+018622Y+124350X0180Y         S1      
317m3286            J11   -I5   D0122PA01X+031776Y+158146X0282Y    R180 S3      
317m3286            VIA   -    MD0080PA01X+018622Y+124724X0160Y         S0      
327m3286            PEX0  -C12        A01X+018622Y+124724X0180Y         S1      
317m3287            VIA   -    MD0100PA01X+047712Y+138430X0180Y         S0      
317m3287            J12   -D5   D0122PA01X+049098Y+160705X0282Y    R180 S3      
327m3287            C348  -2          A01X+047702Y+137939X0120Y0150R090 S1      
317m3288            VIA   -    MD0100PA01X+048052Y+138430X0180Y         S0      
317m3288            J12   -C5   D0122PA01X+049098Y+161217X0282Y    R180 S3      
327m3288            C349  -2          A01X+048062Y+137939X0120Y0150R090 S1      
317m3289            VIA   -    MD0100PA01X+027834Y+138430X0180Y         S0      
317m3289            J11   -D5   D0122PA01X+031776Y+160705X0282Y    R180 S3      
327m3289            C137  -2          A01X+027824Y+137939X0120Y0150R090 S1      
317m3290            VIA   -    MD0100PA01X+028174Y+138430X0180Y         S0      
317m3290            J11   -C5   D0122PA01X+031776Y+161217X0282Y    R180 S3      
327m3290            C138  -2          A01X+028184Y+137939X0120Y0150R090 S1      
317m3291            VIA   -    MD0100PA01X+048936Y+136010X0180Y         S0      
317m3291            J12   -C6   D0122PA01X+049965Y+161138X0282Y    R180 S3      
327m3291            C350  -2          A01X+048926Y+135519X0120Y0150R090 S1      
317m3292            J12   -I6   D0122PA01X+049965Y+158067X0282Y    R180 S3      
317m3292            VIA   -    MD0080PA01X+064705Y+125098X0160Y         S0      
327m3292            PEX1  -B13        A01X+064705Y+125098X0180Y         S1      
317m3293            J12   -H6   D0122PA01X+049965Y+158579X0282Y    R180 S3      
317m3293            VIA   -    MD0080PA01X+064705Y+125472X0160Y         S0      
327m3293            PEX1  -A13        A01X+064705Y+125472X0180Y         S1      
317m3294            J11   -I6   D0122PA01X+032642Y+158067X0282Y    R180 S3      
317m3294            VIA   -    MD0080PA01X+018996Y+125098X0160Y         S0      
327m3294            PEX0  -B13        A01X+018996Y+125098X0180Y         S1      
317m3295            J11   -H6   D0122PA01X+032642Y+158579X0282Y    R180 S3      
317m3295            VIA   -    MD0080PA01X+018996Y+125472X0160Y         S0      
327m3295            PEX0  -A13        A01X+018996Y+125472X0180Y         S1      
317m3296            VIA   -    MD0100PA01X+049276Y+136010X0180Y         S0      
317m3296            J12   -B6   D0122PA01X+049965Y+161650X0282Y    R180 S3      
327m3296            C351  -2          A01X+049286Y+135519X0120Y0150R090 S1      
317m3297            VIA   -    MD0100PA01X+029058Y+136010X0180Y         S0      
317m3297            J11   -C6   D0122PA01X+032642Y+161138X0282Y    R180 S3      
327m3297            C139  -2          A01X+029048Y+135519X0120Y0150R090 S1      
317m3298            VIA   -    MD0100PA01X+029398Y+136010X0180Y         S0      
317m3298            J11   -B6   D0122PA01X+032642Y+161650X0282Y    R180 S3      
327m3298            C140  -2          A01X+029408Y+135519X0120Y0150R090 S1      
317m3299            VIA   -    MD0100PA01X+048936Y+140850X0180Y         S0      
317m3299            J12   -D7   D0122PA01X+050831Y+160705X0282Y    R180 S3      
327m3299            C352  -2          A01X+048926Y+140359X0120Y0150R090 S1      
317m3300            J12   -J7   D0122PA01X+050831Y+157634X0282Y    R180 S3      
317m3300            VIA   -    MD0080PA01X+065079Y+124350X0160Y         S0      
327m3300            PEX1  -D14        A01X+065079Y+124350X0180Y         S1      
317m3301            J12   -I7   D0122PA01X+050831Y+158146X0282Y    R180 S3      
317m3301            VIA   -    MD0080PA01X+065079Y+124724X0160Y         S0      
327m3301            PEX1  -C14        A01X+065079Y+124724X0180Y         S1      
317m3302            J11   -J7   D0122PA01X+033508Y+157634X0282Y    R180 S3      
317m3302            VIA   -    MD0080PA01X+019370Y+124350X0160Y         S0      
327m3302            PEX0  -D14        A01X+019370Y+124350X0180Y         S1      
317m3303            J11   -I7   D0122PA01X+033508Y+158146X0282Y    R180 S3      
317m3303            VIA   -    MD0080PA01X+019370Y+124724X0160Y         S0      
327m3303            PEX0  -C14        A01X+019370Y+124724X0180Y         S1      
317m3304            VIA   -    MD0100PA01X+049276Y+140850X0180Y         S0      
317m3304            J12   -C7   D0122PA01X+050831Y+161217X0282Y    R180 S3      
327m3304            C353  -2          A01X+049286Y+140359X0120Y0150R090 S1      
317m3305            VIA   -    MD0100PA01X+029058Y+140850X0180Y         S0      
317m3305            J11   -D7   D0122PA01X+033508Y+160705X0282Y    R180 S3      
327m3305            C141  -2          A01X+029048Y+140359X0120Y0150R090 S1      
317m3306            VIA   -    MD0100PA01X+029398Y+140850X0180Y         S0      
317m3306            J11   -C7   D0122PA01X+033508Y+161217X0282Y    R180 S3      
327m3306            C142  -2          A01X+029408Y+140359X0120Y0150R090 S1      
317m3307            VIA   -    MD0100PA01X+050160Y+138430X0180Y         S0      
317m3307            J12   -C8   D0122PA01X+051697Y+161138X0282Y    R180 S3      
327m3307            C354  -2          A01X+050150Y+137939X0120Y0150R090 S1      
317m3308            J12   -I8   D0122PA01X+051697Y+158067X0282Y    R180 S3      
317m3308            VIA   -    MD0080PA01X+065453Y+125098X0160Y         S0      
327m3308            PEX1  -B15        A01X+065453Y+125098X0180Y         S1      
317m3309            J12   -H8   D0122PA01X+051697Y+158579X0282Y    R180 S3      
317m3309            VIA   -    MD0080PA01X+065453Y+125472X0160Y         S0      
327m3309            PEX1  -A15        A01X+065453Y+125472X0180Y         S1      
317m3310            J11   -I8   D0122PA01X+034374Y+158067X0282Y    R180 S3      
317m3310            VIA   -    MD0080PA01X+019744Y+125098X0160Y         S0      
327m3310            PEX0  -B15        A01X+019744Y+125098X0180Y         S1      
317m3311            J11   -H8   D0122PA01X+034374Y+158579X0282Y    R180 S3      
317m3311            VIA   -    MD0080PA01X+019744Y+125472X0160Y         S0      
327m3311            PEX0  -A15        A01X+019744Y+125472X0180Y         S1      
317m3312            VIA   -    MD0100PA01X+050500Y+138430X0180Y         S0      
317m3312            J12   -B8   D0122PA01X+051697Y+161650X0282Y    R180 S3      
327m3312            C355  -2          A01X+050510Y+137939X0120Y0150R090 S1      
317m3313            VIA   -    MD0100PA01X+030282Y+138430X0180Y         S0      
317m3313            J11   -C8   D0122PA01X+034374Y+161138X0282Y    R180 S3      
327m3313            C143  -2          A01X+030272Y+137939X0120Y0150R090 S1      
317m3314            VIA   -    MD0100PA01X+030622Y+138430X0180Y         S0      
317m3314            J11   -B8   D0122PA01X+034374Y+161650X0282Y    R180 S3      
327m3314            C144  -2          A01X+030632Y+137939X0120Y0150R090 S1      
327P12V_STBY        VIA   -           A01X+087580Y+147860X0300Y         S1      
327P12V_STBY        VIA   -           A01X+083040Y+147390X0300Y         S1      
327P12V_STBY        VIA   -           A01X+084760Y+147410X0300Y         S1      
327P12V_STBY        VIA   -           A01X+089320Y+147860X0300Y         S1      
327P12V_STBY        PU1   -8          A01X+080676Y+146140X0090Y0150     S1      
327P12V_STBY        FS1   -1          A01X+093488Y+155504X1280Y1350     S1      
327P12V_STBY        PR6603-1A         A01X+101787Y+149860X1260Y2700R090 S1      
327P12V_STBY        PR6602-1A         A01X+098008Y+149860X1260Y2700R090 S1      
327P12V_STBY        PR6001-1          A01X+094259Y+150222X1260Y0591R180 S1      
327P12V_STBY        R6252 -2          A01X+080807Y+148435X0198Y0197     S1      
327P12V_STBY        PR3   -1          A01X+080808Y+147662X0198Y0197R180 S1      
327P12V_STBY        PU3   -9          A01X+091356Y+146145X0100Y0140R180 S1      
327P12V_STBY        PU3   -10         A01X+091159Y+146140X0100Y0150R180 S1      
327P12V_STBY        PU3   -11         A01X+090962Y+146140X0100Y0150R180 S1      
327P12V_STBY        PU3   -12         A01X+090766Y+146140X0100Y0150R180 S1      
327P12V_STBY        PU3   -13         A01X+090569Y+146140X0100Y0150R180 S1      
327P12V_STBY        PU3   -14         A01X+090372Y+146140X0100Y0150R180 S1      
327P12V_STBY        PU3   -15         A01X+090175Y+146140X0100Y0150R180 S1      
327P12V_STBY        PU3   -16         A01X+089978Y+146145X0100Y0140R180 S1      
327P12V_STBY        PU2   -9          A01X+087156Y+146145X0100Y0140R180 S1      
327P12V_STBY        PU2   -10         A01X+086959Y+146140X0100Y0150R180 S1      
327P12V_STBY        PU2   -11         A01X+086762Y+146140X0100Y0150R180 S1      
327P12V_STBY        PU2   -12         A01X+086566Y+146140X0100Y0150R180 S1      
327P12V_STBY        PU2   -13         A01X+086369Y+146140X0100Y0150R180 S1      
327P12V_STBY        PU2   -14         A01X+086172Y+146140X0100Y0150R180 S1      
327P12V_STBY        PU2   -15         A01X+085975Y+146140X0100Y0150R180 S1      
327P12V_STBY        PU2   -16         A01X+085778Y+146145X0100Y0140R180 S1      
327P12V_STBY        PU1   -1          A01X+081917Y+146140X0090Y0150     S1      
327P12V_STBY        PU1   -2          A01X+081740Y+146140X0090Y0150     S1      
327P12V_STBY        PU1   -42         A01X+082128Y+145879X0090Y0150R270 S1      
327P12V_STBY        PC1   -1          A01X+082584Y+146246X0198Y0197     S1      
327P12V_STBY        PU1   -3          A01X+081562Y+146140X0090Y0150     S1      
327P12V_STBY        PU1   -4          A01X+081385Y+146140X0090Y0150     S1      
327P12V_STBY        PU1   -5          A01X+081208Y+146140X0090Y0150     S1      
327P12V_STBY        PU1   -6          A01X+081031Y+146140X0090Y0150     S1      
327P12V_STBY        PU1   -7          A01X+080854Y+146140X0090Y0150     S1      
317P12V_STBY        VIA   -    MD0100PA00X+102642Y+151499X0200Y         S0      
317P12V_STBY        VIA   -    MD0100PA00X+101602Y+151499X0200Y         S0      
317P12V_STBY        VIA   -    MD0100PA00X+101862Y+151499X0200Y         S0      
317P12V_STBY        VIA   -    MD0100PA00X+102122Y+151499X0200Y         S0      
317P12V_STBY        VIA   -    MD0100PA00X+102382Y+151499X0200Y         S0      
317P12V_STBY        VIA   -    MD0100PA00X+101342Y+151499X0200Y         S0      
317P12V_STBY        VIA   -    MD0100PA00X+101082Y+151499X0200Y         S0      
317P12V_STBY        VIA   -    MD0100PA00X+100562Y+151499X0200Y         S0      
317P12V_STBY        VIA   -    MD0100PA00X+100822Y+151499X0200Y         S0      
317P12V_STBY        VIA   -    MD0100PA00X+098934Y+151469X0200Y         S0      
317P12V_STBY        VIA   -    MD0100PA00X+098674Y+151469X0200Y         S0      
317P12V_STBY        VIA   -    MD0100PA00X+097894Y+151469X0200Y         S0      
317P12V_STBY        VIA   -    MD0100PA00X+098154Y+151469X0200Y         S0      
317P12V_STBY        VIA   -    MD0100PA00X+098414Y+151469X0200Y         S0      
317P12V_STBY        VIA   -    MD0100PA00X+097634Y+151469X0200Y         S0      
317P12V_STBY        VIA   -    MD0100PA00X+097374Y+151469X0200Y         S0      
317P12V_STBY        VIA   -    MD0100PA00X+096854Y+151469X0200Y         S0      
317P12V_STBY        VIA   -    MD0100PA00X+097114Y+151469X0200Y         S0      
317P12V_STBY        VIA   -    MD0100PA00X+095024Y+140956X0200Y         S0      
327P12V_STBY        VIA   -    M      A18X+092591Y+141307X0260Y         S2      
317P12V_STBY        VIA   -    MD0100PA00X+091437Y+147058X0200Y    R270 S0      
317P12V_STBY        VIA   -    MD0100PA00X+091137Y+147058X0200Y    R270 S0      
317P12V_STBY        VIA   -    MD0100PA00X+091437Y+146758X0200Y    R270 S0      
317P12V_STBY        VIA   -    MD0100PA00X+091137Y+146758X0200Y    R270 S0      
317P12V_STBY        VIA   -    MD0100PA00X+091137Y+147358X0200Y    R270 S0      
317P12V_STBY        VIA   -    MD0100PA00X+091437Y+147358X0200Y    R270 S0      
317P12V_STBY        VIA   -    MD0100PA00X+091137Y+147658X0200Y    R270 S0      
317P12V_STBY        VIA   -    MD0100PA00X+091437Y+147658X0200Y    R270 S0      
317P12V_STBY        VIA   -    MD0100PA00X+091437Y+146458X0200Y    R270 S0      
317P12V_STBY        VIA   -    MD0100PA00X+091137Y+146458X0200Y    R270 S0      
317P12V_STBY        VIA   -    MD0100PA00X+089937Y+146758X0200Y    R270 S0      
317P12V_STBY        VIA   -    MD0100PA00X+090537Y+147058X0200Y    R270 S0      
317P12V_STBY        VIA   -    MD0100PA00X+090537Y+146758X0200Y    R270 S0      
317P12V_STBY        VIA   -    MD0100PA00X+090837Y+147058X0200Y    R270 S0      
317P12V_STBY        VIA   -    MD0100PA00X+090837Y+146758X0200Y    R270 S0      
317P12V_STBY        VIA   -    MD0100PA00X+090237Y+147058X0200Y    R270 S0      
317P12V_STBY        VIA   -    MD0100PA00X+089937Y+147058X0200Y    R270 S0      
317P12V_STBY        VIA   -    MD0100PA00X+090237Y+146758X0200Y    R270 S0      
317P12V_STBY        VIA   -    MD0100PA00X+089937Y+147358X0200Y    R270 S0      
317P12V_STBY        VIA   -    MD0100PA00X+090237Y+147358X0200Y    R270 S0      
317P12V_STBY        VIA   -    MD0100PA00X+090837Y+147358X0200Y    R270 S0      
317P12V_STBY        VIA   -    MD0100PA00X+090537Y+147358X0200Y    R270 S0      
317P12V_STBY        VIA   -    MD0100PA00X+089937Y+147658X0200Y    R270 S0      
317P12V_STBY        VIA   -    MD0100PA00X+090237Y+147658X0200Y    R270 S0      
317P12V_STBY        VIA   -    MD0100PA00X+090837Y+147658X0200Y    R270 S0      
317P12V_STBY        VIA   -    MD0100PA00X+090537Y+147658X0200Y    R270 S0      
317P12V_STBY        VIA   -    MD0100PA00X+090237Y+146458X0200Y    R270 S0      
317P12V_STBY        VIA   -    MD0100PA00X+089937Y+146458X0200Y    R270 S0      
317P12V_STBY        VIA   -    MD0100PA00X+090537Y+146458X0200Y    R270 S0      
317P12V_STBY        VIA   -    MD0100PA00X+090837Y+146458X0200Y    R270 S0      
317P12V_STBY        VIA   -    MD0100PA00X+087064Y+147676X0200Y    R270 S0      
317P12V_STBY        VIA   -    MD0100PA00X+086764Y+147676X0200Y    R270 S0      
317P12V_STBY        VIA   -    MD0100PA00X+086164Y+147676X0200Y    R270 S0      
317P12V_STBY        VIA   -    MD0100PA00X+086464Y+147676X0200Y    R270 S0      
317P12V_STBY        VIA   -    MD0100PA00X+085864Y+147676X0200Y    R270 S0      
317P12V_STBY        VIA   -    MD0100PA00X+085564Y+147676X0200Y    R270 S0      
317P12V_STBY        VIA   -    MD0100PA00X+087064Y+147376X0200Y    R270 S0      
317P12V_STBY        VIA   -    MD0100PA00X+086764Y+147376X0200Y    R270 S0      
317P12V_STBY        VIA   -    MD0100PA00X+086164Y+147376X0200Y    R270 S0      
317P12V_STBY        VIA   -    MD0100PA00X+086464Y+147376X0200Y    R270 S0      
317P12V_STBY        VIA   -    MD0100PA00X+085864Y+147376X0200Y    R270 S0      
317P12V_STBY        VIA   -    MD0100PA00X+085564Y+147376X0200Y    R270 S0      
317P12V_STBY        VIA   -    MD0100PA00X+100705Y+151242X0200Y         S0      
317P12V_STBY        VIA   -    MD0100PA00X+101745Y+151242X0200Y         S0      
317P12V_STBY        VIA   -    MD0100PA00X+102005Y+151242X0200Y         S0      
317P12V_STBY        VIA   -    MD0100PA00X+102785Y+151242X0200Y         S0      
317P12V_STBY        VIA   -    MD0100PA00X+102265Y+151242X0200Y         S0      
317P12V_STBY        VIA   -    MD0100PA00X+102525Y+151242X0200Y         S0      
317P12V_STBY        VIA   -    MD0100PA00X+101485Y+151242X0200Y         S0      
317P12V_STBY        VIA   -    MD0100PA00X+101225Y+151242X0200Y         S0      
317P12V_STBY        VIA   -    MD0100PA00X+100965Y+151242X0200Y         S0      
317P12V_STBY        VIA   -    MD0100PA00X+085864Y+146476X0200Y    R270 S0      
317P12V_STBY        VIA   -    MD0100PA00X+085564Y+146476X0200Y    R270 S0      
327P12V_STBY        PU3   -33  M      A01X+090667Y+145259X1340Y1340R180 S1      
317P12V_STBY        VIA   -    MD0100PA00X+090107Y+144746X0200Y    R270 S0      
317P12V_STBY        VIA   -    MD0100PA00X+090667Y+144746X0200Y    R270 S0      
317P12V_STBY        VIA   -    MD0100PA00X+091217Y+144746X0200Y    R270 S0      
317P12V_STBY        VIA   -    MD0100PA00X+090107Y+145259X0200Y    R270 S0      
317P12V_STBY        VIA   -    MD0100PA00X+090107Y+145772X0200Y    R270 S0      
317P12V_STBY        VIA   -    MD0100PA00X+090667Y+145772X0200Y    R270 S0      
317P12V_STBY        VIA   -    MD0100PA00X+091217Y+145259X0200Y    R270 S0      
317P12V_STBY        VIA   -    MD0100PA00X+091217Y+145772X0200Y    R270 S0      
317P12V_STBY        VIA   -    MD0100PA00X+085564Y+146776X0200Y    R270 S0      
317P12V_STBY        VIA   -    MD0100PA00X+086164Y+147076X0200Y    R270 S0      
317P12V_STBY        VIA   -    MD0100PA00X+086164Y+146776X0200Y    R270 S0      
317P12V_STBY        VIA   -    MD0100PA00X+087064Y+147076X0200Y    R270 S0      
317P12V_STBY        VIA   -    MD0100PA00X+086764Y+147076X0200Y    R270 S0      
317P12V_STBY        VIA   -    MD0100PA00X+086464Y+147076X0200Y    R270 S0      
317P12V_STBY        VIA   -    MD0100PA00X+087064Y+146776X0200Y    R270 S0      
317P12V_STBY        VIA   -    MD0100PA00X+086764Y+146776X0200Y    R270 S0      
317P12V_STBY        VIA   -    MD0100PA00X+086464Y+146776X0200Y    R270 S0      
317P12V_STBY        VIA   -    MD0100PA00X+086164Y+146476X0200Y    R270 S0      
317P12V_STBY        VIA   -    MD0100PA00X+087064Y+146476X0200Y    R270 S0      
317P12V_STBY        VIA   -    MD0100PA00X+086764Y+146476X0200Y    R270 S0      
317P12V_STBY        VIA   -    MD0100PA00X+086464Y+146476X0200Y    R270 S0      
317P12V_STBY        VIA   -    MD0100PA00X+085864Y+147076X0200Y    R270 S0      
317P12V_STBY        VIA   -    MD0100PA00X+085564Y+147076X0200Y    R270 S0      
317P12V_STBY        VIA   -    MD0100PA00X+085864Y+146776X0200Y    R270 S0      
317P12V_STBY        VIA   -    MD0100PA00X+081510Y+147039X0200Y    R270 S0      
317P12V_STBY        VIA   -    MD0100PA00X+081510Y+147659X0200Y    R270 S0      
317P12V_STBY        VIA   -    MD0100PA00X+081510Y+147959X0200Y    R270 S0      
317P12V_STBY        VIA   -    MD0100PA00X+081510Y+147339X0200Y    R270 S0      
317P12V_STBY        VIA   -    MD0100PA00X+081210Y+147659X0200Y    R270 S0      
317P12V_STBY        VIA   -    MD0100PA00X+081210Y+147959X0200Y    R270 S0      
317P12V_STBY        VIA   -    MD0100PA00X+082410Y+147039X0200Y    R270 S0      
317P12V_STBY        VIA   -    MD0100PA00X+082410Y+146739X0200Y    R270 S0      
317P12V_STBY        VIA   -    MD0100PA00X+082110Y+146739X0200Y    R270 S0      
317P12V_STBY        VIA   -    MD0100PA00X+082110Y+147039X0200Y    R270 S0      
317P12V_STBY        VIA   -    MD0100PA00X+081810Y+147039X0200Y    R270 S0      
317P12V_STBY        VIA   -    MD0100PA00X+081510Y+146739X0200Y    R270 S0      
317P12V_STBY        VIA   -    MD0100PA00X+081810Y+146739X0200Y    R270 S0      
317P12V_STBY        VIA   -    MD0100PA00X+081201Y+147043X0200Y    R270 S0      
317P12V_STBY        VIA   -    MD0100PA00X+082410Y+147659X0200Y    R270 S0      
317P12V_STBY        VIA   -    MD0100PA00X+082110Y+147659X0200Y    R270 S0      
317P12V_STBY        VIA   -    MD0100PA00X+081810Y+147659X0200Y    R270 S0      
317P12V_STBY        VIA   -    MD0100PA00X+081201Y+147343X0200Y    R270 S0      
317P12V_STBY        VIA   -    MD0100PA00X+082410Y+147959X0200Y    R270 S0      
317P12V_STBY        VIA   -    MD0100PA00X+082110Y+147959X0200Y    R270 S0      
317P12V_STBY        VIA   -    MD0100PA00X+081810Y+147959X0200Y    R270 S0      
317P12V_STBY        VIA   -    MD0100PA00X+082410Y+147339X0200Y    R270 S0      
317P12V_STBY        VIA   -    MD0100PA00X+082110Y+147339X0200Y    R270 S0      
317P12V_STBY        VIA   -    MD0100PA00X+081810Y+147339X0200Y    R270 S0      
317P12V_STBY        VIA   -    MD0100PA00X+082110Y+146439X0200Y    R270 S0      
317P12V_STBY        VIA   -    MD0100PA00X+081510Y+146439X0200Y    R270 S0      
317P12V_STBY        VIA   -    MD0100PA00X+081810Y+146439X0200Y    R270 S0      
317P12V_STBY        VIA   -    MD0100PA00X+086467Y+145772X0200Y    R270 S0      
317P12V_STBY        VIA   -    MD0100PA00X+087017Y+145772X0200Y    R270 S0      
317P12V_STBY        VIA   -    MD0100PA00X+087017Y+145259X0200Y    R270 S0      
317P12V_STBY        VIA   -    MD0100PA00X+085907Y+145772X0200Y    R270 S0      
317P12V_STBY        VIA   -    MD0100PA00X+085907Y+145259X0200Y    R270 S0      
317P12V_STBY        VIA   -    MD0100PA00X+086467Y+144746X0200Y    R270 S0      
317P12V_STBY        VIA   -    MD0100PA00X+087017Y+144746X0200Y    R270 S0      
317P12V_STBY        VIA   -    MD0100PA00X+085907Y+144746X0200Y    R270 S0      
327P12V_STBY        PU2   -33  M      A01X+086467Y+145259X1340Y1340R180 S1      
317P12V_STBY        VIA   -    MD0100PA00X+081247Y+145772X0200Y    R270 S0      
317P12V_STBY        VIA   -    MD0100PA00X+081797Y+145772X0200Y    R270 S0      
317P12V_STBY        VIA   -    MD0100PA00X+080687Y+145772X0200Y    R270 S0      
317P12V_STBY        VIA   -    MD0100PA00X+081247Y+144746X0200Y    R270 S0      
317P12V_STBY        VIA   -    MD0100PA00X+081797Y+145259X0200Y    R270 S0      
317P12V_STBY        VIA   -    MD0100PA00X+081797Y+144746X0200Y    R270 S0      
317P12V_STBY        VIA   -    MD0100PA00X+080687Y+145259X0200Y    R270 S0      
317P12V_STBY        VIA   -    MD0100PA00X+080687Y+144746X0200Y    R270 S0      
327P12V_STBY        PU1   -43  M      A01X+081247Y+145259X1340Y1340R270 S1      
317P12V_STBY        VIA   -    MD0100PA00X+094709Y+154235X0200Y         S0      
317P12V_STBY        VIA   -    MD0100PA00X+094709Y+154535X0200Y         S0      
317P12V_STBY        VIA   -    MD0100PA00X+094409Y+154535X0200Y         S0      
317P12V_STBY        VIA   -    MD0100PA00X+094109Y+154535X0200Y         S0      
317P12V_STBY        VIA   -    MD0100PA00X+094409Y+154235X0200Y         S0      
317P12V_STBY        VIA   -    MD0100PA00X+094109Y+154235X0200Y         S0      
317P12V_STBY        VIA   -    MD0100PA00X+092909Y+154535X0200Y         S0      
317P12V_STBY        VIA   -    MD0100PA00X+092909Y+154235X0200Y         S0      
317P12V_STBY        VIA   -    MD0100PA00X+095004Y+154233X0200Y    R090 S0      
317P12V_STBY        VIA   -    MD0100PA00X+095304Y+154233X0200Y    R090 S0      
317P12V_STBY        VIA   -    MD0100PA00X+095604Y+154233X0200Y    R090 S0      
317P12V_STBY        VIA   -    MD0100PA00X+095904Y+154233X0200Y    R090 S0      
317P12V_STBY        VIA   -    MD0100PA00X+092604Y+154237X0200Y    R090 S0      
317P12V_STBY        VIA   -    MD0100PA00X+093809Y+154535X0200Y         S0      
317P12V_STBY        VIA   -    MD0100PA00X+093809Y+154235X0200Y         S0      
317P12V_STBY        VIA   -    MD0100PA00X+093209Y+154535X0200Y         S0      
317P12V_STBY        VIA   -    MD0100PA00X+093509Y+154535X0200Y         S0      
317P12V_STBY        VIA   -    MD0100PA00X+093209Y+154235X0200Y         S0      
317P12V_STBY        VIA   -    MD0100PA00X+093509Y+154235X0200Y         S0      
317P12V_STBY        VIA   -    MD0100PA00X+095004Y+154533X0200Y    R090 S0      
317P12V_STBY        VIA   -    MD0100PA00X+092604Y+156050X0200Y         S0      
317P12V_STBY        VIA   -    MD0100PA00X+092604Y+155750X0200Y         S0      
317P12V_STBY        VIA   -    MD0100PA00X+095304Y+154533X0200Y    R090 S0      
317P12V_STBY        VIA   -    MD0100PA00X+092604Y+154850X0200Y         S0      
317P12V_STBY        VIA   -    MD0100PA00X+092604Y+155150X0200Y         S0      
317P12V_STBY        VIA   -    MD0100PA00X+092604Y+155450X0200Y         S0      
317P12V_STBY        VIA   -    MD0100PA00X+092604Y+154537X0200Y    R090 S0      
317P12V_STBY        VIA   -    MD0100PA00X+095904Y+154533X0200Y    R090 S0      
317P12V_STBY        VIA   -    MD0100PA00X+095604Y+154533X0200Y    R090 S0      
317P12V_STBY        VIA   -    MD0100PA00X+102785Y+150722X0200Y         S0      
317P12V_STBY        VIA   -    MD0100PA00X+102675Y+150982X0200Y         S0      
317P12V_STBY        VIA   -    MD0100PA00X+102935Y+150982X0200Y         S0      
317P12V_STBY        VIA   -    MD0100PA00X+100965Y+150722X0200Y         S0      
317P12V_STBY        VIA   -    MD0100PA00X+101225Y+150722X0200Y         S0      
317P12V_STBY        VIA   -    MD0100PA00X+101485Y+150722X0200Y         S0      
317P12V_STBY        VIA   -    MD0100PA00X+102005Y+150722X0200Y         S0      
317P12V_STBY        VIA   -    MD0100PA00X+101745Y+150722X0200Y         S0      
317P12V_STBY        VIA   -    MD0100PA00X+102525Y+150722X0200Y         S0      
317P12V_STBY        VIA   -    MD0100PA00X+102265Y+150722X0200Y         S0      
317P12V_STBY        VIA   -    MD0100PA00X+102415Y+150982X0200Y         S0      
317P12V_STBY        VIA   -    MD0100PA00X+101895Y+150982X0200Y         S0      
317P12V_STBY        VIA   -    MD0100PA00X+102155Y+150982X0200Y         S0      
317P12V_STBY        VIA   -    MD0100PA00X+101635Y+150982X0200Y         S0      
317P12V_STBY        VIA   -    MD0100PA00X+101375Y+150982X0200Y         S0      
317P12V_STBY        VIA   -    MD0100PA00X+101115Y+150982X0200Y         S0      
317P12V_STBY        VIA   -    MD0100PA00X+100705Y+150722X0200Y         S0      
317P12V_STBY        VIA   -    MD0100PA00X+098817Y+150692X0200Y         S0      
317P12V_STBY        VIA   -    MD0100PA00X+099077Y+150692X0200Y         S0      
317P12V_STBY        VIA   -    MD0100PA00X+099077Y+151212X0200Y         S0      
317P12V_STBY        VIA   -    MD0100PA00X+098817Y+151212X0200Y         S0      
317P12V_STBY        VIA   -    MD0100PA00X+098707Y+150952X0200Y         S0      
317P12V_STBY        VIA   -    MD0100PA00X+099227Y+150952X0200Y         S0      
317P12V_STBY        VIA   -    MD0100PA00X+098967Y+150952X0200Y         S0      
317P12V_STBY        VIA   -    MD0100PA00X+100855Y+150982X0200Y         S0      
317P12V_STBY        VIA   -    MD0100PA00X+098037Y+151212X0200Y         S0      
317P12V_STBY        VIA   -    MD0100PA00X+098297Y+151212X0200Y         S0      
317P12V_STBY        VIA   -    MD0100PA00X+097777Y+151212X0200Y         S0      
317P12V_STBY        VIA   -    MD0100PA00X+097517Y+151212X0200Y         S0      
317P12V_STBY        VIA   -    MD0100PA00X+097257Y+150692X0200Y         S0      
317P12V_STBY        VIA   -    MD0100PA00X+096997Y+150692X0200Y         S0      
317P12V_STBY        VIA   -    MD0100PA00X+097517Y+150692X0200Y         S0      
317P12V_STBY        VIA   -    MD0100PA00X+097777Y+150692X0200Y         S0      
317P12V_STBY        VIA   -    MD0100PA00X+098297Y+150692X0200Y         S0      
317P12V_STBY        VIA   -    MD0100PA00X+098037Y+150692X0200Y         S0      
317P12V_STBY        VIA   -    MD0100PA00X+098557Y+150692X0200Y         S0      
317P12V_STBY        VIA   -    MD0100PA00X+098557Y+151212X0200Y         S0      
317P12V_STBY        VIA   -    MD0100PA00X+098187Y+150952X0200Y         S0      
317P12V_STBY        VIA   -    MD0100PA00X+098447Y+150952X0200Y         S0      
317P12V_STBY        VIA   -    MD0100PA00X+097927Y+150952X0200Y         S0      
317P12V_STBY        VIA   -    MD0100PA00X+097667Y+150952X0200Y         S0      
317P12V_STBY        VIA   -    MD0100PA00X+096997Y+151212X0200Y         S0      
317P12V_STBY        VIA   -    MD0100PA00X+097257Y+151212X0200Y         S0      
317P12V_STBY        VIA   -    MD0100PA00X+097407Y+150952X0200Y         S0      
317P12V_STBY        VIA   -    MD0100PA00X+097147Y+150952X0200Y         S0      
317P12V_STBY        J1    -P4_1MD0400PA00X+092301Y+162279X0705Y    R270 S3      
317P12V_STBY        J1    -P4_5MD0400PA00X+091301Y+162279X0705Y    R270 S3      
317P12V_STBY        J1    -P5_1MD0400PA00X+088801Y+162279X0705Y    R270 S3      
317P12V_STBY        J1    -P5_5MD0400PA00X+087801Y+162279X0705Y    R270 S3      
317P12V_STBY        J1    -P6_1MD0400PA00X+085301Y+162279X0705Y    R270 S3      
317P12V_STBY        J1    -P6_5MD0400PA00X+084301Y+162279X0705Y    R270 S3      
317P12V_STBY        J1    -P4_2MD0400PA00X+092301Y+161279X0705Y    R270 S3      
317P12V_STBY        J1    -P4_3MD0400PA00X+092301Y+160279X0705Y    R270 S3      
317P12V_STBY        J1    -P4_6MD0400PA00X+091301Y+161279X0705Y    R270 S3      
317P12V_STBY        J1    -P4_7MD0400PA00X+091301Y+160279X0705Y    R270 S3      
317P12V_STBY        J1    -P5_2MD0400PA00X+088801Y+161279X0705Y    R270 S3      
317P12V_STBY        J1    -P5_3MD0400PA00X+088801Y+160279X0705Y    R270 S3      
317P12V_STBY        J1    -P5_6MD0400PA00X+087801Y+161279X0705Y    R270 S3      
317P12V_STBY        J1    -P5_7MD0400PA00X+087801Y+160279X0705Y    R270 S3      
317P12V_STBY        J1    -P6_2MD0400PA00X+085301Y+161279X0705Y    R270 S3      
317P12V_STBY        J1    -P6_3MD0400PA00X+085301Y+160279X0705Y    R270 S3      
317P12V_STBY        J1    -P6_6MD0400PA00X+084301Y+161279X0705Y    R270 S3      
317P12V_STBY        J1    -P6_7MD0400PA00X+084301Y+160279X0705Y    R270 S3      
317P12V_STBY        J1    -P4_4MD0400PA00X+092301Y+159279X0705Y    R270 S3      
317P12V_STBY        J1    -P4_8MD0400PA00X+091301Y+159279X0705Y    R270 S3      
317P12V_STBY        J1    -P5_4MD0400PA00X+088801Y+159279X0705Y    R270 S3      
317P12V_STBY        J1    -P5_8MD0400PA00X+087801Y+159279X0705Y    R270 S3      
317P12V_STBY        J1    -P6_4MD0400PA00X+085301Y+159279X0705Y    R270 S3      
317P12V_STBY        J1    -P6_8MD0400PA00X+084301Y+159279X0705Y    R270 S3      
317P12V_STBY        VIA   -    MD0100PA00X+094277Y+150793X0200Y         S0      
317P12V_STBY        VIA   -    MD0100PA00X+094537Y+150793X0200Y         S0      
317P12V_STBY        VIA   -    MD0100PA00X+094647Y+150533X0200Y         S0      
317P12V_STBY        VIA   -    MD0100PA00X+094387Y+150533X0200Y         S0      
317P12V_STBY        VIA   -    MD0100PA00X+094387Y+151053X0200Y         S0      
317P12V_STBY        VIA   -    MD0100PA00X+094647Y+151053X0200Y         S0      
317P12V_STBY        VIA   -    MD0100PA00X+094017Y+150793X0200Y         S0      
317P12V_STBY        VIA   -    MD0100PA00X+093867Y+150533X0200Y         S0      
317P12V_STBY        VIA   -    MD0100PA00X+094127Y+150533X0200Y         S0      
317P12V_STBY        VIA   -    MD0100PA00X+094127Y+151053X0200Y         S0      
317P12V_STBY        VIA   -    MD0100PA00X+093867Y+151053X0200Y         S0      
327P12V_STBY        J69   -11         A01X+095897Y+140709X0240Y0950R090 S1      
317P12V_STBY        VIA   -    MD0100PA00X+095218Y+140709X0200Y         S0      
327m3315            R3405 -1          A01X+065327Y+075914X0198Y0197     S1      
317m3315            VIA   -    M      A01X+057149Y+076309X0200Y    R090 S2      
017m3315            VIA   -    M      A18X+057149Y+076309X0260Y    R090 S2      
017m3315                  -    MD0100PA00X+057149Y+076309                       
317m3315            VIA   -    MD0100PA00X+007653Y+087853X0200Y         S0      
327m3315            U65   -13         A18X+007653Y+088323X0140Y0610R180 S2      
317m3316            VIA   -    M      A01X+057820Y+077514X0200Y    R090 S2      
017m3316            VIA   -    M      A18X+057820Y+077514X0260Y    R090 S2      
017m3316                  -    MD0100PA00X+057820Y+077514                       
317m3316            VIA   -    MD0100PA00X+008034Y+089794X0200Y         S0      
327m3316            U65   -6          A18X+008153Y+090483X0140Y0610R180 S2      
327m3316            R3403 -1          A01X+065327Y+077514X0198Y0197     S1      
327m3317            VIA   -    M      A18X+009640Y+090540X0260Y         S2      
327m3317            U65   -4          A18X+007653Y+090483X0140Y0610R180 S2      
327m3317            R3447 -1          A18X+009535Y+090058X0198Y0197R090 S2      
327m3318            U52   -1          A01X+074036Y+073620X0240Y0420R090 S1      
317m3318            VIA   -    MD0100PA00X+049432Y+094121X0200Y         S0      
317m3318            VIA   -    MD0100PA00X+048957Y+082280X0200Y         S0      
327m3318            U65   -1          A18X+006903Y+090483X0140Y0610R180 S2      
317m3318            VIA   -    MD0100PA00X+006810Y+091012X0200Y         S0      
327m3318            R5297 -2          A01X+085228Y+071344X0198Y0197R270 S1      
327m3318            R5418 -1   M      A01X+085228Y+070964X0198Y0197R270 S1      
317m3318            VIA   -    M      A01X+084585Y+071097X0200Y         S2      
017m3318            VIA   -    M      A18X+084585Y+071097X0260Y         S2      
017m3318                  -    MD0100PA00X+084585Y+071097                       
317m3318            VIA   -    MD0100PA00X+085328Y+078989X0200Y         S0      
317m3319            VIA   -    M      A01X+058718Y+078501X0200Y         S2      
017m3319            VIA   -    M      A18X+058718Y+078501X0260Y         S2      
017m3319                  -    MD0100PA00X+058718Y+078501                       
327m3319            R3402 -1          A01X+065327Y+078314X0198Y0197     S1      
327m3319            U65   -3          A18X+007403Y+090483X0140Y0610R180 S2      
317m3319            VIA   -    MD0100PA00X+007204Y+089835X0200Y         S0      
327m3320            R3404 -1          A01X+065327Y+077114X0198Y0197     S1      
317m3320            VIA   -    M      A01X+057764Y+076977X0200Y    R090 S2      
017m3320            VIA   -    M      A18X+057764Y+076977X0260Y    R090 S2      
017m3320                  -    MD0100PA00X+057764Y+076977                       
327m3320            U65   -10         A18X+008403Y+088323X0140Y0610R180 S2      
317m3320            VIA   -    MD0100PA00X+008437Y+087829X0200Y         S0      
317SPI_PEX3_CS_N    VIA   -    MD0080PA00X+153691Y+114813X0160Y         S0      
327SPI_PEX3_CS_N    VIA   -    M      A18X+153877Y+114627X0260Y         S2      
327SPI_PEX3_CS_N    R6160 -1   M      A18X+153504Y+113848X0198Y0197R090 S2      
327SPI_PEX3_CS_N    R3491 -2          A18X+153130Y+113848X0198Y0197R270 S2      
327SPI_PEX3_CS_N    PEX3  -AJ7        A01X+153878Y+115000X0180Y         S1      
317SPI_PEX3_CLK     VIA   -    M      A01X+153691Y+115187X0200Y         S2      
017SPI_PEX3_CLK     VIA   -    M      A18X+153691Y+115187X0260Y         S2      
017SPI_PEX3_CLK           -    MD0100PA00X+153691Y+115187                       
327SPI_PEX3_CLK     R3489 -2          A18X+153054Y+114853X0198Y0197R180 S2      
327SPI_PEX3_CLK     PEX3  -AH7        A01X+153878Y+115374X0180Y         S1      
327m3321            VIA   -           A01X+047144Y+100114X0300Y         S1      
327m3321            PU6   -3          A01X+047156Y+100785X0070Y0240     S1      
327m3322            PR126 -1          A01X+140853Y+103218X0198Y0197R180 S1      
327m3322            VIA   -           A01X+141560Y+103768X0300Y         S1      
327m3322            PJ7   -2   M      A01X+140991Y+103768X0280Y0320R270 S1      
327m3323            R840  -2          A01X+142319Y+102027X0198Y0197R180 S1      
327m3323            R839  -2   M      A01X+142319Y+101627X0198Y0197R180 S1      
327m3323            C837  -1   M      A01X+141519Y+101627X0198Y0197     S1      
317m3323            VIA   -    M      A01X+141276Y+101627X0200Y         S2      
017m3323            VIA   -    M      A18X+141276Y+101627X0260Y         S2      
017m3323                  -    MD0100PA00X+141276Y+101627                       
327m3323            PU11  -16         A01X+139912Y+101809X0070Y0240R090 S1      
327m3324            PR132 -1          A01X+141519Y+101227X0198Y0197     S1      
327m3324            VIA   -    M      A01X+140984Y+101542X0300Y         S1      
327m3324            PU11  -15         A01X+139912Y+101652X0070Y0240R090 S1      
327m3325            PR126 -2   M      A01X+140538Y+103218X0198Y0197R180 S1      
327m3325            VIA   -           A01X+140538Y+102745X0300Y         S1      
327m3325            PU11  -21         A01X+139676Y+102675X0070Y0240     S1      
327m3325            PC129 -1   M      A01X+139953Y+103168X0198Y0197R180 S1      
327m3326            PR139 -1          A18X+137856Y+102360X0198Y0197R270 S2      
327m3326            VIA   -    M      A18X+137906Y+101907X0260Y    R090 S2      
327m3326            PU11  -36         A01X+138022Y+101652X0070Y0240R090 S1      
317m3326            VIA   -    MD0100PA00X+137636Y+101682X0200Y         S0      
327m3326            PC133 -1   M      A18X+137869Y+101457X0198Y0197R180 S2      
327P0V8_PEX2_VREF   PC186 -1   M      A01X+140767Y+110192X0198Y0197R270 S1      
327P0V8_PEX2_VREF   PU14  -39         A01X+140481Y+111023X0090Y0240R180 S1      
317P0V8_PEX2_VREF   VIA   -    MD0100PA00X+140482Y+110192X0200Y    R180 S0      
327P0V8_PEX2_VREF   PC202 -1   M      A01X+143928Y+110372X0198Y0197     S1      
327P0V8_PEX2_VREF   PU15  -39         A01X+143694Y+111023X0090Y0240R180 S1      
317P0V8_PEX2_VREF   VIA   -    MD0100PA00X+143695Y+110192X0200Y    R090 S0      
327P0V8_PEX2_VREF   PC153 -1   M      A01X+134209Y+110192X0198Y0197R270 S1      
327P0V8_PEX2_VREF   PU12  -39         A01X+133922Y+111023X0090Y0240R180 S1      
317P0V8_PEX2_VREF   VIA   -    MD0100PA00X+133923Y+110192X0200Y    R180 S0      
327P0V8_PEX2_VREF   PC166 -1   M      A01X+137422Y+110192X0198Y0197R270 S1      
327P0V8_PEX2_VREF   PU13  -39         A01X+137135Y+111023X0090Y0240R180 S1      
317P0V8_PEX2_VREF   VIA   -    MD0100PA00X+137136Y+110192X0200Y    R090 S0      
327P0V8_PEX2_VREF   PR140 -1          A01X+135969Y+102627X0198Y0197     S1      
317P0V8_PEX2_VREF   VIA   -    MD0100PA00X+135726Y+102627X0200Y         S0      
327P0V8_PEX2_VREF   PU11  -40         A01X+138022Y+101022X0070Y0240R090 S1      
327P0V8_PEX2_VREF   PC128 -1          A01X+137353Y+100218X0198Y0197R180 S1      
327P0V8_PEX2_VREF   PC127 -1          A01X+137376Y+099677X0400Y0500     S1      
317P0V8_PEX2_VREF   VIA   -    M      A01X+137894Y+100059X0200Y         S2      
017P0V8_PEX2_VREF   VIA   -    M      A18X+137894Y+100059X0260Y         S2      
017P0V8_PEX2_VREF         -    MD0100PA00X+137894Y+100059                       
327P0V8_PEX2_VREF   PR7142-1          A18X+141058Y+102425X0198Y0197     S2      
327m3327            R834  -2          A01X+142319Y+099677X0198Y0197R180 S1      
327m3327            C834  -1   M      A01X+141519Y+100077X0198Y0197     S1      
327m3327            R833  -2          A01X+142319Y+100077X0198Y0197R180 S1      
327m3327            VIA   -    M      A01X+140975Y+100418X0300Y         S1      
327m3327            PU11  -12         A01X+139912Y+101179X0070Y0240R090 S1      
327P0V8_PEX3_TSEN   PR139 -2          A18X+137856Y+102676X0198Y0197R270 S2      
327P0V8_PEX3_TSEN   PU15  -36         A01X+143162Y+111023X0090Y0240R180 S1      
317P0V8_PEX3_TSEN   VIA   -    MD0100PA00X+143267Y+110555X0200Y         S0      
317P0V8_PEX3_TSEN   VIA   -    M      A01X+137856Y+103853X0200Y         S2      
017P0V8_PEX3_TSEN   VIA   -    M      A18X+137856Y+103853X0260Y         S2      
017P0V8_PEX3_TSEN         -    MD0100PA00X+137856Y+103853                       
327P0V8_PEX3_TSEN   PU14  -36         A01X+139949Y+111023X0090Y0240R180 S1      
317P0V8_PEX3_TSEN   VIA   -    MD0100PA00X+140054Y+110555X0200Y         S0      
317P0V8_PEX2_ADDR   VIA   -    M      A01X+136531Y+102179X0200Y         S2      
017P0V8_PEX2_ADDR   VIA   -    M      A18X+136531Y+102179X0260Y         S2      
017P0V8_PEX2_ADDR         -    MD0100PA00X+136531Y+102179                       
327P0V8_PEX2_ADDR   PU11  -34         A01X+138022Y+101966X0070Y0240R090 S1      
327P0V8_PEX2_ADDR   PR140 -2          A01X+136284Y+102627X0198Y0197     S1      
327P0V8_PEX2_ADDR   PR141 -1   M      A01X+136284Y+102277X0198Y0197R180 S1      
317COUPON_GND2      VIA   -    MD0100PA00X+179926Y-003467X0200Y    R090 S0      
317COUPON_GND2      VIA   -    MD0100PA00X+179926Y-002971X0200Y    R090 S0      
317COUPON_GND2      VIA   -    MD0100PA00X+179926Y-003971X0200Y    R090 S0      
317COUPON_GND2      VIA   -    MD0100PA00X+179926Y-004467X0200Y    R090 S0      
317COUPON_GND2      VIA   -    MD0100PA00X+173391Y-007346X0200Y    R090 S0      
317COUPON_GND2      VIA   -    MD0100PA00X+173391Y-006850X0200Y    R090 S0      
317COUPON_GND2      VIA   -    MD0100PA00X+173391Y-007850X0200Y    R090 S0      
317COUPON_GND2      VIA   -    MD0100PA00X+173391Y-008346X0200Y    R090 S0      
317COUPON_GND2      VIA   -    MD0100PA00X+158468Y-003961X0200Y    R270 S0      
317COUPON_GND2      VIA   -    MD0100PA00X+158468Y-003456X0200Y    R270 S0      
317COUPON_GND2      VIA   -    MD0100PA00X+158468Y-002961X0200Y    R270 S0      
317COUPON_GND2      VIA   -    MD0100PA00X+158468Y-004456X0200Y    R270 S0      
317COUPON_GND2      VIA   -    MD0100PA00X+159468Y-007348X0200Y    R270 S0      
317COUPON_GND2      VIA   -    MD0100PA00X+159468Y-006853X0200Y    R270 S0      
317COUPON_GND2      VIA   -    MD0100PA00X+159468Y-007853X0200Y    R270 S0      
317COUPON_GND2      VIA   -    MD0100PA00X+159468Y-008348X0200Y    R270 S0      
317COUPON_GND2      VIA   -    MD0100PA00X+151476Y-003454X0200Y    R090 S0      
317COUPON_GND2      VIA   -    MD0100PA00X+151476Y-002958X0200Y    R090 S0      
317COUPON_GND2      VIA   -    MD0100PA00X+151476Y-003958X0200Y    R090 S0      
317COUPON_GND2      VIA   -    MD0100PA00X+151476Y-004454X0200Y    R090 S0      
317COUPON_GND2      VIA   -    MD0100PA00X+147941Y-007346X0200Y    R090 S0      
317COUPON_GND2      VIA   -    MD0100PA00X+147941Y-006850X0200Y    R090 S0      
317COUPON_GND2      VIA   -    MD0100PA00X+147941Y-007850X0200Y    R090 S0      
317COUPON_GND2      VIA   -    MD0100PA00X+147941Y-008346X0200Y    R090 S0      
317COUPON_GND2      VIA   -    MD0100PA00X+134018Y-007853X0200Y    R270 S0      
317COUPON_GND2      VIA   -    MD0100PA00X+134018Y-008348X0200Y    R270 S0      
317COUPON_GND2      VIA   -    MD0100PA00X+134018Y-007348X0200Y    R270 S0      
317COUPON_GND2      VIA   -    MD0100PA00X+134018Y-006853X0200Y    R270 S0      
317COUPON_GND2      VIA   -    MD0100PA00X+130018Y-003948X0200Y    R270 S0      
317COUPON_GND2      VIA   -    MD0100PA00X+130018Y-003443X0200Y    R270 S0      
317COUPON_GND2      VIA   -    MD0100PA00X+130018Y-002948X0200Y    R270 S0      
317COUPON_GND2      VIA   -    MD0100PA00X+130018Y-004443X0200Y    R270 S0      
317COUPON_GND2      VIA   -    MD0100PA00X+122826Y-003441X0200Y    R090 S0      
317COUPON_GND2      VIA   -    MD0100PA00X+122826Y-002945X0200Y    R090 S0      
317COUPON_GND2      VIA   -    MD0100PA00X+122826Y-003945X0200Y    R090 S0      
317COUPON_GND2      VIA   -    MD0100PA00X+122826Y-004441X0200Y    R090 S0      
317COUPON_GND2      VIA   -    MD0100PA00X+122291Y-007346X0200Y    R090 S0      
317COUPON_GND2      VIA   -    MD0100PA00X+122291Y-006850X0200Y    R090 S0      
317COUPON_GND2      VIA   -    MD0100PA00X+122291Y-007850X0200Y    R090 S0      
317COUPON_GND2      VIA   -    MD0100PA00X+122291Y-008346X0200Y    R090 S0      
317COUPON_GND2      VIA   -    MD0100PA00X+101368Y-003430X0200Y    R270 S0      
317COUPON_GND2      VIA   -    MD0100PA00X+101368Y-002935X0200Y    R270 S0      
317COUPON_GND2      VIA   -    MD0100PA00X+101368Y-003935X0200Y    R270 S0      
317COUPON_GND2      VIA   -    MD0100PA00X+101368Y-004430X0200Y    R270 S0      
317COUPON_GND2      VIA   -    MD0100PA00X+108368Y-008348X0200Y    R270 S0      
317COUPON_GND2      VIA   -    MD0100PA00X+108368Y-007853X0200Y    R270 S0      
317COUPON_GND2      VIA   -    MD0100PA00X+108368Y-006853X0200Y    R270 S0      
317COUPON_GND2      VIA   -    MD0100PA00X+108368Y-007348X0200Y    R270 S0      
317COUPON_GND2      VIA   -    MD0100PA00X+158928Y-006561X0200Y         S0      
317COUPON_GND2      VIA   -    MD0100PA00X+158928Y-007610X0200Y    R180 S0      
317COUPON_GND2      VIA   -    MD0100PA00X+158928Y-008640X0200Y    R180 S0      
317COUPON_GND2      VIA   -    MD0100PA00X+158300Y-006940X0200Y    R180 S0      
317COUPON_GND2      VIA   -    MD0100PA00X+158299Y-006672X0200Y         S0      
317COUPON_GND2      VIA   -    MD0100PA00X+158624Y-006672X0200Y         S0      
317COUPON_GND2      VIA   -    MD0100PA00X+158300Y-006421X0200Y         S0      
317COUPON_GND2      VIA   -    MD0100PA00X+158626Y-006421X0200Y         S0      
317COUPON_GND2      VIA   -    MD0100PA00X+158299Y-007489X0200Y    R180 S0      
317COUPON_GND2      VIA   -    MD0100PA00X+158300Y-007200X0200Y    R180 S0      
317COUPON_GND2      VIA   -    MD0100PA00X+158624Y-007490X0200Y    R180 S0      
317COUPON_GND2      VIA   -    MD0100PA00X+158299Y-008520X0200Y    R180 S0      
317COUPON_GND2      VIA   -    MD0100PA00X+158624Y-008520X0200Y    R180 S0      
317COUPON_GND2      VIA   -    MD0100PA00X+158300Y-008251X0200Y    R180 S0      
317COUPON_GND2      VIA   -    MD0100PA00X+158300Y-008772X0200Y    R180 S0      
317COUPON_GND2      VIA   -    MD0100PA00X+158626Y-008772X0200Y    R180 S0      
317COUPON_GND2      VIA   -    MD0100PA00X+158300Y-007740X0200Y    R180 S0      
327COUPON_GND2      DE05F_-3   M      A01X+158626Y-007101X0850Y1560     S1      
317COUPON_GND2      VIA   -    MD0100PA00X+158626Y-007742X0200Y    R180 S0      
327COUPON_GND2      DE05F_-3   M      A18X+158626Y-008101X0850Y1560R180 S2      
317COUPON_GND2      VIA   -    MD0100PA00X+158300Y-008001X0200Y    R180 S0      
317COUPON_GND2      VIA   -    MD0100PA00X+157928Y-002669X0200Y         S0      
317COUPON_GND2      VIA   -    MD0100PA00X+157928Y-003718X0200Y    R180 S0      
317COUPON_GND2      VIA   -    MD0100PA00X+157928Y-004748X0200Y    R180 S0      
317COUPON_GND2      VIA   -    MD0100PA00X+157300Y-003048X0200Y    R180 S0      
317COUPON_GND2      VIA   -    MD0100PA00X+157299Y-002780X0200Y         S0      
317COUPON_GND2      VIA   -    MD0100PA00X+157624Y-002779X0200Y         S0      
317COUPON_GND2      VIA   -    MD0100PA00X+157300Y-002529X0200Y         S0      
317COUPON_GND2      VIA   -    MD0100PA00X+157626Y-002527X0200Y         S0      
317COUPON_GND2      VIA   -    MD0100PA00X+157299Y-003597X0200Y    R180 S0      
317COUPON_GND2      VIA   -    MD0100PA00X+157300Y-003308X0200Y    R180 S0      
317COUPON_GND2      VIA   -    MD0100PA00X+157624Y-003598X0200Y    R180 S0      
317COUPON_GND2      VIA   -    MD0100PA00X+157299Y-004628X0200Y    R180 S0      
317COUPON_GND2      VIA   -    MD0100PA00X+157624Y-004628X0200Y    R180 S0      
317COUPON_GND2      VIA   -    MD0100PA00X+157300Y-004359X0200Y    R180 S0      
317COUPON_GND2      VIA   -    MD0100PA00X+157300Y-004880X0200Y    R180 S0      
317COUPON_GND2      VIA   -    MD0100PA00X+157626Y-004880X0200Y    R180 S0      
317COUPON_GND2      VIA   -    MD0100PA00X+157300Y-003848X0200Y    R180 S0      
327COUPON_GND2      DE15T_-3   M      A01X+157626Y-003209X0850Y1560     S1      
317COUPON_GND2      VIA   -    MD0100PA00X+157626Y-003850X0200Y    R180 S0      
327COUPON_GND2      DE15T_-3   M      A18X+157626Y-004209X0850Y1560R180 S2      
317COUPON_GND2      VIA   -    MD0100PA00X+157300Y-004109X0200Y    R180 S0      
317COUPON_GND2      VIA   -    MD0100PA00X+173931Y-008637X0200Y    R180 S0      
317COUPON_GND2      VIA   -    MD0100PA00X+173931Y-007588X0200Y         S0      
317COUPON_GND2      VIA   -    MD0100PA00X+173931Y-006558X0200Y         S0      
317COUPON_GND2      VIA   -    MD0100PA00X+174559Y-008258X0200Y         S0      
317COUPON_GND2      VIA   -    MD0100PA00X+174560Y-008526X0200Y    R180 S0      
317COUPON_GND2      VIA   -    MD0100PA00X+174235Y-008526X0200Y    R180 S0      
317COUPON_GND2      VIA   -    MD0100PA00X+174559Y-008778X0200Y    R180 S0      
317COUPON_GND2      VIA   -    MD0100PA00X+174234Y-008778X0200Y    R180 S0      
317COUPON_GND2      VIA   -    MD0100PA00X+174560Y-007709X0200Y         S0      
317COUPON_GND2      VIA   -    MD0100PA00X+174559Y-007998X0200Y         S0      
317COUPON_GND2      VIA   -    MD0100PA00X+174235Y-007708X0200Y         S0      
317COUPON_GND2      VIA   -    MD0100PA00X+174560Y-006678X0200Y         S0      
317COUPON_GND2      VIA   -    MD0100PA00X+174235Y-006678X0200Y         S0      
317COUPON_GND2      VIA   -    MD0100PA00X+174559Y-006947X0200Y         S0      
317COUPON_GND2      VIA   -    MD0100PA00X+174559Y-006426X0200Y         S0      
317COUPON_GND2      VIA   -    MD0100PA00X+174234Y-006426X0200Y         S0      
317COUPON_GND2      VIA   -    MD0100PA00X+174559Y-007458X0200Y         S0      
327COUPON_GND2      DE05F_-3   M      A18X+174234Y-008098X0850Y1560     S2      
317COUPON_GND2      VIA   -    MD0100PA00X+174234Y-007456X0200Y         S0      
327COUPON_GND2      DE05F_-3   M      A01X+174234Y-007098X0850Y1560R180 S1      
317COUPON_GND2      VIA   -    MD0100PA00X+174559Y-007197X0200Y         S0      
317COUPON_GND2      VIA   -    MD0100PA00X+180467Y-004758X0200Y    R180 S0      
317COUPON_GND2      VIA   -    MD0100PA00X+180467Y-003710X0200Y         S0      
317COUPON_GND2      VIA   -    MD0100PA00X+180467Y-002680X0200Y         S0      
317COUPON_GND2      VIA   -    MD0100PA00X+181095Y-004379X0200Y         S0      
317COUPON_GND2      VIA   -    MD0100PA00X+181096Y-004647X0200Y    R180 S0      
317COUPON_GND2      VIA   -    MD0100PA00X+180771Y-004649X0200Y    R180 S0      
317COUPON_GND2      VIA   -    MD0100PA00X+181094Y-004899X0200Y    R180 S0      
317COUPON_GND2      VIA   -    MD0100PA00X+180769Y-004900X0200Y    R180 S0      
317COUPON_GND2      VIA   -    MD0100PA00X+181096Y-003830X0200Y         S0      
317COUPON_GND2      VIA   -    MD0100PA00X+181095Y-004119X0200Y         S0      
317COUPON_GND2      VIA   -    MD0100PA00X+180771Y-003829X0200Y         S0      
317COUPON_GND2      VIA   -    MD0100PA00X+181096Y-002799X0200Y         S0      
317COUPON_GND2      VIA   -    MD0100PA00X+180771Y-002799X0200Y         S0      
317COUPON_GND2      VIA   -    MD0100PA00X+181095Y-003068X0200Y         S0      
317COUPON_GND2      VIA   -    MD0100PA00X+181094Y-002548X0200Y         S0      
317COUPON_GND2      VIA   -    MD0100PA00X+180769Y-002548X0200Y         S0      
317COUPON_GND2      VIA   -    MD0100PA00X+181094Y-003579X0200Y         S0      
327COUPON_GND2      DE15T_-3   M      A18X+180769Y-004219X0850Y1560     S2      
317COUPON_GND2      VIA   -    MD0100PA00X+180769Y-003578X0200Y         S0      
327COUPON_GND2      DE15T_-3   M      A01X+180769Y-003219X0850Y1560R180 S1      
317COUPON_GND2      VIA   -    MD0100PA00X+181095Y-003318X0200Y         S0      
317COUPON_GND2      VIA   -    MD0100PA00X+152017Y-004745X0200Y    R180 S0      
317COUPON_GND2      VIA   -    MD0100PA00X+152017Y-003696X0200Y         S0      
317COUPON_GND2      VIA   -    MD0100PA00X+152017Y-002666X0200Y         S0      
317COUPON_GND2      VIA   -    MD0100PA00X+152645Y-004366X0200Y         S0      
317COUPON_GND2      VIA   -    MD0100PA00X+152646Y-004634X0200Y    R180 S0      
317COUPON_GND2      VIA   -    MD0100PA00X+152321Y-004634X0200Y    R180 S0      
317COUPON_GND2      VIA   -    MD0100PA00X+152644Y-004886X0200Y    R180 S0      
317COUPON_GND2      VIA   -    MD0100PA00X+152319Y-004886X0200Y    R180 S0      
317COUPON_GND2      VIA   -    MD0100PA00X+152646Y-003817X0200Y         S0      
317COUPON_GND2      VIA   -    MD0100PA00X+152645Y-004106X0200Y         S0      
317COUPON_GND2      VIA   -    MD0100PA00X+152321Y-003816X0200Y         S0      
317COUPON_GND2      VIA   -    MD0100PA00X+152646Y-002786X0200Y         S0      
317COUPON_GND2      VIA   -    MD0100PA00X+152321Y-002786X0200Y         S0      
317COUPON_GND2      VIA   -    MD0100PA00X+152645Y-003055X0200Y         S0      
317COUPON_GND2      VIA   -    MD0100PA00X+152644Y-002534X0200Y         S0      
317COUPON_GND2      VIA   -    MD0100PA00X+152319Y-002534X0200Y         S0      
317COUPON_GND2      VIA   -    MD0100PA00X+152644Y-003566X0200Y         S0      
327COUPON_GND2      DE16T_-3   M      A18X+152319Y-004206X0850Y1560     S2      
317COUPON_GND2      VIA   -    MD0100PA00X+152319Y-003564X0200Y         S0      
327COUPON_GND2      DE14T_-3   M      A01X+152319Y-003206X0850Y1560R180 S1      
317COUPON_GND2      VIA   -    MD0100PA00X+152645Y-003305X0200Y         S0      
317COUPON_GND2      VIA   -    MD0100PA00X+148481Y-008637X0200Y    R180 S0      
317COUPON_GND2      VIA   -    MD0100PA00X+148481Y-007588X0200Y         S0      
317COUPON_GND2      VIA   -    MD0100PA00X+148481Y-006558X0200Y         S0      
317COUPON_GND2      VIA   -    MD0100PA00X+149109Y-008258X0200Y         S0      
317COUPON_GND2      VIA   -    MD0100PA00X+149110Y-008526X0200Y    R180 S0      
317COUPON_GND2      VIA   -    MD0100PA00X+148785Y-008526X0200Y    R180 S0      
317COUPON_GND2      VIA   -    MD0100PA00X+149109Y-008778X0200Y    R180 S0      
317COUPON_GND2      VIA   -    MD0100PA00X+148784Y-008778X0200Y    R180 S0      
317COUPON_GND2      VIA   -    MD0100PA00X+149110Y-007709X0200Y         S0      
317COUPON_GND2      VIA   -    MD0100PA00X+149109Y-007998X0200Y         S0      
317COUPON_GND2      VIA   -    MD0100PA00X+148785Y-007708X0200Y         S0      
317COUPON_GND2      VIA   -    MD0100PA00X+149110Y-006678X0200Y         S0      
317COUPON_GND2      VIA   -    MD0100PA00X+148785Y-006678X0200Y         S0      
317COUPON_GND2      VIA   -    MD0100PA00X+149109Y-006947X0200Y         S0      
317COUPON_GND2      VIA   -    MD0100PA00X+149109Y-006426X0200Y         S0      
317COUPON_GND2      VIA   -    MD0100PA00X+148784Y-006426X0200Y         S0      
317COUPON_GND2      VIA   -    MD0100PA00X+149109Y-007458X0200Y         S0      
327COUPON_GND2      DE06F_-3   M      A18X+148784Y-008098X0850Y1560     S2      
317COUPON_GND2      VIA   -    MD0100PA00X+148784Y-007456X0200Y         S0      
327COUPON_GND2      DE04F_-3   M      A01X+148784Y-007098X0850Y1560R180 S1      
317COUPON_GND2      VIA   -    MD0100PA00X+149109Y-007197X0200Y         S0      
317COUPON_GND2      VIA   -    MD0100PA00X+133478Y-006551X0200Y         S0      
317COUPON_GND2      VIA   -    MD0100PA00X+133478Y-007610X0200Y    R180 S0      
317COUPON_GND2      VIA   -    MD0100PA00X+133478Y-008650X0200Y    R180 S0      
317COUPON_GND2      VIA   -    MD0100PA00X+132850Y-006940X0200Y    R180 S0      
317COUPON_GND2      VIA   -    MD0100PA00X+132849Y-006672X0200Y         S0      
317COUPON_GND2      VIA   -    MD0100PA00X+133174Y-006671X0200Y         S0      
317COUPON_GND2      VIA   -    MD0100PA00X+132850Y-006421X0200Y         S0      
317COUPON_GND2      VIA   -    MD0100PA00X+133176Y-006419X0200Y         S0      
317COUPON_GND2      VIA   -    MD0100PA00X+132849Y-007489X0200Y    R180 S0      
317COUPON_GND2      VIA   -    MD0100PA00X+132850Y-007200X0200Y    R180 S0      
317COUPON_GND2      VIA   -    MD0100PA00X+133174Y-007490X0200Y    R180 S0      
317COUPON_GND2      VIA   -    MD0100PA00X+132849Y-008529X0200Y    R180 S0      
317COUPON_GND2      VIA   -    MD0100PA00X+133174Y-008529X0200Y    R180 S0      
317COUPON_GND2      VIA   -    MD0100PA00X+132850Y-008260X0200Y    R180 S0      
317COUPON_GND2      VIA   -    MD0100PA00X+132850Y-008780X0200Y    R180 S0      
317COUPON_GND2      VIA   -    MD0100PA00X+133176Y-008780X0200Y    R180 S0      
317COUPON_GND2      VIA   -    MD0100PA00X+132850Y-007740X0200Y    R180 S0      
327COUPON_GND2      DE04F_-3   M      A01X+133176Y-007101X0850Y1560     S1      
317COUPON_GND2      VIA   -    MD0100PA00X+133176Y-007742X0200Y    R180 S0      
327COUPON_GND2      DE06F_-3   M      A18X+133176Y-008101X0850Y1560R180 S2      
317COUPON_GND2      VIA   -    MD0100PA00X+132850Y-008010X0200Y    R180 S0      
317COUPON_GND2      VIA   -    MD0100PA00X+129478Y-002646X0200Y         S0      
317COUPON_GND2      VIA   -    MD0100PA00X+129478Y-003705X0200Y    R180 S0      
317COUPON_GND2      VIA   -    MD0100PA00X+129478Y-004735X0200Y    R180 S0      
317COUPON_GND2      VIA   -    MD0100PA00X+128850Y-003035X0200Y    R180 S0      
317COUPON_GND2      VIA   -    MD0100PA00X+128849Y-002767X0200Y         S0      
317COUPON_GND2      VIA   -    MD0100PA00X+129174Y-002766X0200Y         S0      
317COUPON_GND2      VIA   -    MD0100PA00X+128850Y-002516X0200Y         S0      
317COUPON_GND2      VIA   -    MD0100PA00X+129176Y-002514X0200Y         S0      
317COUPON_GND2      VIA   -    MD0100PA00X+128849Y-003584X0200Y    R180 S0      
317COUPON_GND2      VIA   -    MD0100PA00X+128850Y-003295X0200Y    R180 S0      
317COUPON_GND2      VIA   -    MD0100PA00X+129174Y-003585X0200Y    R180 S0      
317COUPON_GND2      VIA   -    MD0100PA00X+128849Y-004615X0200Y    R180 S0      
317COUPON_GND2      VIA   -    MD0100PA00X+129174Y-004615X0200Y    R180 S0      
317COUPON_GND2      VIA   -    MD0100PA00X+128850Y-004346X0200Y    R180 S0      
317COUPON_GND2      VIA   -    MD0100PA00X+128850Y-004867X0200Y    R180 S0      
317COUPON_GND2      VIA   -    MD0100PA00X+129176Y-004867X0200Y    R180 S0      
317COUPON_GND2      VIA   -    MD0100PA00X+128850Y-003836X0200Y    R180 S0      
327COUPON_GND2      DE14T_-3   M      A01X+129176Y-003196X0850Y1560     S1      
317COUPON_GND2      VIA   -    MD0100PA00X+129176Y-003837X0200Y    R180 S0      
327COUPON_GND2      DE16T_-3   M      A18X+129176Y-004196X0850Y1560R180 S2      
317COUPON_GND2      VIA   -    MD0100PA00X+128850Y-004096X0200Y    R180 S0      
317COUPON_GND2      VIA   -    MD0100PA00X+123367Y-004742X0200Y    R180 S0      
317COUPON_GND2      VIA   -    MD0100PA00X+123367Y-003684X0200Y         S0      
317COUPON_GND2      VIA   -    MD0100PA00X+123367Y-002654X0200Y         S0      
317COUPON_GND2      VIA   -    MD0100PA00X+123995Y-004353X0200Y         S0      
317COUPON_GND2      VIA   -    MD0100PA00X+123996Y-004621X0200Y    R180 S0      
317COUPON_GND2      VIA   -    MD0100PA00X+123671Y-004621X0200Y    R180 S0      
317COUPON_GND2      VIA   -    MD0100PA00X+123994Y-004873X0200Y    R180 S0      
317COUPON_GND2      VIA   -    MD0100PA00X+123669Y-004873X0200Y    R180 S0      
317COUPON_GND2      VIA   -    MD0100PA00X+123996Y-003804X0200Y         S0      
317COUPON_GND2      VIA   -    MD0100PA00X+123995Y-004093X0200Y         S0      
317COUPON_GND2      VIA   -    MD0100PA00X+123671Y-003803X0200Y         S0      
317COUPON_GND2      VIA   -    MD0100PA00X+123996Y-002773X0200Y         S0      
317COUPON_GND2      VIA   -    MD0100PA00X+123671Y-002773X0200Y         S0      
317COUPON_GND2      VIA   -    MD0100PA00X+123995Y-003042X0200Y         S0      
317COUPON_GND2      VIA   -    MD0100PA00X+123994Y-002522X0200Y         S0      
317COUPON_GND2      VIA   -    MD0100PA00X+123669Y-002522X0200Y         S0      
317COUPON_GND2      VIA   -    MD0100PA00X+123994Y-003553X0200Y         S0      
327COUPON_GND2      DE16T_-3   M      A18X+123669Y-004193X0850Y1560     S2      
317COUPON_GND2      VIA   -    MD0100PA00X+123669Y-003552X0200Y         S0      
327COUPON_GND2      DE13T_-3   M      A01X+123669Y-003193X0850Y1560R180 S1      
317COUPON_GND2      VIA   -    MD0100PA00X+123995Y-003292X0200Y         S0      
317COUPON_GND2      VIA   -    MD0100PA00X+122831Y-008637X0200Y    R180 S0      
317COUPON_GND2      VIA   -    MD0100PA00X+122831Y-007588X0200Y         S0      
317COUPON_GND2      VIA   -    MD0100PA00X+122831Y-006558X0200Y         S0      
317COUPON_GND2      VIA   -    MD0100PA00X+123459Y-008258X0200Y         S0      
317COUPON_GND2      VIA   -    MD0100PA00X+123460Y-008526X0200Y    R180 S0      
317COUPON_GND2      VIA   -    MD0100PA00X+123135Y-008518X0200Y    R180 S0      
317COUPON_GND2      VIA   -    MD0100PA00X+123459Y-008778X0200Y    R180 S0      
317COUPON_GND2      VIA   -    MD0100PA00X+123134Y-008769X0200Y    R180 S0      
317COUPON_GND2      VIA   -    MD0100PA00X+123460Y-007709X0200Y         S0      
317COUPON_GND2      VIA   -    MD0100PA00X+123459Y-007998X0200Y         S0      
317COUPON_GND2      VIA   -    MD0100PA00X+123135Y-007708X0200Y         S0      
317COUPON_GND2      VIA   -    MD0100PA00X+123460Y-006678X0200Y         S0      
317COUPON_GND2      VIA   -    MD0100PA00X+123135Y-006678X0200Y         S0      
317COUPON_GND2      VIA   -    MD0100PA00X+123459Y-006947X0200Y         S0      
317COUPON_GND2      VIA   -    MD0100PA00X+123459Y-006426X0200Y         S0      
317COUPON_GND2      VIA   -    MD0100PA00X+123134Y-006426X0200Y         S0      
317COUPON_GND2      VIA   -    MD0100PA00X+123459Y-007458X0200Y         S0      
327COUPON_GND2      DE06F_-3   M      A18X+123134Y-008098X0850Y1560     S2      
317COUPON_GND2      VIA   -    MD0100PA00X+123134Y-007456X0200Y         S0      
327COUPON_GND2      DE03F_-3   M      A01X+123134Y-007098X0850Y1560R180 S1      
317COUPON_GND2      VIA   -    MD0100PA00X+123459Y-007197X0200Y         S0      
317COUPON_GND2      VIA   -    MD0100PA00X+100828Y-002643X0200Y         S0      
317COUPON_GND2      VIA   -    MD0100PA00X+100828Y-003692X0200Y    R180 S0      
317COUPON_GND2      VIA   -    MD0100PA00X+100828Y-004722X0200Y    R180 S0      
317COUPON_GND2      VIA   -    MD0100PA00X+100200Y-003012X0200Y    R180 S0      
317COUPON_GND2      VIA   -    MD0100PA00X+100199Y-002754X0200Y         S0      
317COUPON_GND2      VIA   -    MD0100PA00X+100524Y-002763X0200Y         S0      
317COUPON_GND2      VIA   -    MD0100PA00X+100200Y-002503X0200Y         S0      
317COUPON_GND2      VIA   -    MD0100PA00X+100526Y-002511X0200Y         S0      
317COUPON_GND2      VIA   -    MD0100PA00X+100199Y-003571X0200Y    R180 S0      
317COUPON_GND2      VIA   -    MD0100PA00X+100200Y-003272X0200Y    R180 S0      
317COUPON_GND2      VIA   -    MD0100PA00X+100524Y-003572X0200Y    R180 S0      
317COUPON_GND2      VIA   -    MD0100PA00X+100199Y-004602X0200Y    R180 S0      
317COUPON_GND2      VIA   -    MD0100PA00X+100524Y-004602X0200Y    R180 S0      
317COUPON_GND2      VIA   -    MD0100PA00X+100200Y-004333X0200Y    R180 S0      
317COUPON_GND2      VIA   -    MD0100PA00X+100200Y-004854X0200Y    R180 S0      
317COUPON_GND2      VIA   -    MD0100PA00X+100526Y-004854X0200Y    R180 S0      
317COUPON_GND2      VIA   -    MD0100PA00X+100200Y-003822X0200Y    R180 S0      
327COUPON_GND2      DE13T_-3   M      A01X+100526Y-003183X0850Y1560     S1      
317COUPON_GND2      VIA   -    MD0100PA00X+100526Y-003824X0200Y    R180 S0      
327COUPON_GND2      DE16T_-3   M      A18X+100526Y-004183X0850Y1560R180 S2      
317COUPON_GND2      VIA   -    MD0100PA00X+100200Y-004083X0200Y    R180 S0      
317COUPON_GND2      VIA   -    MD0100PA00X+107200Y-008010X0200Y    R180 S0      
317COUPON_GND2      VIA   -    MD0100PA00X+107828Y-008640X0200Y    R180 S0      
317COUPON_GND2      VIA   -    MD0100PA00X+107526Y-008780X0200Y    R180 S0      
317COUPON_GND2      VIA   -    MD0100PA00X+107200Y-008780X0200Y    R180 S0      
317COUPON_GND2      VIA   -    MD0100PA00X+107200Y-008260X0200Y    R180 S0      
317COUPON_GND2      VIA   -    MD0100PA00X+107524Y-008529X0200Y    R180 S0      
317COUPON_GND2      VIA   -    MD0100PA00X+107199Y-008529X0200Y    R180 S0      
317COUPON_GND2      VIA   -    MD0100PA00X+095646Y-002761X0200Y         S0      
317COUPON_GND2      VIA   -    MD0100PA00X+095321Y-002760X0200Y         S0      
317COUPON_GND2      VIA   -    MD0100PA00X+095017Y-002640X0200Y         S0      
317COUPON_GND2      VIA   -    MD0100PA00X+095017Y-003719X0200Y    R180 S0      
317COUPON_GND2      VIA   -    MD0100PA00X+095319Y-003851X0200Y    R180 S0      
317COUPON_GND2      VIA   -    MD0100PA00X+095644Y-003850X0200Y    R180 S0      
317COUPON_GND2      VIA   -    MD0100PA00X+095321Y-003600X0200Y    R180 S0      
317COUPON_GND2      VIA   -    MD0100PA00X+095646Y-003598X0200Y    R180 S0      
317COUPON_GND2      VIA   -    MD0100PA00X+095645Y-003320X0200Y         S0      
317COUPON_GND2      VIA   -    MD0100PA00X+095645Y-003030X0200Y         S0      
317COUPON_GND2      VIA   -    MD0100PA00X+095644Y-002510X0200Y         S0      
327COUPON_GND2      DE11T_-3   M      A01X+095319Y-003180X0850Y1560R180 S1      
327COUPON_GND2      DE12T_-3   M      A18X+095319Y-003180X0850Y1560     S2      
317COUPON_GND2      VIA   -    MD0100PA00X+095319Y-002508X0200Y         S0      
317COUPON_GND2      VIA   -    MD0100PA00X+098130Y-006679X0200Y         S0      
317COUPON_GND2      VIA   -    MD0100PA00X+097805Y-006678X0200Y         S0      
317COUPON_GND2      VIA   -    MD0100PA00X+097501Y-006558X0200Y         S0      
317COUPON_GND2      VIA   -    MD0100PA00X+097501Y-007637X0200Y    R180 S0      
317COUPON_GND2      VIA   -    MD0100PA00X+097804Y-007769X0200Y    R180 S0      
317COUPON_GND2      VIA   -    MD0100PA00X+098129Y-007768X0200Y    R180 S0      
317COUPON_GND2      VIA   -    MD0100PA00X+097805Y-007518X0200Y    R180 S0      
317COUPON_GND2      VIA   -    MD0100PA00X+098130Y-007516X0200Y    R180 S0      
317COUPON_GND2      VIA   -    MD0100PA00X+098129Y-007238X0200Y         S0      
317COUPON_GND2      VIA   -    MD0100PA00X+098129Y-006948X0200Y         S0      
317COUPON_GND2      VIA   -    MD0100PA00X+098129Y-006428X0200Y         S0      
327COUPON_GND2      DE01F_-3   M      A01X+097804Y-007098X0850Y1560R180 S1      
327COUPON_GND2      DE02F_-3   M      A18X+097804Y-007098X0850Y1560     S2      
317COUPON_GND2      VIA   -    MD0100PA00X+097804Y-006426X0200Y         S0      
317COUPON_GND2      VIA   -    MD0100PA00X+071849Y-003601X0200Y    R180 S0      
317COUPON_GND2      VIA   -    MD0100PA00X+072174Y-003602X0200Y    R180 S0      
317COUPON_GND2      VIA   -    MD0100PA00X+072478Y-003722X0200Y    R180 S0      
317COUPON_GND2      VIA   -    MD0100PA00X+072478Y-002643X0200Y         S0      
317COUPON_GND2      VIA   -    MD0100PA00X+072176Y-002511X0200Y         S0      
317COUPON_GND2      VIA   -    MD0100PA00X+071850Y-002513X0200Y         S0      
317COUPON_GND2      VIA   -    MD0100PA00X+072174Y-002763X0200Y         S0      
317COUPON_GND2      VIA   -    MD0100PA00X+071849Y-002764X0200Y         S0      
317COUPON_GND2      VIA   -    MD0100PA00X+071850Y-003042X0200Y    R180 S0      
317COUPON_GND2      VIA   -    MD0100PA00X+071850Y-003332X0200Y    R180 S0      
317COUPON_GND2      VIA   -    MD0100PA00X+071850Y-003852X0200Y    R180 S0      
327COUPON_GND2      DE11T_-3   M      A01X+072176Y-003183X0850Y1560     S1      
327COUPON_GND2      DE12T_-3   M      A18X+072176Y-003183X0850Y1560R180 S2      
317COUPON_GND2      VIA   -    MD0100PA00X+072176Y-003854X0200Y    R180 S0      
317COUPON_GND2      VIA   -    MD0100PA00X+107199Y-007489X0200Y    R180 S0      
317COUPON_GND2      VIA   -    MD0100PA00X+107524Y-007490X0200Y    R180 S0      
317COUPON_GND2      VIA   -    MD0100PA00X+107828Y-007610X0200Y    R180 S0      
317COUPON_GND2      VIA   -    MD0100PA00X+107828Y-006561X0200Y         S0      
317COUPON_GND2      VIA   -    MD0100PA00X+107526Y-006429X0200Y         S0      
317COUPON_GND2      VIA   -    MD0100PA00X+107200Y-006421X0200Y         S0      
317COUPON_GND2      VIA   -    MD0100PA00X+107524Y-006681X0200Y         S0      
317COUPON_GND2      VIA   -    MD0100PA00X+107199Y-006672X0200Y         S0      
317COUPON_GND2      VIA   -    MD0100PA00X+107200Y-006940X0200Y    R180 S0      
317COUPON_GND2      VIA   -    MD0100PA00X+107200Y-007200X0200Y    R180 S0      
317COUPON_GND2      VIA   -    MD0100PA00X+107200Y-007740X0200Y    R180 S0      
327COUPON_GND2      DE03F_-3   M      A01X+107526Y-007101X0850Y1560     S1      
327COUPON_GND2      DE06F_-3   M      A18X+107526Y-008101X0850Y1560R180 S2      
317COUPON_GND2      VIA   -    MD0100PA00X+107526Y-007742X0200Y    R180 S0      
317COUPON_GND2      VIA   -    MD0100PA00X+083849Y-006682X0200Y         S0      
317COUPON_GND2      VIA   -    MD0100PA00X+084174Y-006681X0200Y         S0      
317COUPON_GND2      VIA   -    MD0100PA00X+083850Y-006431X0200Y         S0      
317COUPON_GND2      VIA   -    MD0100PA00X+084176Y-006429X0200Y         S0      
317COUPON_GND2      VIA   -    MD0100PA00X+084478Y-006561X0200Y         S0      
317COUPON_GND2      VIA   -    MD0100PA00X+083850Y-006960X0200Y    R180 S0      
317COUPON_GND2      VIA   -    MD0100PA00X+084478Y-007640X0200Y    R180 S0      
317COUPON_GND2      VIA   -    MD0100PA00X+084174Y-007520X0200Y    R180 S0      
317COUPON_GND2      VIA   -    MD0100PA00X+084176Y-007772X0200Y    R180 S0      
317COUPON_GND2      VIA   -    MD0100PA00X+083849Y-007519X0200Y    R180 S0      
317COUPON_GND2      VIA   -    MD0100PA00X+083850Y-007250X0200Y    R180 S0      
327COUPON_GND2      DE01F_-3   M      A01X+084176Y-007101X0850Y1560     S1      
317COUPON_GND2      VIA   -    MD0100PA00X+083850Y-007770X0200Y    R180 S0      
327COUPON_GND2      DE02F_-3   M      A18X+084176Y-007101X0850Y1560R180 S2      
327P0V8_PEX3        C1868 -1          A18X+163871Y+115561X0120Y0150R180 S2      
327P0V8_PEX3        C1890 -1          A18X+163871Y+117431X0120Y0150R180 S2      
327P0V8_PEX3        C1889 -1          A18X+163041Y+117349X0120Y0150R090 S2      
327P0V8_PEX3        C1913 -1          A18X+162293Y+117349X0120Y0150R090 S2      
327P0V8_PEX3        C1914 -1          A18X+161545Y+117349X0120Y0150R090 S2      
327P0V8_PEX3        C1887 -1          A18X+160797Y+117349X0120Y0150R090 S2      
327P0V8_PEX3        C1919 -1          A18X+159675Y+117349X0120Y0150R090 S2      
327P0V8_PEX3        C1885 -1          A18X+158927Y+117349X0120Y0150R090 S2      
327P0V8_PEX3        C1881 -1          A18X+158179Y+117349X0120Y0150R090 S2      
327P0V8_PEX3        C1904 -1          A18X+157431Y+117349X0120Y0150R090 S2      
327P0V8_PEX3        C1902 -1          A18X+156683Y+117349X0120Y0150R090 S2      
327P0V8_PEX3        C1894 -1          A18X+156601Y+118179X0120Y0150     S2      
327P0V8_PEX3        C1893 -1          A18X+156391Y+117825X0120Y0150R180 S2      
327P0V8_PEX3        C1865 -1          A18X+161896Y+116229X0280Y0320R090 S2      
327P0V8_PEX3        C1899 -1          A18X+162667Y+115853X0120Y0150R090 S2      
327P0V8_PEX3        C1910 -1          A18X+161919Y+115853X0120Y0150R090 S2      
327P0V8_PEX3        C1912 -1          A18X+162667Y+117139X0120Y0150R270 S2      
327P0V8_PEX3        C1901 -1          A18X+161919Y+117139X0120Y0150R270 S2      
327P0V8_PEX3        C1867 -1          A18X+160026Y+116229X0280Y0320R090 S2      
327P0V8_PEX3        C1921 -1          A18X+161171Y+115853X0120Y0150R090 S2      
327P0V8_PEX3        C1908 -1          A18X+160049Y+115853X0120Y0150R090 S2      
327P0V8_PEX3        C1909 -1          A18X+161171Y+117139X0120Y0150R270 S2      
327P0V8_PEX3        C1898 -1          A18X+160055Y+117139X0120Y0150R270 S2      
327P0V8_PEX3        C1877 -1          A18X+160349Y+116683X0120Y0150     S2      
327P0V8_PEX3        C1866 -1          A18X+158530Y+116229X0280Y0320R090 S2      
327P0V8_PEX3        C1883 -1          A18X+159301Y+115853X0120Y0150R090 S2      
327P0V8_PEX3        C1917 -1          A18X+158553Y+115853X0120Y0150R090 S2      
327P0V8_PEX3        C1884 -1          A18X+159301Y+117139X0120Y0150R270 S2      
327P0V8_PEX3        C1907 -1          A18X+158553Y+117139X0120Y0150R270 S2      
327P0V8_PEX3        C1903 -1          A18X+157805Y+115853X0120Y0150R090 S2      
327P0V8_PEX3        C1915 -1          A18X+157057Y+115853X0120Y0150R090 S2      
327P0V8_PEX3        C1882 -1          A18X+157805Y+117139X0120Y0150R270 S2      
327P0V8_PEX3        C1905 -1          A18X+157057Y+117139X0120Y0150R270 S2      
327P0V8_PEX3        C1891 -1          A18X+156309Y+115853X0120Y0150R090 S2      
327P0V8_PEX3        C1872 -1          A18X+156309Y+117139X0120Y0150R270 S2      
327P0V8_PEX3        C1900 -1          A18X+163041Y+115643X0120Y0150R270 S2      
327P0V8_PEX3        C1911 -1          A18X+162293Y+115643X0120Y0150R270 S2      
327P0V8_PEX3        C1886 -1          A18X+161545Y+115643X0120Y0150R270 S2      
327P0V8_PEX3        C1920 -1          A18X+160797Y+115643X0120Y0150R270 S2      
327P0V8_PEX3        C1906 -1          A18X+159675Y+115643X0120Y0150R270 S2      
327P0V8_PEX3        C1918 -1          A18X+158927Y+115643X0120Y0150R270 S2      
327P0V8_PEX3        C1916 -1          A18X+158179Y+115643X0120Y0150R270 S2      
327P0V8_PEX3        C1880 -1          A18X+157431Y+115643X0120Y0150R270 S2      
327P0V8_PEX3        C1879 -1          A18X+156683Y+115643X0120Y0150R270 S2      
327P0V8_PEX3        C1869 -1          A18X+156391Y+115187X0120Y0150R180 S2      
327P0V8_PEX3        C1870 -1          A18X+156601Y+114813X0120Y0150     S2      
327P0V8_PEX3        C1871 -1          A18X+156391Y+114439X0120Y0150R180 S2      
327P0V8_PEX3        C1895 -1   M      A18X+158115Y+116683X0120Y0150     S2      
327P0V8_PEX3        C1874 -1   M      A18X+157367Y+116683X0120Y0150     S2      
327P0V8_PEX3        C1892 -1   M      A18X+156619Y+116683X0120Y0150     S2      
327P0V8_PEX3        C1873 -1   M      A18X+156371Y+118510X0120Y0150R180 S2      
327P0V8_PEX3        C1875 -1   M      A18X+159611Y+116683X0120Y0150     S2      
327P0V8_PEX3        C1896 -1   M      A18X+158863Y+116683X0120Y0150     S2      
327P0V8_PEX3        C1876 -1   M      A18X+160821Y+116690X0120Y0150R180 S2      
327P0V8_PEX3        C1878 -1   M      A18X+162967Y+116683X0120Y0150     S2      
327P0V8_PEX3        C1888 -1   M      A18X+162219Y+116683X0120Y0150     S2      
327P0V8_PEX3        C1897 -1   M      A18X+161531Y+116690X0120Y0150     S2      
317P0V8_PEX3        VIA   -    MD0080PA00X+156309Y+117805X0160Y         S0      
317P0V8_PEX3        VIA   -    MD0080PA00X+156309Y+118553X0160Y         S0      
317P0V8_PEX3        VIA   -    MD0080PA00X+156309Y+117057X0160Y         S0      
317P0V8_PEX3        VIA   -    MD0080PA00X+156309Y+115935X0160Y         S0      
317P0V8_PEX3        VIA   -    MD0080PA00X+156309Y+115187X0160Y         S0      
317P0V8_PEX3        VIA   -    MD0080PA00X+156309Y+114439X0160Y         S0      
317P0V8_PEX3        VIA   -    MD0080PA00X+156683Y+117431X0160Y         S0      
317P0V8_PEX3        VIA   -    MD0080PA00X+156683Y+118179X0160Y         S0      
317P0V8_PEX3        VIA   -    MD0080PA00X+157431Y+117431X0160Y         S0      
317P0V8_PEX3        VIA   -    MD0080PA00X+157057Y+115935X0160Y         S0      
317P0V8_PEX3        VIA   -    MD0080PA00X+157805Y+115935X0160Y         S0      
317P0V8_PEX3        VIA   -    MD0080PA00X+156683Y+116683X0160Y         S0      
317P0V8_PEX3        VIA   -    MD0080PA00X+157057Y+117057X0160Y         S0      
317P0V8_PEX3        VIA   -    MD0080PA00X+157431Y+116683X0160Y         S0      
317P0V8_PEX3        VIA   -    MD0080PA00X+157805Y+117057X0160Y         S0      
317P0V8_PEX3        VIA   -    MD0080PA00X+156683Y+115561X0160Y         S0      
317P0V8_PEX3        VIA   -    MD0080PA00X+156683Y+114813X0160Y         S0      
317P0V8_PEX3        VIA   -    MD0080PA00X+157431Y+115561X0160Y         S0      
317P0V8_PEX3        VIA   -    MD0080PA00X+158179Y+117431X0160Y         S0      
317P0V8_PEX3        VIA   -    MD0080PA00X+158927Y+117431X0160Y         S0      
317P0V8_PEX3        VIA   -    MD0080PA00X+159301Y+115935X0160Y         S0      
317P0V8_PEX3        VIA   -    MD0080PA00X+158553Y+115935X0160Y         S0      
317P0V8_PEX3        VIA   -    MD0080PA00X+158179Y+116683X0160Y         S0      
317P0V8_PEX3        VIA   -    MD0080PA00X+158927Y+116683X0160Y         S0      
317P0V8_PEX3        VIA   -    MD0080PA00X+158553Y+117057X0160Y         S0      
317P0V8_PEX3        VIA   -    MD0080PA00X+159301Y+117057X0160Y         S0      
317P0V8_PEX3        VIA   -    MD0080PA00X+158927Y+115561X0160Y         S0      
317P0V8_PEX3        VIA   -    MD0080PA00X+158179Y+115561X0160Y         S0      
317P0V8_PEX3        VIA   -    MD0080PA00X+159675Y+117431X0160Y         S0      
317P0V8_PEX3        VIA   -    MD0080PA00X+160797Y+117431X0160Y         S0      
317P0V8_PEX3        VIA   -    MD0080PA00X+160049Y+115935X0160Y         S0      
317P0V8_PEX3        VIA   -    MD0080PA00X+161171Y+115935X0160Y         S0      
317P0V8_PEX3        VIA   -    MD0080PA00X+159675Y+116683X0160Y         S0      
317P0V8_PEX3        VIA   -    MD0080PA00X+160049Y+117057X0160Y         S0      
317P0V8_PEX3        VIA   -    MD0080PA00X+161171Y+117057X0160Y         S0      
317P0V8_PEX3        VIA   -    MD0080PA00X+160797Y+116683X0160Y         S0      
317P0V8_PEX3        VIA   -    MD0080PA00X+160797Y+115561X0160Y         S0      
317P0V8_PEX3        VIA   -    MD0080PA00X+159675Y+115561X0160Y         S0      
317P0V8_PEX3        VIA   -    MD0080PA00X+162667Y+117057X0160Y         S0      
317P0V8_PEX3        VIA   -    MD0080PA00X+162293Y+116683X0160Y         S0      
317P0V8_PEX3        VIA   -    MD0080PA00X+161919Y+115935X0160Y         S0      
317P0V8_PEX3        VIA   -    MD0080PA00X+162667Y+115935X0160Y         S0      
317P0V8_PEX3        VIA   -    MD0080PA00X+161919Y+117057X0160Y         S0      
317P0V8_PEX3        VIA   -    MD0080PA00X+161545Y+116683X0160Y         S0      
317P0V8_PEX3        VIA   -    MD0080PA00X+161545Y+115561X0160Y         S0      
317P0V8_PEX3        VIA   -    MD0080PA00X+162293Y+115561X0160Y         S0      
317P0V8_PEX3        VIA   -    MD0080PA00X+161545Y+117431X0160Y         S0      
317P0V8_PEX3        VIA   -    MD0080PA00X+162293Y+117431X0160Y         S0      
317P0V8_PEX3        VIA   -    MD0080PA00X+163041Y+115561X0160Y         S0      
317P0V8_PEX3        VIA   -    MD0080PA00X+163789Y+115561X0160Y         S0      
317P0V8_PEX3        VIA   -    MD0080PA00X+163041Y+117431X0160Y         S0      
317P0V8_PEX3        VIA   -    MD0080PA00X+163789Y+117431X0160Y         S0      
317P0V8_PEX3        VIA   -    MD0080PA00X+163041Y+116683X0160Y         S0      
327P0V8_PEX3        PR158 -2          A18X+141055Y+110882X0198Y0197R090 S2      
327P0V8_PEX3        PR162 -2          A18X+144267Y+110882X0198Y0197R090 S2      
327P0V8_PEX3        C4376 -1          A18X+142094Y+121632X0120Y0150R090 S2      
327P0V8_PEX3        C4377 -1          A18X+143434Y+121632X0120Y0150R090 S2      
327P0V8_PEX3        C4362 -1          A18X+144590Y+121635X0120Y0150R090 S2      
327P0V8_PEX3        C4363 -1          A18X+144280Y+121632X0120Y0150R090 S2      
327P0V8_PEX3        C4372 -1          A18X+143836Y+121791X0280Y0320R180 S2      
327P0V8_PEX3        C4373 -1          A18X+143013Y+121791X0280Y0320R180 S2      
327P0V8_PEX3        C4358 -1          A18X+142486Y+121791X0280Y0320R180 S2      
327P0V8_PEX3        C4359 -1          A18X+141143Y+121791X0280Y0320R180 S2      
327P0V8_PEX3        C4374 -1          A18X+141658Y+121791X0280Y0320R180 S2      
327P0V8_PEX3        C4360 -1          A01X+141495Y+121722X0280Y0320R180 S1      
327P0V8_PEX3        C4375 -1   M      A18X+140308Y+121791X0280Y0320R180 S2      
327P0V8_PEX3        C4361 -1          A01X+144066Y+121706X0280Y0320R180 S1      
327P0V8_PEX3        R5796 -1B  M      A18X+142700Y+125381X0100Y0200R270 S2      
327P0V8_PEX3        R5796 -1A  M      A18X+142700Y+125136X0590Y0790R270 S2      
327P0V8_PEX3        L77   -1   M      A18X+142700Y+125185X0460Y3860R270 S2      
327P0V8_PEX3        L76   -1   M      A18X+140340Y+123473X0460Y3860     S2      
327P0V8_PEX3        R5797 -1A  M      A18X+140390Y+123473X0590Y0790     S2      
327P0V8_PEX3        R5797 -1B  M      A18X+140145Y+123473X0100Y0200     S2      
327P0V8_PEX3        PR18  -1          A18X+142731Y+119257X0280Y0320     S2      
327P0V8_PEX3        PC182 -1          A18X+141431Y+119197X0400Y0500R090 S2      
327P0V8_PEX3        PC199 -1          A18X+140084Y+119197X0400Y0500R090 S2      
327P0V8_PEX3        PR128 -1          A18X+138562Y+119347X0198Y0197     S2      
327P0V8_PEX3        PC184 -1          A18X+142665Y+116874X0950Y1110R090 S2      
327P0V8_PEX3        PC181 -1          A18X+141274Y+115904X0400Y0500R270 S2      
327P0V8_PEX3        PC200 -1          A18X+139882Y+116874X0950Y1110R090 S2      
327P0V8_PEX3        L75   -1   M      A01X+142700Y+125185X0460Y3860R090 S1      
327P0V8_PEX3        R5798 -1A  M      A01X+142700Y+125087X0590Y0790R090 S1      
327P0V8_PEX3        R5798 -1B  M      A01X+142700Y+125332X0100Y0200R090 S1      
327P0V8_PEX3        L78   -1   M      A01X+140340Y+123473X0460Y3860R180 S1      
327P0V8_PEX3        R5795 -1A  M      A01X+140390Y+123473X0590Y0790R180 S1      
327P0V8_PEX3        R5795 -1B  M      A01X+140145Y+123473X0100Y0200R180 S1      
327P0V8_PEX3        PC198 -1          A01X+144124Y+119197X0400Y0500R270 S1      
327P0V8_PEX3        PC197 -1          A01X+141431Y+119197X0400Y0500R270 S1      
327P0V8_PEX3        PC183 -1          A01X+138738Y+119197X0400Y0500R270 S1      
327P0V8_PEX3        PC185 -1          A01X+142778Y+118306X0950Y1110R090 S1      
327P0V8_PEX3        PC201 -1          A01X+140084Y+118306X0950Y1110R090 S1      
327P0V8_PEX3        PC196 -1          A01X+144245Y+115833X0198Y0197R270 S1      
327P0V8_PEX3        PL16  -2          A01X+142665Y+116776X1220Y1320R180 S1      
327P0V8_PEX3        PL15  -2          A01X+139882Y+116776X1220Y1320R180 S1      
327P0V8_PEX3        PC180 -1          A01X+138302Y+115833X0198Y0197R270 S1      
317P0V8_PEX3        VIA   -    MD0100PA00X+141674Y+115820X0200Y         S0      
317P0V8_PEX3        VIA   -    MD0100PA00X+142874Y+124219X0200Y         S0      
317P0V8_PEX3        VIA   -    MD0100PA00X+142874Y+124619X0200Y         S0      
317P0V8_PEX3        VIA   -    MD0100PA00X+142474Y+124219X0200Y         S0      
317P0V8_PEX3        VIA   -    MD0100PA00X+142474Y+124619X0200Y         S0      
317P0V8_PEX3        VIA   -    MD0100PA00X+142074Y+124219X0200Y         S0      
317P0V8_PEX3        VIA   -    MD0100PA00X+142074Y+124619X0200Y         S0      
317P0V8_PEX3        VIA   -    MD0100PA00X+140874Y+124619X0200Y         S0      
317P0V8_PEX3        VIA   -    MD0100PA00X+140874Y+124219X0200Y         S0      
317P0V8_PEX3        VIA   -    M      A01X+141674Y+124219X0200Y         S2      
017P0V8_PEX3        VIA   -    M      A18X+141674Y+124219X0260Y         S2      
017P0V8_PEX3              -    MD0100PA00X+141674Y+124219                       
317P0V8_PEX3        VIA   -    MD0100PA00X+141674Y+124619X0200Y         S0      
317P0V8_PEX3        VIA   -    MD0100PA00X+141274Y+124219X0200Y         S0      
317P0V8_PEX3        VIA   -    MD0100PA00X+141274Y+124619X0200Y         S0      
317P0V8_PEX3        VIA   -    MD0100PA00X+143674Y+122619X0200Y         S0      
317P0V8_PEX3        VIA   -    MD0100PA00X+143274Y+122619X0200Y         S0      
317P0V8_PEX3        VIA   -    M      A01X+143274Y+123019X0200Y         S2      
017P0V8_PEX3        VIA   -    M      A18X+143274Y+123019X0260Y         S2      
017P0V8_PEX3              -    MD0100PA00X+143274Y+123019                       
317P0V8_PEX3        VIA   -    MD0100PA00X+143274Y+123419X0200Y         S0      
317P0V8_PEX3        VIA   -    MD0100PA00X+142874Y+122619X0200Y         S0      
317P0V8_PEX3        VIA   -    MD0100PA00X+142874Y+123019X0200Y         S0      
317P0V8_PEX3        VIA   -    MD0100PA00X+142874Y+123419X0200Y         S0      
317P0V8_PEX3        VIA   -    MD0100PA00X+142874Y+123819X0200Y         S0      
317P0V8_PEX3        VIA   -    MD0100PA00X+142474Y+122619X0200Y         S0      
317P0V8_PEX3        VIA   -    MD0100PA00X+142474Y+123019X0200Y         S0      
317P0V8_PEX3        VIA   -    MD0100PA00X+142474Y+123419X0200Y         S0      
317P0V8_PEX3        VIA   -    M      A01X+142474Y+123819X0200Y         S2      
017P0V8_PEX3        VIA   -    M      A18X+142474Y+123819X0260Y         S2      
017P0V8_PEX3              -    MD0100PA00X+142474Y+123819                       
317P0V8_PEX3        VIA   -    M      A01X+142074Y+122619X0200Y         S2      
017P0V8_PEX3        VIA   -    M      A18X+142074Y+122619X0260Y         S2      
017P0V8_PEX3              -    MD0100PA00X+142074Y+122619                       
317P0V8_PEX3        VIA   -    MD0100PA00X+142074Y+123019X0200Y         S0      
317P0V8_PEX3        VIA   -    MD0100PA00X+142074Y+123419X0200Y         S0      
317P0V8_PEX3        VIA   -    MD0100PA00X+142074Y+123819X0200Y         S0      
317P0V8_PEX3        VIA   -    MD0100PA00X+141674Y+122619X0200Y         S0      
317P0V8_PEX3        VIA   -    MD0100PA00X+141674Y+123019X0200Y         S0      
317P0V8_PEX3        VIA   -    MD0100PA00X+141674Y+123419X0200Y         S0      
317P0V8_PEX3        VIA   -    MD0100PA00X+141674Y+123819X0200Y         S0      
317P0V8_PEX3        VIA   -    MD0100PA00X+141274Y+122619X0200Y         S0      
317P0V8_PEX3        VIA   -    MD0100PA00X+141274Y+123019X0200Y         S0      
317P0V8_PEX3        VIA   -    MD0100PA00X+141274Y+123419X0200Y         S0      
317P0V8_PEX3        VIA   -    MD0100PA00X+141274Y+123819X0200Y         S0      
317P0V8_PEX3        VIA   -    MD0100PA00X+140874Y+122619X0200Y         S0      
317P0V8_PEX3        VIA   -    MD0100PA00X+140874Y+123019X0200Y         S0      
317P0V8_PEX3        VIA   -    MD0100PA00X+140874Y+123419X0200Y         S0      
317P0V8_PEX3        VIA   -    MD0100PA00X+140874Y+123819X0200Y         S0      
317P0V8_PEX3        VIA   -    MD0100PA00X+143674Y+122219X0200Y         S0      
317P0V8_PEX3        VIA   -    MD0100PA00X+143274Y+122219X0200Y         S0      
317P0V8_PEX3        VIA   -    MD0100PA00X+142874Y+122219X0200Y         S0      
317P0V8_PEX3        VIA   -    MD0100PA00X+142474Y+122219X0200Y         S0      
317P0V8_PEX3        VIA   -    MD0100PA00X+142074Y+122219X0200Y         S0      
317P0V8_PEX3        VIA   -    MD0100PA00X+141674Y+122219X0200Y         S0      
317P0V8_PEX3        VIA   -    MD0100PA00X+141274Y+122219X0200Y         S0      
317P0V8_PEX3        VIA   -    MD0100PA00X+140874Y+122219X0200Y         S0      
317P0V8_PEX3        VIA   -    MD0100PA00X+143724Y+119012X0200Y         S0      
317P0V8_PEX3        VIA   -    MD0100PA00X+143724Y+119262X0200Y         S0      
317P0V8_PEX3        VIA   -    MD0100PA00X+141831Y+119012X0200Y    R180 S0      
317P0V8_PEX3        VIA   -    MD0100PA00X+141831Y+119262X0200Y    R180 S0      
317P0V8_PEX3        VIA   -    MD0100PA00X+140484Y+119262X0200Y    R180 S0      
317P0V8_PEX3        VIA   -    MD0100PA00X+140484Y+119012X0200Y    R180 S0      
317P0V8_PEX3        VIA   -    MD0100PA00X+141031Y+119012X0200Y         S0      
317P0V8_PEX3        VIA   -    MD0100PA00X+141031Y+119262X0200Y         S0      
317P0V8_PEX3        VIA   -    MD0100PA00X+139138Y+119262X0200Y    R180 S0      
317P0V8_PEX3        VIA   -    MD0100PA00X+139138Y+119012X0200Y    R180 S0      
327P0V8_PEX3        PEX3  -AC33       A01X+163602Y+117244X0180Y         S1      
327P0V8_PEX3        PEX3  -AC25       A01X+160610Y+117244X0180Y         S1      
327P0V8_PEX3        PEX3  -AC17       A01X+157618Y+117244X0180Y         S1      
327P0V8_PEX3        PEX3  -Y14 M      A01X+156496Y+118366X0180Y         S1      
327P0V8_PEX3        PEX3  -AA15       A01X+156870Y+117992X0180Y         S1      
317P0V8_PEX3        VIA   -    MD0100PA00X+143732Y+117488X0200Y         S0      
317P0V8_PEX3        VIA   -    MD0100PA00X+143482Y+117488X0200Y         S0      
317P0V8_PEX3        VIA   -    MD0100PA00X+143492Y+118692X0200Y    R180 S0      
317P0V8_PEX3        VIA   -    MD0100PA00X+143492Y+118442X0200Y    R180 S0      
317P0V8_PEX3        VIA   -    MD0100PA00X+143492Y+118192X0200Y    R180 S0      
317P0V8_PEX3        VIA   -    MD0100PA00X+143492Y+117942X0200Y    R180 S0      
317P0V8_PEX3        VIA   -    MD0100PA00X+142062Y+117921X0200Y         S0      
317P0V8_PEX3        VIA   -    MD0100PA00X+142062Y+118171X0200Y         S0      
317P0V8_PEX3        VIA   -    MD0100PA00X+142062Y+118421X0200Y         S0      
317P0V8_PEX3        VIA   -    MD0100PA00X+142062Y+118671X0200Y         S0      
317P0V8_PEX3        VIA   -    MD0100PA00X+141905Y+117488X0200Y         S0      
317P0V8_PEX3        VIA   -    MD0100PA00X+140800Y+118692X0200Y    R180 S0      
317P0V8_PEX3        VIA   -    MD0100PA00X+140800Y+118442X0200Y    R180 S0      
317P0V8_PEX3        VIA   -    MD0100PA00X+140800Y+118192X0200Y    R180 S0      
317P0V8_PEX3        VIA   -    MD0100PA00X+140800Y+117942X0200Y    R180 S0      
317P0V8_PEX3        VIA   -    MD0100PA00X+140699Y+117488X0200Y         S0      
317P0V8_PEX3        VIA   -    MD0100PA00X+140949Y+117488X0200Y         S0      
317P0V8_PEX3        VIA   -    MD0100PA00X+141655Y+117488X0200Y         S0      
317P0V8_PEX3        VIA   -    MD0100PA00X+139370Y+117921X0200Y         S0      
317P0V8_PEX3        VIA   -    MD0100PA00X+139370Y+118171X0200Y         S0      
317P0V8_PEX3        VIA   -    MD0100PA00X+139370Y+118421X0200Y         S0      
317P0V8_PEX3        VIA   -    MD0100PA00X+139370Y+118671X0200Y         S0      
317P0V8_PEX3        VIA   -    MD0100PA00X+139122Y+117488X0200Y         S0      
317P0V8_PEX3        VIA   -    MD0100PA00X+138872Y+117488X0200Y         S0      
327P0V8_PEX3        PEX3  -AE31       A01X+162854Y+116496X0180Y         S1      
327P0V8_PEX3        PEX3  -AE27       A01X+161358Y+116496X0180Y         S1      
327P0V8_PEX3        PEX3  -AD28M      A01X+161732Y+116870X0180Y         S1      
327P0V8_PEX3        PEX3  -AC29M      A01X+162106Y+117244X0180Y         S1      
327P0V8_PEX3        PEX3  -AE29       A01X+162106Y+116496X0180Y         S1      
327P0V8_PEX3        PEX3  -AD30M      A01X+162480Y+116870X0180Y         S1      
327P0V8_PEX3        PEX3  -AC31M      A01X+162854Y+117244X0180Y         S1      
327P0V8_PEX3        PEX3  -AE25       A01X+160610Y+116496X0180Y         S1      
327P0V8_PEX3        PEX3  -AD26       A01X+160984Y+116870X0180Y         S1      
327P0V8_PEX3        PEX3  -AC27M      A01X+161358Y+117244X0180Y         S1      
327P0V8_PEX3        PEX3  -AD24       A01X+160236Y+116870X0180Y         S1      
327P0V8_PEX3        PEX3  -AC23M      A01X+159862Y+117244X0180Y         S1      
327P0V8_PEX3        PEX3  -AD22M      A01X+159488Y+116870X0180Y         S1      
327P0V8_PEX3        PEX3  -AE23       A01X+159862Y+116496X0180Y         S1      
327P0V8_PEX3        PEX3  -AC21M      A01X+159114Y+117244X0180Y         S1      
327P0V8_PEX3        PEX3  -AE21       A01X+159114Y+116496X0180Y         S1      
327P0V8_PEX3        PEX3  -AC19M      A01X+158366Y+117244X0180Y         S1      
327P0V8_PEX3        PEX3  -AD20M      A01X+158740Y+116870X0180Y         S1      
327P0V8_PEX3        PEX3  -AD18M      A01X+157992Y+116870X0180Y         S1      
327P0V8_PEX3        PEX3  -AE19       A01X+158366Y+116496X0180Y         S1      
327P0V8_PEX3        PEX3  -AC15M      A01X+156870Y+117244X0180Y         S1      
327P0V8_PEX3        PEX3  -AB14M      A01X+156496Y+117618X0180Y         S1      
327P0V8_PEX3        PEX3  -AD16M      A01X+157244Y+116870X0180Y         S1      
327P0V8_PEX3        PEX3  -AE17       A01X+157618Y+116496X0180Y         S1      
327P0V8_PEX3        PEX3  -AF14       A01X+156496Y+116122X0180Y         S1      
327P0V8_PEX3        PEX3  -AE15       A01X+156870Y+116496X0180Y         S1      
327P0V8_PEX3        PEX3  -AD14M      A01X+156496Y+116870X0180Y         S1      
317P0V8_PEX3        VIA   -    MD0100PA00X+143732Y+116238X0200Y         S0      
317P0V8_PEX3        VIA   -    MD0100PA00X+144267Y+110636X0200Y         S0      
317P0V8_PEX3        VIA   -    MD0100PA00X+143732Y+116488X0200Y         S0      
317P0V8_PEX3        VIA   -    MD0100PA00X+143732Y+116738X0200Y         S0      
317P0V8_PEX3        VIA   -    MD0100PA00X+143732Y+116988X0200Y         S0      
317P0V8_PEX3        VIA   -    MD0100PA00X+143732Y+117238X0200Y         S0      
317P0V8_PEX3        VIA   -    MD0100PA00X+143482Y+117238X0200Y         S0      
317P0V8_PEX3        VIA   -    MD0100PA00X+143482Y+116988X0200Y         S0      
317P0V8_PEX3        VIA   -    MD0100PA00X+143482Y+116738X0200Y         S0      
317P0V8_PEX3        VIA   -    MD0100PA00X+143482Y+116488X0200Y         S0      
317P0V8_PEX3        VIA   -    MD0100PA00X+143482Y+116238X0200Y         S0      
317P0V8_PEX3        VIA   -    MD0100PA00X+144245Y+116083X0200Y         S0      
317P0V8_PEX3        VIA   -    MD0100PA00X+141905Y+117238X0200Y         S0      
317P0V8_PEX3        VIA   -    MD0100PA00X+141905Y+116988X0200Y         S0      
317P0V8_PEX3        VIA   -    MD0100PA00X+141905Y+116738X0200Y         S0      
317P0V8_PEX3        VIA   -    MD0100PA00X+141905Y+116488X0200Y         S0      
317P0V8_PEX3        VIA   -    MD0100PA00X+141905Y+116238X0200Y         S0      
317P0V8_PEX3        VIA   -    MD0100PA00X+140949Y+116488X0200Y         S0      
317P0V8_PEX3        VIA   -    MD0100PA00X+140949Y+116238X0200Y         S0      
317P0V8_PEX3        VIA   -    MD0100PA00X+141055Y+110630X0200Y         S0      
317P0V8_PEX3        VIA   -    MD0100PA00X+140699Y+116238X0200Y         S0      
317P0V8_PEX3        VIA   -    MD0100PA00X+140699Y+116488X0200Y         S0      
317P0V8_PEX3        VIA   -    MD0100PA00X+140699Y+116738X0200Y         S0      
317P0V8_PEX3        VIA   -    MD0100PA00X+141655Y+117238X0200Y         S0      
317P0V8_PEX3        VIA   -    MD0100PA00X+141655Y+116988X0200Y         S0      
317P0V8_PEX3        VIA   -    MD0100PA00X+141655Y+116738X0200Y         S0      
317P0V8_PEX3        VIA   -    MD0100PA00X+141655Y+116488X0200Y         S0      
317P0V8_PEX3        VIA   -    MD0100PA00X+141655Y+116238X0200Y         S0      
317P0V8_PEX3        VIA   -    MD0100PA00X+140699Y+116988X0200Y         S0      
317P0V8_PEX3        VIA   -    MD0100PA00X+140699Y+117238X0200Y         S0      
317P0V8_PEX3        VIA   -    MD0100PA00X+140949Y+117238X0200Y         S0      
317P0V8_PEX3        VIA   -    MD0100PA00X+140949Y+116988X0200Y         S0      
317P0V8_PEX3        VIA   -    MD0100PA00X+140949Y+116738X0200Y         S0      
317P0V8_PEX3        VIA   -    MD0100PA00X+139122Y+117238X0200Y         S0      
317P0V8_PEX3        VIA   -    MD0100PA00X+139122Y+116988X0200Y         S0      
317P0V8_PEX3        VIA   -    MD0100PA00X+139122Y+116738X0200Y         S0      
317P0V8_PEX3        VIA   -    MD0100PA00X+139122Y+116488X0200Y         S0      
317P0V8_PEX3        VIA   -    MD0100PA00X+139122Y+116238X0200Y         S0      
317P0V8_PEX3        VIA   -    MD0100PA00X+138872Y+117238X0200Y         S0      
317P0V8_PEX3        VIA   -    MD0100PA00X+138872Y+116988X0200Y         S0      
317P0V8_PEX3        VIA   -    MD0100PA00X+138872Y+116738X0200Y         S0      
317P0V8_PEX3        VIA   -    MD0100PA00X+138872Y+116488X0200Y         S0      
317P0V8_PEX3        VIA   -    MD0100PA00X+138872Y+116238X0200Y         S0      
317P0V8_PEX3        VIA   -    MD0100PA00X+138302Y+116083X0200Y         S0      
327P0V8_PEX3        PEX3  -AG33       A01X+163602Y+115748X0180Y         S1      
327P0V8_PEX3        PEX3  -AF30       A01X+162480Y+116122X0180Y         S1      
327P0V8_PEX3        PEX3  -AG31M      A01X+162854Y+115748X0180Y         S1      
327P0V8_PEX3        PEX3  -AG29M      A01X+162106Y+115748X0180Y         S1      
327P0V8_PEX3        PEX3  -AF28       A01X+161732Y+116122X0180Y         S1      
327P0V8_PEX3        PEX3  -AF26       A01X+160984Y+116122X0180Y         S1      
327P0V8_PEX3        PEX3  -AG27M      A01X+161358Y+115748X0180Y         S1      
327P0V8_PEX3        PEX3  -AG23M      A01X+159862Y+115748X0180Y         S1      
327P0V8_PEX3        PEX3  -AF24       A01X+160236Y+116122X0180Y         S1      
327P0V8_PEX3        PEX3  -AG25       A01X+160610Y+115748X0180Y         S1      
327P0V8_PEX3        PEX3  -AG19M      A01X+158366Y+115748X0180Y         S1      
327P0V8_PEX3        PEX3  -AF20       A01X+158740Y+116122X0180Y         S1      
327P0V8_PEX3        PEX3  -AG21M      A01X+159114Y+115748X0180Y         S1      
327P0V8_PEX3        PEX3  -AF22       A01X+159488Y+116122X0180Y         S1      
327P0V8_PEX3        PEX3  -AG17M      A01X+157618Y+115748X0180Y         S1      
327P0V8_PEX3        PEX3  -AF18       A01X+157992Y+116122X0180Y         S1      
327P0V8_PEX3        PEX3  -AK14M      A01X+156496Y+114626X0180Y         S1      
327P0V8_PEX3        PEX3  -AJ15       A01X+156870Y+115000X0180Y         S1      
327P0V8_PEX3        PEX3  -AH14M      A01X+156496Y+115374X0180Y         S1      
327P0V8_PEX3        PEX3  -AG15M      A01X+156870Y+115748X0180Y         S1      
327P0V8_PEX3        PEX3  -AF16       A01X+157244Y+116122X0180Y         S1      
317P0V8_PEX1_PWM1   VIA   -    M      A01X+046734Y+099648X0200Y    R090 S2      
017P0V8_PEX1_PWM1   VIA   -    M      A18X+046734Y+099648X0260Y    R090 S2      
017P0V8_PEX1_PWM1         -    MD0100PA00X+046734Y+099648                       
327P0V8_PEX1_PWM1   PU6   -1          A01X+046841Y+100785X0070Y0240     S1      
327P0V8_PEX1_PWM1   PU9   -34         A01X+048177Y+111023X0090Y0240R180 S1      
317P0V8_PEX1_PWM1   VIA   -    MD0100PA00X+048258Y+110479X0200Y         S0      
317P0V8_PEX0_PWM2   VIA   -    M      A01X+047786Y+100438X0200Y    R090 S2      
017P0V8_PEX0_PWM2   VIA   -    M      A18X+047786Y+100438X0260Y    R090 S2      
017P0V8_PEX0_PWM2         -    MD0100PA00X+047786Y+100438                       
327P0V8_PEX0_PWM2   PU6   -7          A01X+047786Y+100785X0070Y0240     S1      
317P0V8_PEX0_PWM2   VIA   -    MD0100PA00X+044912Y+110479X0200Y         S0      
327P0V8_PEX0_PWM2   PU8   -34         A01X+044832Y+111023X0090Y0240R180 S1      
327m3328            PR134 -2          A01X+141519Y+100877X0198Y0197R180 S1      
317m3328            VIA   -    M      A01X+141261Y+100877X0200Y         S2      
017m3328            VIA   -    M      A18X+141261Y+100877X0260Y         S2      
017m3328                  -    MD0100PA00X+141261Y+100877                       
327m3328            PU11  -14         A01X+139912Y+101494X0070Y0240R090 S1      
327m3329            PR7134-1          A18X+048412Y+102704X0198Y0197R090 S2      
327m3329            VIA   -    M      A18X+047974Y+103255X0260Y         S2      
317m3329            VIA   -    MD0100PA00X+047364Y+103095X0200Y         S0      
327m3329            PU6   -27         A01X+047313Y+102675X0070Y0240     S1      
327P1V25_PEX2       C3249 -1          A18X+121517Y+116309X0280Y0320R090 S2      
327P1V25_PEX2       C3253 -1          A18X+122034Y+116308X0280Y0320R270 S2      
327P1V25_PEX2       C3272 -1          A18X+117894Y+119383X0120Y0150R270 S2      
327P1V25_PEX2       C3255 -1          A18X+117520Y+119383X0120Y0150R270 S2      
327P1V25_PEX2       C3250 -1          A18X+117146Y+119383X0120Y0150R270 S2      
327P1V25_PEX2       C3267 -1          A18X+116772Y+119383X0120Y0150R270 S2      
327P1V25_PEX2       C3257 -1          A18X+116398Y+119383X0120Y0150R270 S2      
327P1V25_PEX2       C3254 -1          A18X+116024Y+119383X0120Y0150R270 S2      
327P1V25_PEX2       C3256 -1          A18X+115650Y+119383X0120Y0150R270 S2      
327P1V25_PEX2       C3259 -1          A18X+115276Y+119383X0120Y0150R270 S2      
327P1V25_PEX2       C3251 -1          A18X+114902Y+119383X0120Y0150R270 S2      
327P1V25_PEX2       C3280 -1          A18X+114528Y+119383X0120Y0150R270 S2      
327P1V25_PEX2       C3265 -1          A18X+114154Y+119383X0120Y0150R270 S2      
327P1V25_PEX2       C3262 -1          A18X+113780Y+119383X0120Y0150R270 S2      
327P1V25_PEX2       C3266 -1          A18X+113405Y+119383X0120Y0150R270 S2      
327P1V25_PEX2       C3263 -1          A18X+113031Y+119383X0120Y0150R270 S2      
327P1V25_PEX2       C3261 -1          A18X+112657Y+119383X0120Y0150R270 S2      
327P1V25_PEX2       C3260 -1          A18X+112283Y+119383X0120Y0150R270 S2      
327P1V25_PEX2       C3252 -1          A18X+111909Y+119383X0120Y0150R270 S2      
327P1V25_PEX2       C3264 -1          A18X+111535Y+119383X0120Y0150R270 S2      
327P1V25_PEX2       C3271 -1          A18X+111535Y+113609X0120Y0150R090 S2      
327P1V25_PEX2       C3279 -1          A18X+111909Y+113609X0120Y0150R090 S2      
327P1V25_PEX2       C3282 -1          A18X+112283Y+113609X0120Y0150R090 S2      
327P1V25_PEX2       C3281 -1          A18X+112657Y+113609X0120Y0150R090 S2      
327P1V25_PEX2       C3278 -1          A18X+113031Y+113609X0120Y0150R090 S2      
327P1V25_PEX2       C3290 -1          A18X+113405Y+113609X0120Y0150R090 S2      
327P1V25_PEX2       C3291 -1          A18X+113780Y+113609X0120Y0150R090 S2      
327P1V25_PEX2       C3268 -1          A18X+114154Y+113609X0120Y0150R090 S2      
327P1V25_PEX2       C3283 -1          A18X+114528Y+113609X0120Y0150R090 S2      
327P1V25_PEX2       C3289 -1          A18X+114902Y+113609X0120Y0150R090 S2      
327P1V25_PEX2       C3269 -1          A18X+115276Y+113609X0120Y0150R090 S2      
327P1V25_PEX2       C3286 -1          A18X+115650Y+113609X0120Y0150R090 S2      
327P1V25_PEX2       C3287 -1          A18X+116024Y+113609X0120Y0150R090 S2      
327P1V25_PEX2       C3276 -1          A18X+116398Y+113609X0120Y0150R090 S2      
327P1V25_PEX2       C3275 -1          A18X+116772Y+113609X0120Y0150R090 S2      
327P1V25_PEX2       C3273 -1          A18X+117146Y+113609X0120Y0150R090 S2      
327P1V25_PEX2       C3270 -1          A18X+117520Y+113609X0120Y0150R090 S2      
327P1V25_PEX2       C3284 -1          A18X+117894Y+113609X0120Y0150R090 S2      
327P1V25_PEX2       C3288 -1          A18X+119285Y+115561X0120Y0150R180 S2      
327P1V25_PEX2       C3274 -1          A18X+119285Y+115935X0120Y0150R180 S2      
327P1V25_PEX2       C3285 -1          A18X+119285Y+116683X0120Y0150R180 S2      
327P1V25_PEX2       C3258 -1          A18X+119285Y+117057X0120Y0150R180 S2      
327P1V25_PEX2       C3277 -1          A18X+119285Y+117431X0120Y0150R180 S2      
317P1V25_PEX2       VIA   -    MD0080PA00X+112096Y+113691X0160Y         S0      
317P1V25_PEX2       VIA   -    MD0080PA00X+111722Y+113691X0160Y         S0      
317P1V25_PEX2       VIA   -    MD0080PA00X+111348Y+113691X0160Y         S0      
317P1V25_PEX2       VIA   -    MD0080PA00X+112470Y+113691X0160Y         S0      
317P1V25_PEX2       VIA   -    MD0080PA00X+112470Y+119301X0160Y         S0      
317P1V25_PEX2       VIA   -    MD0080PA00X+111348Y+119301X0160Y         S0      
317P1V25_PEX2       VIA   -    MD0080PA00X+111722Y+119301X0160Y         S0      
317P1V25_PEX2       VIA   -    MD0080PA00X+112096Y+119301X0160Y         S0      
317P1V25_PEX2       VIA   -    MD0080PA00X+112844Y+113691X0160Y         S0      
317P1V25_PEX2       VIA   -    MD0080PA00X+113218Y+113691X0160Y         S0      
317P1V25_PEX2       VIA   -    MD0080PA00X+113592Y+113691X0160Y         S0      
317P1V25_PEX2       VIA   -    MD0080PA00X+113966Y+113691X0160Y         S0      
317P1V25_PEX2       VIA   -    MD0080PA00X+113966Y+119301X0160Y         S0      
317P1V25_PEX2       VIA   -    MD0080PA00X+113592Y+119301X0160Y         S0      
317P1V25_PEX2       VIA   -    MD0080PA00X+113218Y+119301X0160Y         S0      
317P1V25_PEX2       VIA   -    MD0080PA00X+112844Y+119301X0160Y         S0      
317P1V25_PEX2       VIA   -    MD0080PA00X+115088Y+113691X0160Y         S0      
317P1V25_PEX2       VIA   -    MD0080PA00X+115462Y+113691X0160Y         S0      
317P1V25_PEX2       VIA   -    MD0080PA00X+114340Y+113691X0160Y         S0      
317P1V25_PEX2       VIA   -    MD0080PA00X+114340Y+119301X0160Y         S0      
317P1V25_PEX2       VIA   -    MD0080PA00X+115462Y+119301X0160Y         S0      
317P1V25_PEX2       VIA   -    MD0080PA00X+115088Y+119301X0160Y         S0      
317P1V25_PEX2       VIA   -    MD0080PA00X+116211Y+113691X0160Y         S0      
317P1V25_PEX2       VIA   -    MD0080PA00X+115836Y+113691X0160Y         S0      
317P1V25_PEX2       VIA   -    MD0080PA00X+116585Y+113691X0160Y         S0      
317P1V25_PEX2       VIA   -    MD0080PA00X+116959Y+113691X0160Y         S0      
317P1V25_PEX2       VIA   -    MD0080PA00X+117333Y+113691X0160Y         S0      
317P1V25_PEX2       VIA   -    MD0080PA00X+117333Y+119301X0160Y         S0      
317P1V25_PEX2       VIA   -    MD0080PA00X+116211Y+119301X0160Y         S0      
317P1V25_PEX2       VIA   -    MD0080PA00X+115836Y+119301X0160Y         S0      
317P1V25_PEX2       VIA   -    MD0080PA00X+116959Y+119301X0160Y         S0      
317P1V25_PEX2       VIA   -    MD0080PA00X+116585Y+119301X0160Y         S0      
317P1V25_PEX2       VIA   -    MD0080PA00X+117707Y+113691X0160Y         S0      
317P1V25_PEX2       VIA   -    MD0080PA00X+118081Y+113691X0160Y         S0      
317P1V25_PEX2       VIA   -    MD0080PA00X+118081Y+119301X0160Y         S0      
317P1V25_PEX2       VIA   -    MD0080PA00X+117707Y+119301X0160Y         S0      
317P1V25_PEX2       VIA   -    MD0080PA00X+119203Y+115935X0160Y         S0      
317P1V25_PEX2       VIA   -    MD0080PA00X+119203Y+115561X0160Y         S0      
317P1V25_PEX2       VIA   -    MD0080PA00X+119203Y+117431X0160Y         S0      
317P1V25_PEX2       VIA   -    MD0080PA00X+119203Y+117057X0160Y         S0      
317P1V25_PEX2       VIA   -    MD0080PA00X+119203Y+116683X0160Y         S0      
317P1V25_PEX2       VIA   -    MD0080PA00X+122195Y+116683X0160Y    R180 S0      
317P1V25_PEX2       VIA   -    MD0080PA00X+121821Y+115935X0160Y    R090 S0      
317P1V25_PEX2       VIA   -    MD0080PA00X+121821Y+116683X0160Y    R180 S0      
327P1V25_PEX2       C4348 -1          A18X+095142Y+109596X0120Y0150R270 S2      
327P1V25_PEX2       C4335 -1          A01X+092140Y+108083X0120Y0150R180 S1      
327P1V25_PEX2       C4334 -1          A01X+092138Y+108872X0120Y0150R180 S1      
327P1V25_PEX2       C4349 -1          A18X+092321Y+109002X0120Y0150     S2      
327P1V25_PEX2       C4345 -1          A18X+092511Y+109511X0280Y0320     S2      
327P1V25_PEX2       C4344 -1          A18X+093543Y+109512X0280Y0320     S2      
327P1V25_PEX2       C4330 -1          A18X+094589Y+109502X0280Y0320     S2      
327P1V25_PEX2       C4332 -1          A18X+094070Y+109502X0280Y0320     S2      
327P1V25_PEX2       C4346 -1          A18X+093017Y+109513X0280Y0320     S2      
327P1V25_PEX2       C4331 -1          A18X+092710Y+108517X0280Y0320R090 S2      
327P1V25_PEX2       C4347 -1          A18X+092699Y+107982X0280Y0320R090 S2      
327P1V25_PEX2       C4333 -1          A18X+092701Y+107437X0280Y0320R090 S2      
317P1V25_PEX2       VIA   -    MD0100PA00X+097861Y+121484X0200Y         S0      
327P1V25_PEX2       PJ13  -2          A01X+097620Y+121484X0180Y0200R180 S1      
327P1V25_PEX2       PEX2  -V16 M      A01X+111535Y+119114X0180Y         S1      
327P1V25_PEX2       PEX2  -V17 M      A01X+111909Y+119114X0180Y         S1      
327P1V25_PEX2       PEX2  -V18 M      A01X+112283Y+119114X0180Y         S1      
327P1V25_PEX2       PEX2  -V23 M      A01X+114154Y+119114X0180Y         S1      
327P1V25_PEX2       PEX2  -V24        A01X+114528Y+119114X0180Y         S1      
327P1V25_PEX2       PEX2  -V22 M      A01X+113780Y+119114X0180Y         S1      
327P1V25_PEX2       PEX2  -V21 M      A01X+113405Y+119114X0180Y         S1      
327P1V25_PEX2       PEX2  -V19 M      A01X+112657Y+119114X0180Y         S1      
327P1V25_PEX2       PEX2  -V20 M      A01X+113031Y+119114X0180Y         S1      
327P1V25_PEX2       PEX2  -V25        A01X+114902Y+119114X0180Y         S1      
327P1V25_PEX2       PEX2  -V26 M      A01X+115276Y+119114X0180Y         S1      
327P1V25_PEX2       PEX2  -V31        A01X+117146Y+119114X0180Y         S1      
327P1V25_PEX2       PEX2  -V28        A01X+116024Y+119114X0180Y         S1      
327P1V25_PEX2       PEX2  -V27        A01X+115650Y+119114X0180Y         S1      
327P1V25_PEX2       PEX2  -V30        A01X+116772Y+119114X0180Y         S1      
327P1V25_PEX2       PEX2  -V29        A01X+116398Y+119114X0180Y         S1      
327P1V25_PEX2       PEX2  -V33        A01X+117894Y+119114X0180Y         S1      
327P1V25_PEX2       PEX2  -V32        A01X+117520Y+119114X0180Y         S1      
327P1V25_PEX2       PEX2  -AD36M      A01X+119016Y+116870X0180Y         S1      
327P1V25_PEX2       PEX2  -AC36M      A01X+119016Y+117244X0180Y         S1      
327P1V25_PEX2       PEX2  -AE36       A01X+119016Y+116496X0180Y         S1      
327P1V25_PEX2       PEX2  -AG36       A01X+119016Y+115748X0180Y         S1      
327P1V25_PEX2       PEX2  -AF36       A01X+119016Y+116122X0180Y         S1      
327P1V25_PEX2       VIA   -           A18X+119164Y+116311X0260Y         S2      
317P1V25_PEX2       VIA   -    MD0100PA00X+094676Y+107410X0200Y    R090 S0      
317P1V25_PEX2       VIA   -    MD0100PA00X+094676Y+107160X0200Y    R090 S0      
317P1V25_PEX2       VIA   -    MD0100PA00X+095196Y+107410X0200Y    R090 S0      
317P1V25_PEX2       VIA   -    MD0100PA00X+094936Y+107410X0200Y    R090 S0      
317P1V25_PEX2       VIA   -    MD0100PA00X+095456Y+107410X0200Y    R090 S0      
317P1V25_PEX2       VIA   -    MD0100PA00X+095456Y+107160X0200Y    R090 S0      
317P1V25_PEX2       VIA   -    MD0100PA00X+094936Y+107160X0200Y    R090 S0      
317P1V25_PEX2       VIA   -    MD0100PA00X+095196Y+107160X0200Y    R090 S0      
317P1V25_PEX2       VIA   -    MD0100PA00X+094659Y+108467X0200Y         S0      
317P1V25_PEX2       VIA   -    MD0100PA00X+093749Y+107168X0200Y    R090 S0      
317P1V25_PEX2       VIA   -    MD0100PA00X+093489Y+107168X0200Y    R090 S0      
317P1V25_PEX2       VIA   -    MD0100PA00X+094009Y+107168X0200Y    R090 S0      
317P1V25_PEX2       VIA   -    MD0100PA00X+094009Y+107418X0200Y    R090 S0      
317P1V25_PEX2       VIA   -    MD0100PA00X+093489Y+107418X0200Y    R090 S0      
317P1V25_PEX2       VIA   -    MD0100PA00X+093749Y+107418X0200Y    R090 S0      
317P1V25_PEX2       VIA   -    MD0100PA00X+093229Y+107168X0200Y    R090 S0      
317P1V25_PEX2       VIA   -    MD0100PA00X+093229Y+107418X0200Y    R090 S0      
317P1V25_PEX2       VIA   -    MD0100PA00X+093683Y+108891X0200Y    R090 S0      
317P1V25_PEX2       VIA   -    MD0100PA00X+093423Y+108891X0200Y    R090 S0      
317P1V25_PEX2       VIA   -    MD0100PA00X+093943Y+108891X0200Y    R090 S0      
317P1V25_PEX2       VIA   -    MD0100PA00X+093943Y+109141X0200Y    R090 S0      
317P1V25_PEX2       VIA   -    MD0100PA00X+093423Y+109141X0200Y    R090 S0      
317P1V25_PEX2       VIA   -    MD0100PA00X+093683Y+109141X0200Y    R090 S0      
317P1V25_PEX2       VIA   -    MD0100PA00X+093163Y+108891X0200Y    R090 S0      
317P1V25_PEX2       VIA   -    MD0100PA00X+093163Y+109141X0200Y    R090 S0      
317P1V25_PEX2       VIA   -    MD0100PA00X+094409Y+108467X0200Y         S0      
327P1V25_PEX2       R6134 -1B  M      A18X+093703Y+105068X0100Y0200     S2      
327P1V25_PEX2       R6134 -1A  M      A18X+093948Y+105068X0590Y0790     S2      
327P1V25_PEX2       L117  -1   M      A18X+093898Y+105068X0460Y3860     S2      
327P1V25_PEX2       R6135 -1B  M      A18X+095027Y+105068X0100Y0200R180 S2      
327P1V25_PEX2       R6135 -1A  M      A18X+094782Y+105068X0590Y0790R180 S2      
327P1V25_PEX2       L115  -1   M      A18X+094832Y+105037X0460Y3860R180 S2      
327P1V25_PEX2       VIA   -           A18X+093388Y+107908X0260Y         S2      
327P1V25_PEX2       VIA   -           A18X+094863Y+107891X0260Y         S2      
327P1V25_PEX2       R6137 -1B  M      A01X+093703Y+105068X0100Y0200R180 S1      
327P1V25_PEX2       R6137 -1A  M      A01X+093948Y+105068X0590Y0790R180 S1      
327P1V25_PEX2       L116  -1   M      A01X+093898Y+105068X0460Y3860R180 S1      
327P1V25_PEX2       R6136 -1B  M      A01X+095027Y+105068X0100Y0200     S1      
327P1V25_PEX2       R6136 -1A  M      A01X+094782Y+105068X0590Y0790     S1      
327P1V25_PEX2       L114  -1   M      A01X+094832Y+105037X0460Y3860     S1      
327P1V25_PEX2       R792  -1          A01X+093538Y+108161X1150Y1380R090 S1      
327P1V25_PEX2       R800  -1          A01X+094582Y+108738X0198Y0197     S1      
327P1V25_PEX2       PEX2  -AM26M      A01X+115276Y+113878X0180Y         S1      
327P1V25_PEX2       PEX2  -AM25       A01X+114902Y+113878X0180Y         S1      
327P1V25_PEX2       PEX2  -AM29M      A01X+116398Y+113878X0180Y         S1      
327P1V25_PEX2       PEX2  -AM28M      A01X+116024Y+113878X0180Y         S1      
327P1V25_PEX2       PEX2  -AM30M      A01X+116772Y+113878X0180Y         S1      
327P1V25_PEX2       PEX2  -AM31M      A01X+117146Y+113878X0180Y         S1      
327P1V25_PEX2       PEX2  -AM33M      A01X+117894Y+113878X0180Y         S1      
327P1V25_PEX2       PEX2  -AM32M      A01X+117520Y+113878X0180Y         S1      
327P1V25_PEX2       PEX2  -AM27M      A01X+115650Y+113878X0180Y         S1      
327P1V25_PEX2       PEX2  -AM18M      A01X+112283Y+113878X0180Y         S1      
327P1V25_PEX2       PEX2  -AM24       A01X+114528Y+113878X0180Y         S1      
327P1V25_PEX2       PEX2  -AM23M      A01X+114154Y+113878X0180Y         S1      
327P1V25_PEX2       PEX2  -AM19M      A01X+112657Y+113878X0180Y         S1      
327P1V25_PEX2       PEX2  -AM22M      A01X+113780Y+113878X0180Y         S1      
327P1V25_PEX2       PEX2  -AM20M      A01X+113031Y+113878X0180Y         S1      
327P1V25_PEX2       PEX2  -AM21M      A01X+113405Y+113878X0180Y         S1      
327P1V25_PEX2       PEX2  -AM17M      A01X+111909Y+113878X0180Y         S1      
327P1V25_PEX2       PEX2  -AM16M      A01X+111535Y+113878X0180Y         S1      
317m3330            VIA   -    MD0100PA00X+045712Y+110690X0200Y    R090 S0      
327m3330            PU8   -38         A01X+045540Y+111023X0090Y0240R180 S1      
327m3330            PU6   -24         A01X+047786Y+102675X0070Y0240     S1      
317m3330            VIA   -    M      A01X+047559Y+104306X0200Y    R090 S2      
017m3330            VIA   -    M      A18X+047559Y+104306X0260Y    R090 S2      
017m3330                  -    MD0100PA00X+047559Y+104306                       
327m3331            PU19  -9          A01X+179740Y+122202X0120Y0320R270 S1      
317m3331            VIA   -    M      A01X+180513Y+122574X0200Y         S2      
017m3331            VIA   -    M      A18X+180513Y+122574X0260Y         S2      
017m3331                  -    MD0100PA00X+180513Y+122574                       
327m3331            R4438 -2          A18X+181783Y+120941X0198Y0197R090 S2      
327m3331            R847  -2   M      A18X+181777Y+120548X0198Y0197R270 S2      
327P1V8_VDDA_PEX2   C3360 -1          A18X+110764Y+119301X0120Y0150R180 S2      
327P1V8_VDDA_PEX2   C3343 -1   M      A18X+110436Y+119301X0120Y0150     S2      
327P1V8_VDDA_PEX2   C3336 -1          A18X+110534Y+118909X0280Y0320R090 S2      
327P1V8_VDDA_PEX2   VIA   -           A18X+109665Y+119492X0260Y         S2      
327P1V8_VDDA_PEX2   VIA   -           A18X+108316Y+117009X0260Y         S2      
327P1V8_VDDA_PEX2   C3357 -1          A18X+110682Y+113691X0120Y0150R180 S2      
327P1V8_VDDA_PEX2   VIA   -           A18X+120031Y+112810X0260Y         S2      
327P1V8_VDDA_PEX2   C3345 -1          A18X+118665Y+113317X0120Y0150     S2      
327P1V8_VDDA_PEX2   C3344 -1          A18X+118665Y+112943X0120Y0150     S2      
327P1V8_VDDA_PEX2   C3337 -1          A18X+119413Y+118179X0120Y0150     S2      
327P1V8_VDDA_PEX2   C3361 -1          A18X+119741Y+118179X0120Y0150R180 S2      
327P1V8_VDDA_PEX2   C3362 -1          A18X+118537Y+118179X0120Y0150R180 S2      
327P1V8_VDDA_PEX2   C3359 -1          A18X+118829Y+119885X0120Y0150R090 S2      
327P1V8_VDDA_PEX2   C3346 -1          A18X+118829Y+120213X0120Y0150R270 S2      
327P1V8_VDDA_PEX2   C3358 -1          A18X+109022Y+117431X0120Y0150     S2      
327P1V8_VDDA_PEX2   C3355 -1          A18X+109022Y+117805X0120Y0150     S2      
327P1V8_VDDA_PEX2   C3356 -1          A18X+109022Y+118179X0120Y0150     S2      
317P1V8_VDDA_PEX2   VIA   -    MD0080PA00X+109104Y+117431X0160Y         S0      
317P1V8_VDDA_PEX2   VIA   -    MD0080PA00X+109104Y+117805X0160Y         S0      
317P1V8_VDDA_PEX2   VIA   -    MD0080PA00X+109104Y+118179X0160Y         S0      
317P1V8_VDDA_PEX2   VIA   -    MD0080PA00X+110600Y+113691X0160Y         S0      
317P1V8_VDDA_PEX2   VIA   -    MD0080PA00X+110600Y+119301X0160Y    R270 S0      
317P1V8_VDDA_PEX2   VIA   -    MD0080PA00X+118829Y+112943X0160Y         S0      
317P1V8_VDDA_PEX2   VIA   -    MD0080PA00X+118829Y+120049X0160Y    R180 S0      
317P1V8_VDDA_PEX2   VIA   -    MD0080PA00X+118455Y+118179X0160Y         S0      
317P1V8_VDDA_PEX2   VIA   -    MD0080PA00X+119577Y+118179X0160Y         S0      
327P1V8_VDDA_PEX2   C3418 -1          A01X+101684Y+102766X0280Y0320R090 S1      
327P1V8_VDDA_PEX2   L129  -2          A01X+101813Y+102178X0440Y0540R270 S1      
327P1V8_VDDA_PEX2   R4587 -1          A01X+102186Y+102693X0198Y0197     S1      
327P1V8_VDDA_PEX2   C3420 -1          A01X+101717Y+103299X0120Y0150R090 S1      
317P1V8_VDDA_PEX2   VIA   -     D0100PA00X+101614Y+103067X0200Y    R090 S0      
317P1V8_VDDA_PEX2   VIA   -     D0100PA00X+101914Y+103067X0200Y    R090 S0      
317P1V8_VDDA_PEX2   VIA   -    MD0100PA00X+102214Y+103067X0200Y    R090 S0      
327P1V8_VDDA_PEX2   C3419 -1          A01X+101252Y+103299X0120Y0150R090 S1      
317P1V8_VDDA_PEX2   VIA   -    MD0100PA00X+107465Y+107001X0200Y         S0      
327P1V8_VDDA_PEX2   PEX2  -T35        A01X+118642Y+119862X0180Y         S1      
327P1V8_VDDA_PEX2   PEX2  -V14        A01X+110787Y+119114X0180Y         S1      
327P1V8_VDDA_PEX2   PEX2  -AA37       A01X+119390Y+117992X0180Y         S1      
327P1V8_VDDA_PEX2   PEX2  -AA34       A01X+118268Y+117992X0180Y         S1      
327P1V8_VDDA_PEX2   PEX2  -AM14       A01X+110787Y+113878X0180Y         S1      
327P1V8_VDDA_PEX2   PEX2  -AP35       A01X+118642Y+113130X0180Y         S1      
327P1V8_VDDA_PEX2   PEX2  -AC10       A01X+109291Y+117244X0180Y         S1      
327P1V8_VDDA_PEX2   PEX2  -AA10M      A01X+109291Y+117992X0180Y         S1      
327P1V8_VDDA_PEX2   PEX2  -AB10M      A01X+109291Y+117618X0180Y         S1      
327m3332            VIA   -           A01X+134957Y+110279X0300Y         S1      
317m3332            VIA   -    MD0100PA00X+132302Y+109396X0200Y         S0      
317m3332            VIA   -    MD0100PA00X+132302Y+109096X0200Y         S0      
317m3332            VIA   -    MD0100PA00X+132316Y+108250X0200Y         S0      
317m3332            VIA   -    MD0100PA00X+132319Y+108770X0200Y         S0      
317m3332            VIA   -    MD0100PA00X+132319Y+108520X0200Y         S0      
317m3332            VIA   -    MD0100PA00X+132919Y+108820X0200Y         S2      
317m3332            VIA   -    MD0100PA00X+132647Y+109123X0200Y         S0      
317m3332            VIA   -    MD0100PA00X+132619Y+108820X0200Y         S0      
317m3332            VIA   -    MD0100PA00X+132919Y+108520X0200Y         S0      
317m3332            VIA   -    MD0100PA00X+132916Y+108250X0200Y         S0      
317m3332            VIA   -    MD0100PA00X+132619Y+108520X0200Y         S0      
317m3332            VIA   -    MD0100PA00X+132616Y+108250X0200Y         S0      
327m3332            PC6618-1          A18X+131936Y+108588X0400Y0500R180 S2      
327m3332            PC6615-1          A18X+135392Y+109309X0400Y0500     S2      
327m3332            PC6616-1          A18X+131936Y+109307X0400Y0500R180 S2      
327m3332            PC6617-1          A01X+131936Y+108588X0400Y0500     S1      
327m3332            PL11  -1          A01X+132514Y+107868X0420Y0990R270 S1      
327m3332            PC144 -1          A01X+135242Y+108033X0630Y1380R180 S1      
327m3332            PC160 -1          A18X+135740Y+110990X0400Y0500R270 S2      
327m3332            PC143 -1          A18X+135953Y+111775X0400Y0500R090 S2      
327m3332            PC161 -1          A18X+135153Y+111775X0400Y0500R090 S2      
327m3332            PC141 -1          A18X+132527Y+110990X0400Y0500R270 S2      
327m3332            PC159 -1          A18X+132740Y+111775X0400Y0500R090 S2      
327m3332            PC140 -1          A18X+131940Y+111775X0400Y0500R090 S2      
327m3332            PU13  -30         A01X+135540Y+111023X0090Y0240R180 S1      
317m3332            VIA   -    MD0100PA00X+135838Y+111365X0200Y         S0      
317m3332            VIA   -    MD0100PA00X+136088Y+111365X0200Y         S0      
317m3332            VIA   -    MD0100PA00X+135553Y+111880X0200Y         S0      
317m3332            VIA   -    MD0100PA00X+135553Y+111610X0200Y         S0      
317m3332            VIA   -    MD0100PA00X+135408Y+111365X0200Y         S0      
327m3332            PU13  -25_2M      A01X+135741Y+111661X0810Y0910R090 S1      
317m3332            VIA   -    MD0100PA00X+135330Y+111060X0200Y         S0      
327m3332            PC157 -1          A01X+134946Y+111982X0198Y0197R090 S1      
317m3332            VIA   -    MD0100PA00X+135110Y+110940X0200Y         S0      
317m3332            VIA   -    MD0100PA00X+135120Y+111240X0200Y         S0      
317m3332            VIA   -    MD0100PA00X+134900Y+111090X0200Y         S0      
317m3332            VIA   -    MD0100PA00X+134900Y+111380X0200Y         S0      
327m3332            PU12  -30         A01X+132328Y+111023X0090Y0240R180 S1      
317m3332            VIA   -    MD0100PA00X+132340Y+111610X0200Y         S0      
317m3332            VIA   -    MD0100PA00X+132340Y+111880X0200Y         S0      
317m3332            VIA   -    MD0100PA00X+132875Y+111365X0200Y         S0      
317m3332            VIA   -    MD0100PA00X+132625Y+111365X0200Y         S0      
317m3332            VIA   -    MD0100PA00X+132195Y+111365X0200Y         S0      
327m3332            PU12  -25_2M      A01X+132528Y+111661X0810Y0910R090 S1      
317m3332            VIA   -    MD0100PA00X+132117Y+111060X0200Y         S0      
327m3332            PC139 -1          A01X+131733Y+111982X0198Y0197R090 S1      
317m3332            VIA   -    MD0100PA00X+131687Y+111090X0200Y         S0      
317m3332            VIA   -    MD0100PA00X+131687Y+111380X0200Y         S0      
317m3332            VIA   -    MD0100PA00X+131897Y+110940X0200Y         S0      
317m3332            VIA   -    MD0100PA00X+131907Y+111240X0200Y         S0      
327m3332            PC156 -1          A01X+135542Y+109883X0198Y0197     S1      
317m3332            VIA   -    MD0100PA00X+135320Y+110800X0200Y         S0      
317m3332            VIA   -    MD0100PA00X+135042Y+109309X0200Y         S0      
317m3332            VIA   -    MD0100PA00X+134900Y+110800X0200Y         S0      
327m3332            PC138 -1          A01X+132329Y+109883X0198Y0197     S1      
317m3332            VIA   -    MD0100PA00X+132107Y+110800X0200Y         S0      
317m3332            VIA   -    MD0100PA00X+131687Y+110800X0200Y         S0      
327m3332            PC142 -1          A01X+135392Y+109309X0400Y0500R180 S1      
317m3332            VIA   -    MD0100PA00X+134755Y+108182X0200Y         S0      
317m3332            VIA   -    MD0100PA00X+135042Y+109029X0200Y         S0      
317m3332            VIA   -    MD0100PA00X+134755Y+108432X0200Y         S0      
317m3332            VIA   -    MD0100PA00X+134755Y+108682X0200Y         S0      
317m3332            VIA   -    MD0100PA00X+134505Y+108682X0200Y         S0      
317m3332            VIA   -    MD0100PA00X+134505Y+108432X0200Y         S0      
317m3332            VIA   -    MD0100PA00X+134505Y+108182X0200Y         S0      
317m3332            VIA   -    MD0100PA00X+134755Y+108932X0200Y         S0      
317m3332            VIA   -    MD0100PA00X+134755Y+109182X0200Y         S0      
327m3332            PC158 -1          A01X+131936Y+109307X0400Y0500     S1      
327m3333            PU19  -10         A01X+179307Y+122044X0120Y0790R180 S1      
327m3333            PU19  -21         A01X+179307Y+121020X0120Y0790R180 S1      
327m3333            PC1010-1          A01X+179140Y+125078X0400Y0500     S1      
327m3333            PL23  -2          A01X+179907Y+125211X0280Y0320R180 S1      
327m3333            PC266 -1          A01X+179940Y+124528X0400Y0500R180 S1      
327m3333            PC263 -1          A01X+179140Y+124388X0400Y0500     S1      
327m3333            PC265 -1          A01X+179940Y+123148X0400Y0500R180 S1      
327m3333            PC267 -1          A01X+179940Y+123838X0400Y0500R180 S1      
327m3333            PC269 -1          A01X+179140Y+123698X0400Y0500     S1      
327m3333            PC268 -1          A01X+179140Y+123008X0400Y0500     S1      
327m3333            PC270 -1          A01X+179346Y+120276X0198Y0197     S1      
327m3334            C3294 -1          A18X+111348Y+112861X0120Y0150R090 S2      
327m3334            C3320 -1          A18X+111722Y+112861X0120Y0150R090 S2      
327m3334            C3331 -1          A18X+112096Y+112861X0120Y0150R090 S2      
327m3334            C3318 -1          A18X+111327Y+120131X0120Y0150R270 S2      
327m3334            C3326 -1          A18X+111701Y+120131X0120Y0150R270 S2      
327m3334            C3333 -1          A18X+112075Y+120131X0120Y0150R270 S2      
327m3334            C3325 -1          A18X+112449Y+120131X0120Y0150R270 S2      
327m3334            C3334 -1          A18X+112470Y+112861X0120Y0150R090 S2      
327m3334            C3332 -1          A18X+112844Y+112861X0120Y0150R090 S2      
327m3334            C3308 -1          A18X+113218Y+112861X0120Y0150R090 S2      
327m3334            C3309 -1          A18X+113592Y+112861X0120Y0150R090 S2      
327m3334            C3300 -1          A18X+113966Y+112861X0120Y0150R090 S2      
327m3334            C3319 -1          A18X+112823Y+120131X0120Y0150R270 S2      
327m3334            C3310 -1          A18X+113197Y+120131X0120Y0150R270 S2      
327m3334            C3311 -1          A18X+113571Y+120131X0120Y0150R270 S2      
327m3334            C3329 -1          A18X+113945Y+120131X0120Y0150R270 S2      
327m3334            C3292 -1          A18X+114712Y+112961X0280Y0320R180 S2      
327m3334            C3307 -1          A18X+114340Y+112861X0120Y0150R090 S2      
327m3334            C3303 -1          A18X+115088Y+112861X0120Y0150R090 S2      
327m3334            C3304 -1          A18X+115462Y+112861X0120Y0150R090 S2      
327m3334            C3330 -1          A18X+114319Y+120131X0120Y0150R270 S2      
327m3334            C3293 -1          A18X+114709Y+120008X0280Y0320     S2      
327m3334            C3315 -1          A18X+115099Y+120131X0120Y0150R270 S2      
327m3334            C3322 -1          A18X+115473Y+120131X0120Y0150R270 S2      
327m3334            C3306 -1          A18X+115836Y+112861X0120Y0150R090 S2      
327m3334            C3327 -1          A18X+116211Y+112861X0120Y0150R090 S2      
327m3334            C3312 -1          A18X+116585Y+112861X0120Y0150R090 S2      
327m3334            C3328 -1          A18X+116959Y+112861X0120Y0150R090 S2      
327m3334            C3314 -1          A18X+115847Y+120131X0120Y0150R270 S2      
327m3334            C3321 -1          A18X+116221Y+120131X0120Y0150R270 S2      
327m3334            C3301 -1          A18X+116595Y+120131X0120Y0150R270 S2      
327m3334            C3302 -1          A18X+116969Y+120131X0120Y0150R270 S2      
327m3334            C3324 -1          A18X+117333Y+112861X0120Y0150R090 S2      
327m3334            C3313 -1          A18X+117707Y+112861X0120Y0150R090 S2      
327m3334            C3299 -1          A18X+118081Y+112861X0120Y0150R090 S2      
327m3334            C3305 -1          A18X+117343Y+120131X0120Y0150R270 S2      
327m3334            C3317 -1          A18X+117717Y+120131X0120Y0150R270 S2      
327m3334            C3323 -1          A18X+118091Y+120131X0120Y0150R270 S2      
327m3334            C3298 -1          A18X+120033Y+115748X0120Y0150R180 S2      
327m3334            C3297 -1          A18X+120033Y+116122X0120Y0150R180 S2      
327m3334            C3316 -1          A18X+120033Y+116496X0120Y0150R180 S2      
327m3334            C3296 -1          A18X+120033Y+116870X0120Y0150R180 S2      
327m3334            C3295 -1          A18X+120033Y+117244X0120Y0150R180 S2      
317m3334            VIA   -    MD0080PA00X+112470Y+112943X0160Y         S0      
317m3334            VIA   -    MD0080PA00X+111722Y+112943X0160Y         S0      
317m3334            VIA   -    MD0080PA00X+111348Y+112943X0160Y         S0      
317m3334            VIA   -    MD0080PA00X+112096Y+112943X0160Y         S0      
317m3334            VIA   -    MD0080PA00X+112470Y+120049X0160Y         S0      
317m3334            VIA   -    MD0080PA00X+111348Y+120049X0160Y         S0      
317m3334            VIA   -    MD0080PA00X+112096Y+120049X0160Y         S0      
317m3334            VIA   -    MD0080PA00X+111722Y+120049X0160Y         S0      
317m3334            VIA   -    MD0080PA00X+113966Y+112943X0160Y         S0      
317m3334            VIA   -    MD0080PA00X+113592Y+112943X0160Y         S0      
317m3334            VIA   -    MD0080PA00X+112844Y+112943X0160Y         S0      
317m3334            VIA   -    MD0080PA00X+113218Y+112943X0160Y         S0      
317m3334            VIA   -    MD0080PA00X+113966Y+120049X0160Y         S0      
317m3334            VIA   -    MD0080PA00X+113592Y+120049X0160Y         S0      
317m3334            VIA   -    MD0080PA00X+112844Y+120049X0160Y         S0      
317m3334            VIA   -    MD0080PA00X+113218Y+120049X0160Y         S0      
317m3334            VIA   -    MD0080PA00X+114340Y+112943X0160Y         S0      
317m3334            VIA   -    MD0080PA00X+115088Y+112943X0160Y         S0      
317m3334            VIA   -    MD0080PA00X+115462Y+112943X0160Y         S0      
317m3334            VIA   -    MD0080PA00X+115088Y+120049X0160Y         S0      
317m3334            VIA   -    MD0080PA00X+115462Y+120049X0160Y         S0      
317m3334            VIA   -    MD0080PA00X+114340Y+120049X0160Y         S0      
317m3334            VIA   -    MD0080PA00X+117333Y+112943X0160Y         S0      
317m3334            VIA   -    MD0080PA00X+115836Y+112943X0160Y         S0      
317m3334            VIA   -    MD0080PA00X+116211Y+112943X0160Y         S0      
317m3334            VIA   -    MD0080PA00X+116585Y+112943X0160Y         S0      
317m3334            VIA   -    MD0080PA00X+116959Y+112943X0160Y         S0      
317m3334            VIA   -    MD0080PA00X+116959Y+120049X0160Y         S0      
317m3334            VIA   -    MD0080PA00X+115836Y+120049X0160Y         S0      
317m3334            VIA   -    MD0080PA00X+116211Y+120049X0160Y         S0      
317m3334            VIA   -    MD0080PA00X+116585Y+120049X0160Y         S0      
317m3334            VIA   -    MD0080PA00X+117333Y+120049X0160Y         S0      
317m3334            VIA   -    MD0080PA00X+117707Y+112943X0160Y         S0      
317m3334            VIA   -    MD0080PA00X+118081Y+112943X0160Y         S0      
317m3334            VIA   -    MD0080PA00X+117707Y+120049X0160Y         S0      
317m3334            VIA   -    MD0080PA00X+118081Y+120049X0160Y         S0      
317m3334            VIA   -    MD0080PA00X+119951Y+115935X0160Y         S0      
317m3334            VIA   -    MD0080PA00X+119951Y+116683X0160Y         S0      
317m3334            VIA   -    MD0080PA00X+119951Y+117057X0160Y         S0      
317m3334            VIA   -    MD0080PA00X+119951Y+115561X0160Y         S0      
317m3334            VIA   -    MD0080PA00X+119951Y+117431X0160Y         S0      
327m3334            R6135 -2B  M      A18X+095876Y+105068X0100Y0200R180 S2      
327m3334            R6135 -2A  M      A18X+096121Y+105068X0590Y0790R180 S2      
327m3334            L115  -2   M      A18X+096072Y+105037X0460Y3860R180 S2      
327m3334            R6134 -2B  M      A18X+092854Y+105068X0100Y0200     S2      
327m3334            R6134 -2A  M      A18X+092609Y+105068X0590Y0790     S2      
327m3334            L117  -2   M      A18X+092658Y+105068X0460Y3860     S2      
327m3334            C4351 -1          A18X+091206Y+101175X0120Y0150     S2      
327m3334            C4350 -1          A18X+091211Y+100854X0120Y0150     S2      
327m3334            PEX2  -AG38       A01X+119764Y+115748X0180Y         S1      
327m3334            PEX2  -AD38       A01X+119764Y+116870X0180Y         S1      
327m3334            PEX2  -AE38       A01X+119764Y+116496X0180Y         S1      
327m3334            PEX2  -AF38       A01X+119764Y+116122X0180Y         S1      
327m3334            PEX2  -AC38       A01X+119764Y+117244X0180Y         S1      
327m3334            PEX2  -AP32       A01X+117520Y+113130X0180Y         S1      
327m3334            PEX2  -AP33       A01X+117894Y+113130X0180Y         S1      
327m3334            PEX2  -AP31       A01X+117146Y+113130X0180Y         S1      
327m3334            PEX2  -AP27       A01X+115650Y+113130X0180Y         S1      
327m3334            PEX2  -AP28       A01X+116024Y+113130X0180Y         S1      
327m3334            PEX2  -AP29       A01X+116398Y+113130X0180Y         S1      
327m3334            PEX2  -AP30       A01X+116772Y+113130X0180Y         S1      
327m3334            PEX2  -AP24       A01X+114528Y+113130X0180Y         S1      
327m3334            PEX2  -AP25       A01X+114902Y+113130X0180Y         S1      
327m3334            PEX2  -AP26       A01X+115276Y+113130X0180Y         S1      
327m3334            PEX2  -AP23       A01X+114154Y+113130X0180Y         S1      
327m3334            PEX2  -AP22       A01X+113780Y+113130X0180Y         S1      
327m3334            PEX2  -AP20       A01X+113031Y+113130X0180Y         S1      
327m3334            PEX2  -AP21       A01X+113405Y+113130X0180Y         S1      
327m3334            PEX2  -AP19       A01X+112657Y+113130X0180Y         S1      
327m3334            PEX2  -AP17       A01X+111909Y+113130X0180Y         S1      
327m3334            PEX2  -AP16       A01X+111535Y+113130X0180Y         S1      
327m3334            PEX2  -AP18       A01X+112283Y+113130X0180Y         S1      
327m3334            R6534 -1          A01X+097566Y+101750X0198Y0197R270 S1      
327m3334            C4336 -1          A01X+091394Y+102810X0120Y0150R180 S1      
327m3334            C4337 -1          A01X+091399Y+102289X0120Y0150R180 S1      
327m3334            R6530 -1          A01X+096382Y+101732X0198Y0197R270 S1      
327m3334            R6529 -1          A01X+097176Y+101748X0198Y0197R270 S1      
327m3334            R6525 -1          A01X+096762Y+101746X0198Y0197R270 S1      
327m3334            R6526 -1          A01X+095099Y+101723X0198Y0197R270 S1      
327m3334            R6533 -1          A01X+095487Y+101723X0198Y0197R270 S1      
327m3334            R6523 -1          A01X+093993Y+101723X0198Y0197R270 S1      
327m3334            R6524 -1          A01X+094543Y+101723X0198Y0197R270 S1      
327m3334            R6531 -1          A01X+093438Y+101723X0198Y0197R270 S1      
327m3334            R6521 -1          A01X+092798Y+101723X0198Y0197R270 S1      
327m3334            R6522 -1          A01X+091646Y+101723X0198Y0197R270 S1      
327m3334            R6532 -1          A01X+092186Y+101723X0198Y0197R270 S1      
327m3334            L114  -2   M      A01X+096072Y+105037X0460Y3860     S1      
327m3334            R6136 -2A  M      A01X+096121Y+105068X0590Y0790     S1      
327m3334            R6136 -2B  M      A01X+095876Y+105068X0100Y0200     S1      
327m3334            L116  -2   M      A01X+092658Y+105068X0460Y3860R180 S1      
327m3334            R6137 -2A  M      A01X+092609Y+105068X0590Y0790R180 S1      
327m3334            R6137 -2B  M      A01X+092854Y+105068X0100Y0200R180 S1      
317m3334            VIA   -    MD0100PA00X+092786Y+102477X0200Y         S0      
317m3334            VIA   -    MD0100PA00X+092502Y+101891X0200Y         S0      
317m3334            VIA   -    M      A01X+092486Y+102321X0200Y         S2      
017m3334            VIA   -    M      A18X+092486Y+102321X0260Y         S2      
017m3334                  -    MD0100PA00X+092486Y+102321                       
317m3334            VIA   -    MD0100PA00X+092486Y+102676X0200Y         S0      
317m3334            VIA   -    MD0100PA00X+094898Y+102132X0200Y         S0      
317m3334            VIA   -    M      A01X+094309Y+102177X0200Y         S2      
017m3334            VIA   -    M      A18X+094309Y+102177X0260Y         S2      
017m3334                  -    MD0100PA00X+094309Y+102177                       
317m3334            VIA   -    MD0100PA00X+094276Y+101875X0200Y         S0      
317m3334            VIA   -    MD0100PA00X+093682Y+101899X0200Y         S0      
317m3334            VIA   -    MD0100PA00X+093088Y+101875X0200Y         S0      
317m3334            VIA   -    MD0100PA00X+093086Y+102321X0200Y         S0      
317m3334            VIA   -    MD0100PA00X+093986Y+102321X0200Y         S0      
317m3334            VIA   -    MD0100PA00X+094286Y+102676X0200Y         S0      
317m3334            VIA   -    MD0100PA00X+093686Y+102676X0200Y         S0      
317m3334            VIA   -    MD0100PA00X+093086Y+102676X0200Y         S0      
317m3334            VIA   -    MD0100PA00X+094586Y+102321X0200Y         S0      
317m3334            VIA   -    MD0100PA00X+093491Y+102358X0200Y         S0      
317m3334            VIA   -    MD0100PA00X+095937Y+102698X0200Y         S0      
317m3334            VIA   -    MD0100PA00X+096064Y+102192X0200Y         S0      
317m3334            VIA   -    MD0100PA00X+096121Y+101859X0200Y         S0      
317m3334            VIA   -    MD0100PA00X+095768Y+101856X0200Y         S0      
317m3334            VIA   -    MD0100PA00X+094002Y+102018X0200Y         S0      
317m3334            VIA   -    MD0100PA00X+095786Y+102321X0200Y         S0      
317m3334            VIA   -    MD0100PA00X+095186Y+102321X0200Y         S0      
317m3334            VIA   -    MD0100PA00X+095486Y+102676X0200Y         S0      
317m3334            VIA   -    MD0100PA00X+094886Y+102676X0200Y         S0      
317m3334            VIA   -    M      A01X+095494Y+102200X0200Y         S2      
017m3334            VIA   -    M      A18X+095494Y+102200X0260Y         S2      
017m3334                  -    MD0100PA00X+095494Y+102200                       
317m3334            VIA   -    MD0100PA00X+096386Y+102321X0200Y         S0      
317m3334            VIA   -    MD0100PA00X+096386Y+102676X0200Y         S0      
317m3334            VIA   -    MD0100PA00X+098780Y+113162X0200Y    R090 S0      
317m3334            VIA   -    MD0100PA00X+098456Y+113477X0200Y    R090 S0      
317m3334            VIA   -    MD0100PA00X+098456Y+112877X0200Y    R090 S0      
317m3334            VIA   -    MD0100PA00X+098811Y+113777X0200Y    R090 S0      
317m3334            VIA   -    MD0100PA00X+098456Y+114077X0200Y    R090 S0      
317m3334            VIA   -    MD0100PA00X+099176Y+113438X0200Y    R090 S0      
317m3334            VIA   -    MD0100PA00X+099176Y+112838X0200Y    R090 S0      
317m3334            VIA   -    MD0100PA00X+099176Y+114038X0200Y    R090 S0      
317m3334            VIA   -    MD0100PA00X+099501Y+113122X0200Y    R090 S0      
317m3334            VIA   -    MD0100PA00X+099532Y+113738X0200Y    R090 S0      
327m3334            PEX2  -T17        A01X+111909Y+119862X0180Y         S1      
327m3334            PEX2  -T18        A01X+112283Y+119862X0180Y         S1      
327m3334            PEX2  -T16        A01X+111535Y+119862X0180Y         S1      
327m3334            PEX2  -T19        A01X+112657Y+119862X0180Y         S1      
327m3334            PEX2  -T21        A01X+113405Y+119862X0180Y         S1      
327m3334            PEX2  -T20        A01X+113031Y+119862X0180Y         S1      
327m3334            PEX2  -T22        A01X+113780Y+119862X0180Y         S1      
327m3334            PEX2  -T23        A01X+114154Y+119862X0180Y         S1      
327m3334            PEX2  -T24        A01X+114528Y+119862X0180Y         S1      
327m3334            PEX2  -T26        A01X+115276Y+119862X0180Y         S1      
327m3334            PEX2  -T25        A01X+114902Y+119862X0180Y         S1      
327m3334            PEX2  -T31        A01X+117146Y+119862X0180Y         S1      
327m3334            PEX2  -T29        A01X+116398Y+119862X0180Y         S1      
327m3334            PEX2  -T28        A01X+116024Y+119862X0180Y         S1      
327m3334            PEX2  -T27        A01X+115650Y+119862X0180Y         S1      
327m3334            PEX2  -T30        A01X+116772Y+119862X0180Y         S1      
327m3334            PEX2  -T33        A01X+117894Y+119862X0180Y         S1      
327m3334            PEX2  -T32        A01X+117520Y+119862X0180Y         S1      
327m3335            PU10  -38         A01X+052099Y+111023X0090Y0240R180 S1      
317m3335            VIA   -    MD0100PA00X+052271Y+110690X0200Y    R090 S0      
327m3335            PU6   -29         A01X+046998Y+102675X0070Y0240     S1      
317m3335            VIA   -    M      A01X+047061Y+103378X0200Y    R090 S2      
017m3335            VIA   -    M      A18X+047061Y+103378X0260Y    R090 S2      
017m3335                  -    MD0100PA00X+047061Y+103378                       
327P1V25_PEX3_CS    PU19  -3          A01X+179740Y+121217X0070Y0320R270 S1      
317P1V25_PEX3_CS    VIA   -    M      A01X+180267Y+121090X0200Y         S2      
017P1V25_PEX3_CS    VIA   -    M      A18X+180267Y+121090X0260Y         S2      
017P1V25_PEX3_CS          -    MD0100PA00X+180267Y+121090                       
327P1V25_PEX3_CS    PR182 -1          A01X+180538Y+120947X0198Y0197R270 S1      
327P0V8_PEX2_TSEN   PR144 -2          A18X+137055Y+102677X0198Y0197R270 S2      
317P0V8_PEX2_TSEN   VIA   -    MD0100PA00X+133496Y+110555X0200Y         S0      
327P0V8_PEX2_TSEN   PU12  -36         A01X+133390Y+111023X0090Y0240R180 S1      
317P0V8_PEX2_TSEN   VIA   -    M      A01X+136626Y+103988X0200Y         S2      
017P0V8_PEX2_TSEN   VIA   -    M      A18X+136626Y+103988X0260Y         S2      
017P0V8_PEX2_TSEN         -    MD0100PA00X+136626Y+103988                       
327P0V8_PEX2_TSEN   PU13  -36         A01X+136603Y+111023X0090Y0240R180 S1      
317P0V8_PEX2_TSEN   VIA   -    MD0100PA00X+136708Y+110555X0200Y         S0      
327P1V25_PEX3_VCC   PU19  -19         A01X+178638Y+120863X0120Y0320R090 S1      
327P1V25_PEX3_VCC   R847  -1          A18X+181777Y+120232X0198Y0197R270 S2      
327P1V25_PEX3_VCC   PC277 -1          A01X+178077Y+120811X0198Y0197R090 S1      
317P1V25_PEX3_VCC   VIA   -    M      A01X+178328Y+120814X0200Y         S2      
017P1V25_PEX3_VCC   VIA   -    M      A18X+178328Y+120814X0260Y         S2      
017P1V25_PEX3_VCC         -    MD0100PA00X+178328Y+120814                       
317P0V8_PEX0_PWM1   VIA   -    MD0100PA00X+041699Y+110479X0200Y         S0      
327P0V8_PEX0_PWM1   PU7   -34         A01X+041619Y+111023X0090Y0240R180 S1      
327P0V8_PEX0_PWM1   PU6   -8          A01X+047943Y+100785X0070Y0240     S1      
317P0V8_PEX0_PWM1   VIA   -    M      A01X+048071Y+099994X0200Y    R090 S2      
017P0V8_PEX0_PWM1   VIA   -    M      A18X+048071Y+099994X0260Y    R090 S2      
017P0V8_PEX0_PWM1         -    MD0100PA00X+048071Y+099994                       
327P1V25_PEX3_FB    PU19  -7          A01X+179740Y+121847X0070Y0320R270 S1      
317P1V25_PEX3_FB    VIA   -    M      A01X+180724Y+121996X0200Y         S2      
017P1V25_PEX3_FB    VIA   -    M      A18X+180724Y+121996X0260Y         S2      
017P1V25_PEX3_FB          -    MD0100PA00X+180724Y+121996                       
327P1V25_PEX3_FB    PR183 -2   M      A01X+180470Y+121943X0198Y0197R090 S1      
327P1V25_PEX3_FB    PR181 -2          A01X+180986Y+122321X0198Y0197R180 S1      
327P1V25_PEX3_FB    PC280 -1   M      A01X+180986Y+121921X0198Y0197     S1      
327m3336            VIA   -           A01X+047215Y+099605X0300Y         S1      
327m3336            PU6   -4          A01X+047313Y+100785X0070Y0240     S1      
327P1V25_PEX3_EN    PU19  -8          A01X+179740Y+122005X0070Y0320R270 S1      
317P1V25_PEX3_EN    VIA   -    M      A01X+180049Y+122060X0200Y         S2      
017P1V25_PEX3_EN    VIA   -    M      A18X+180049Y+122060X0260Y         S2      
017P1V25_PEX3_EN          -    MD0100PA00X+180049Y+122060                       
327P1V25_PEX3_EN    R848  -1          A01X+180298Y+122320X0198Y0197     S1      
327m3337            PR129 -2          A01X+137134Y+102477X0198Y0197     S1      
327m3337            PU11  -32         A01X+138022Y+102282X0070Y0240R090 S1      
327m3337            PC130 -1   M      A01X+137526Y+102469X0198Y0197R090 S1      
327m3338            PU19  -1          A01X+179720Y+120863X0120Y0360R270 S1      
327m3338            PC271 -1          A01X+180050Y+120174X0198Y0197     S1      
317m3339            VIA   -    MD0100PA00X+042500Y+110690X0200Y    R090 S0      
327m3339            PU7   -38         A01X+042327Y+111023X0090Y0240R180 S1      
327m3339            PU6   -23         A01X+047943Y+102675X0070Y0240     S1      
317m3339            VIA   -    M      A01X+047098Y+104659X0200Y    R090 S2      
017m3339            VIA   -    M      A18X+047098Y+104659X0260Y    R090 S2      
017m3339                  -    MD0100PA00X+047098Y+104659                       
327P1V25_PEX3_REF   PU19  -5          A01X+179740Y+121532X0070Y0320R270 S1      
317P1V25_PEX3_REF   VIA   -           A01X+181213Y+120535X0200Y         S2      
017P1V25_PEX3_REF   VIA   -           A18X+181213Y+120535X0260Y         S2      
017P1V25_PEX3_REF         -     D0100PA00X+181213Y+120535                       
327P1V25_PEX3_REF   PC282 -1   M      A01X+180920Y+121215X0198Y0197R090 S1      
327P1V25_PEX3_REF   PC281 -1   M      A01X+180935Y+120831X0198Y0197R270 S1      
327m3340            VIA   -    M      A18X+145779Y+129273X0260Y         S2      
327m3340            PJ24  -1          A18X+144446Y+129300X0200Y0400R270 S2      
327m3340            PEX3  -V39        A01X+165846Y+119114X0180Y         S1      
317m3340            VIA   -    MD0080PA00X+166033Y+118927X0160Y         S0      
327m3341            PU19  -6          A01X+179740Y+121690X0070Y0320R270 S1      
317m3341            VIA   -    M      A01X+180684Y+121467X0200Y         S2      
017m3341            VIA   -    M      A18X+180684Y+121467X0260Y         S2      
017m3341                  -    MD0100PA00X+180684Y+121467                       
327m3341            PR183 -1   M      A01X+180470Y+121628X0198Y0197R090 S1      
327m3341            PJ16  -1          A01X+181703Y+121105X0200Y0400R090 S1      
327m3341            PC981 -2   M      A01X+181303Y+121188X0198Y0197R270 S1      
327m3341            PC282 -2   M      A01X+180920Y+121530X0198Y0197R090 S1      
327m3342            R5773 -2          A01X+085368Y+083946X0198Y0197R180 S1      
327m3342            PR124 -2          A01X+141519Y+099677X0198Y0197R180 S1      
327m3342            PU11  -11         A01X+139912Y+101022X0070Y0240R090 S1      
317m3342            VIA   -    M      A01X+141270Y+099759X0200Y         S2      
017m3342            VIA   -    M      A18X+141270Y+099759X0260Y         S2      
017m3342                  -    MD0100PA00X+141270Y+099759                       
317m3342            VIA   -    MD0100PA00X+119970Y+101366X0200Y         S0      
317m3342            VIA   -    MD0100PA00X+085118Y+083946X0200Y         S0      
317m3342            VIA   -    MD0100PA00X+086597Y+097819X0200Y         S0      
327m3343            PU19  -20         A01X+179071Y+121020X0120Y0790R180 S1      
327m3343            PC271 -2          A01X+180365Y+120174X0198Y0197     S1      
327m3343            PL24  -1          A01X+179310Y+119014X1160Y1460R270 S1      
327m3344            PR129 -1          A01X+136819Y+102477X0198Y0197     S1      
327m3344            PJ8   -2          A01X+137026Y+102982X0280Y0320R180 S1      
317m3345            VIA   -    M      A01X+181474Y+121709X0200Y         S2      
017m3345            VIA   -    M      A18X+181474Y+121709X0260Y         S2      
017m3345                  -    MD0100PA00X+181474Y+121709                       
327m3345            PJ15  -1          A01X+181703Y+121532X0200Y0400R090 S1      
327m3345            PC981 -1   M      A01X+181303Y+121504X0198Y0197R270 S1      
327m3345            PC280 -2   M      A01X+181301Y+121921X0198Y0197     S1      
327m3345            PR181 -1          A01X+181301Y+122321X0198Y0197R180 S1      
327m3346            R835  -2          A01X+142319Y+100477X0198Y0197R180 S1      
327m3346            PU11  -13         A01X+139912Y+101337X0070Y0240R090 S1      
327m3346            VIA   -    M      A01X+140582Y+101196X0300Y         S1      
327m3346            C835  -2   M      A01X+141519Y+100477X0198Y0197R180 S1      
327P0V8_PEX2        C1629 -1          A18X+117333Y+117349X0120Y0150R090 S2      
327P0V8_PEX2        C1656 -1          A18X+116585Y+117349X0120Y0150R090 S2      
327P0V8_PEX2        C1645 -1          A18X+115836Y+117349X0120Y0150R090 S2      
327P0V8_PEX2        C1651 -1          A18X+115088Y+117349X0120Y0150R090 S2      
327P0V8_PEX2        C1661 -1          A18X+113966Y+117349X0120Y0150R090 S2      
327P0V8_PEX2        C1664 -1          A18X+113218Y+117349X0120Y0150R090 S2      
327P0V8_PEX2        C1620 -1          A18X+112470Y+117349X0120Y0150R090 S2      
327P0V8_PEX2        C1660 -1          A18X+111722Y+117349X0120Y0150R090 S2      
327P0V8_PEX2        C1642 -1          A18X+110974Y+117349X0120Y0150R090 S2      
327P0V8_PEX2        C1619 -1          A18X+110892Y+118179X0120Y0150     S2      
327P0V8_PEX2        C1634 -1          A18X+110682Y+117825X0120Y0150R180 S2      
327P0V8_PEX2        C1652 -1          A18X+116959Y+117139X0120Y0150R270 S2      
327P0V8_PEX2        C1648 -1          A18X+116211Y+117139X0120Y0150R270 S2      
327P0V8_PEX2        C1640 -1          A18X+116959Y+115853X0120Y0150R090 S2      
327P0V8_PEX2        C1641 -1          A18X+116210Y+115853X0120Y0150R090 S2      
327P0V8_PEX2        C1612 -1          A18X+116188Y+116229X0280Y0320R090 S2      
327P0V8_PEX2        C1649 -1          A18X+115462Y+117139X0120Y0150R270 S2      
327P0V8_PEX2        C1643 -1          A18X+114346Y+117139X0120Y0150R270 S2      
327P0V8_PEX2        C1631 -1          A18X+114640Y+116683X0120Y0150     S2      
327P0V8_PEX2        C1623 -1          A18X+115462Y+115853X0120Y0150R090 S2      
327P0V8_PEX2        C1654 -1          A18X+114340Y+115853X0120Y0150R090 S2      
327P0V8_PEX2        C1610 -1          A18X+114318Y+116229X0280Y0320R090 S2      
327P0V8_PEX2        C1624 -1          A18X+113592Y+117139X0120Y0150R270 S2      
327P0V8_PEX2        C1663 -1          A18X+112844Y+117139X0120Y0150R270 S2      
327P0V8_PEX2        C1621 -1          A18X+113592Y+115853X0120Y0150R090 S2      
327P0V8_PEX2        C1657 -1          A18X+112844Y+115853X0120Y0150R090 S2      
327P0V8_PEX2        C1611 -1          A18X+112822Y+116229X0280Y0320R090 S2      
327P0V8_PEX2        C1647 -1          A18X+112096Y+117139X0120Y0150R270 S2      
327P0V8_PEX2        C1662 -1          A18X+111348Y+117139X0120Y0150R270 S2      
327P0V8_PEX2        C1625 -1          A18X+112096Y+115853X0120Y0150R090 S2      
327P0V8_PEX2        C1644 -1          A18X+111348Y+115853X0120Y0150R090 S2      
327P0V8_PEX2        C1633 -1          A18X+110600Y+117139X0120Y0150R270 S2      
327P0V8_PEX2        C1638 -1          A18X+110600Y+115853X0120Y0150R090 S2      
327P0V8_PEX2        C1659 -1          A18X+117333Y+115643X0120Y0150R270 S2      
327P0V8_PEX2        C1655 -1          A18X+116585Y+115643X0120Y0150R270 S2      
327P0V8_PEX2        C1658 -1          A18X+115836Y+115643X0120Y0150R270 S2      
327P0V8_PEX2        C1650 -1          A18X+115088Y+115643X0120Y0150R270 S2      
327P0V8_PEX2        C1653 -1          A18X+113966Y+115643X0120Y0150R270 S2      
327P0V8_PEX2        C1646 -1          A18X+113218Y+115643X0120Y0150R270 S2      
327P0V8_PEX2        C1665 -1          A18X+112470Y+115643X0120Y0150R270 S2      
327P0V8_PEX2        C1666 -1          A18X+111722Y+115643X0120Y0150R270 S2      
327P0V8_PEX2        C1622 -1          A18X+110974Y+115643X0120Y0150R270 S2      
327P0V8_PEX2        C1616 -1          A18X+110892Y+114813X0120Y0150     S2      
327P0V8_PEX2        C1615 -1          A18X+110682Y+115187X0120Y0150R180 S2      
327P0V8_PEX2        C1614 -1          A18X+110682Y+114439X0120Y0150R180 S2      
327P0V8_PEX2        C1613 -1          A18X+118163Y+115561X0120Y0150R180 S2      
327P0V8_PEX2        C1630 -1          A18X+118163Y+117431X0120Y0150R180 S2      
327P0V8_PEX2        C1626 -1   M      A18X+110910Y+116683X0120Y0150     S2      
327P0V8_PEX2        C1639 -1   M      A18X+110662Y+118510X0120Y0150R180 S2      
327P0V8_PEX2        C1628 -1   M      A18X+111658Y+116683X0120Y0150     S2      
327P0V8_PEX2        C1618 -1   M      A18X+112406Y+116683X0120Y0150     S2      
327P0V8_PEX2        C1636 -1   M      A18X+113154Y+116683X0120Y0150     S2      
327P0V8_PEX2        C1627 -1   M      A18X+113902Y+116683X0120Y0150     S2      
327P0V8_PEX2        C1637 -1   M      A18X+115112Y+116690X0120Y0150R180 S2      
327P0V8_PEX2        C1635 -1   M      A18X+115822Y+116690X0120Y0150     S2      
327P0V8_PEX2        C1617 -1   M      A18X+116511Y+116683X0120Y0150     S2      
327P0V8_PEX2        C1632 -1   M      A18X+117259Y+116683X0120Y0150     S2      
317P0V8_PEX2        VIA   -    MD0080PA00X+110600Y+115935X0160Y         S0      
317P0V8_PEX2        VIA   -    MD0080PA00X+110600Y+117057X0160Y         S0      
317P0V8_PEX2        VIA   -    MD0080PA00X+110600Y+114439X0160Y         S0      
317P0V8_PEX2        VIA   -    MD0080PA00X+110600Y+115187X0160Y         S0      
317P0V8_PEX2        VIA   -    MD0080PA00X+110600Y+118553X0160Y         S0      
317P0V8_PEX2        VIA   -    MD0080PA00X+110600Y+117805X0160Y         S0      
317P0V8_PEX2        VIA   -    MD0080PA00X+112470Y+117431X0160Y         S0      
317P0V8_PEX2        VIA   -    MD0080PA00X+111722Y+117431X0160Y         S0      
317P0V8_PEX2        VIA   -    MD0080PA00X+110974Y+118179X0160Y         S0      
317P0V8_PEX2        VIA   -    MD0080PA00X+110974Y+117431X0160Y         S0      
317P0V8_PEX2        VIA   -    MD0080PA00X+112470Y+116683X0160Y         S0      
317P0V8_PEX2        VIA   -    MD0080PA00X+112096Y+117057X0160Y         S0      
317P0V8_PEX2        VIA   -    MD0080PA00X+111722Y+116683X0160Y         S0      
317P0V8_PEX2        VIA   -    MD0080PA00X+111348Y+117057X0160Y         S0      
317P0V8_PEX2        VIA   -    MD0080PA00X+110974Y+116683X0160Y         S0      
317P0V8_PEX2        VIA   -    MD0080PA00X+112096Y+115935X0160Y         S0      
317P0V8_PEX2        VIA   -    MD0080PA00X+111348Y+115935X0160Y         S0      
317P0V8_PEX2        VIA   -    MD0080PA00X+111722Y+115561X0160Y         S0      
317P0V8_PEX2        VIA   -    MD0080PA00X+110974Y+114813X0160Y         S0      
317P0V8_PEX2        VIA   -    MD0080PA00X+110974Y+115561X0160Y         S0      
317P0V8_PEX2        VIA   -    MD0080PA00X+112470Y+115561X0160Y         S0      
317P0V8_PEX2        VIA   -    MD0080PA00X+113592Y+115935X0160Y         S0      
317P0V8_PEX2        VIA   -    MD0080PA00X+112844Y+115935X0160Y         S0      
317P0V8_PEX2        VIA   -    MD0080PA00X+113218Y+116683X0160Y         S0      
317P0V8_PEX2        VIA   -    MD0080PA00X+112844Y+117057X0160Y         S0      
317P0V8_PEX2        VIA   -    MD0080PA00X+113592Y+117057X0160Y         S0      
317P0V8_PEX2        VIA   -    MD0080PA00X+113966Y+116683X0160Y         S0      
317P0V8_PEX2        VIA   -    MD0080PA00X+113218Y+115561X0160Y         S0      
317P0V8_PEX2        VIA   -    MD0080PA00X+113966Y+115561X0160Y         S0      
317P0V8_PEX2        VIA   -    MD0080PA00X+113218Y+117431X0160Y         S0      
317P0V8_PEX2        VIA   -    MD0080PA00X+113966Y+117431X0160Y         S0      
317P0V8_PEX2        VIA   -    MD0080PA00X+115088Y+117431X0160Y         S0      
317P0V8_PEX2        VIA   -    MD0080PA00X+115462Y+117057X0160Y         S0      
317P0V8_PEX2        VIA   -    MD0080PA00X+115088Y+116683X0160Y         S0      
317P0V8_PEX2        VIA   -    MD0080PA00X+114340Y+115935X0160Y         S0      
317P0V8_PEX2        VIA   -    MD0080PA00X+115462Y+115935X0160Y         S0      
317P0V8_PEX2        VIA   -    MD0080PA00X+114340Y+117057X0160Y         S0      
317P0V8_PEX2        VIA   -    MD0080PA00X+115088Y+115561X0160Y         S0      
317P0V8_PEX2        VIA   -    MD0080PA00X+116211Y+115935X0160Y         S0      
317P0V8_PEX2        VIA   -    MD0080PA00X+116959Y+115935X0160Y         S0      
317P0V8_PEX2        VIA   -    MD0080PA00X+116211Y+117057X0160Y         S0      
317P0V8_PEX2        VIA   -    MD0080PA00X+115836Y+116683X0160Y         S0      
317P0V8_PEX2        VIA   -    MD0080PA00X+116959Y+117057X0160Y         S0      
317P0V8_PEX2        VIA   -    MD0080PA00X+116585Y+116683X0160Y         S0      
317P0V8_PEX2        VIA   -    MD0080PA00X+115836Y+115561X0160Y         S0      
317P0V8_PEX2        VIA   -    MD0080PA00X+116585Y+115561X0160Y         S0      
317P0V8_PEX2        VIA   -    MD0080PA00X+117333Y+115561X0160Y         S0      
317P0V8_PEX2        VIA   -    MD0080PA00X+117333Y+117431X0160Y         S0      
317P0V8_PEX2        VIA   -    MD0080PA00X+115836Y+117431X0160Y         S0      
317P0V8_PEX2        VIA   -    MD0080PA00X+116585Y+117431X0160Y         S0      
317P0V8_PEX2        VIA   -    MD0080PA00X+117333Y+116683X0160Y         S0      
317P0V8_PEX2        VIA   -    MD0080PA00X+118081Y+115561X0160Y         S0      
317P0V8_PEX2        VIA   -    MD0080PA00X+118081Y+117431X0160Y         S0      
327P0V8_PEX2        PR150 -2          A18X+134496Y+110882X0198Y0197R090 S2      
327P0V8_PEX2        PR154 -2          A18X+137709Y+110882X0198Y0197R090 S2      
327P0V8_PEX2        L63   -1   M      A01X+132869Y+125185X0460Y3860R090 S1      
327P0V8_PEX2        R5791 -1A  M      A01X+132869Y+125087X0590Y0790R090 S1      
327P0V8_PEX2        R5791 -1B  M      A01X+132869Y+125332X0100Y0200R090 S1      
327P0V8_PEX2        R5794 -1B  M      A01X+135425Y+123473X0100Y0200     S1      
327P0V8_PEX2        R5794 -1A  M      A01X+135180Y+123473X0590Y0790     S1      
327P0V8_PEX2        L62   -1   M      A01X+135229Y+123473X0460Y3860     S1      
327P0V8_PEX2        C4319 -1          A01X+134145Y+121756X0280Y0320R180 S1      
327P0V8_PEX2        C4303 -1          A01X+131482Y+121793X0280Y0320R180 S1      
327P0V8_PEX2        PC167 -1          A01X+136804Y+119197X0400Y0500R270 S1      
327P0V8_PEX2        PC164 -1          A01X+134111Y+119197X0400Y0500R270 S1      
327P0V8_PEX2        PC150 -1          A01X+131418Y+119197X0400Y0500R270 S1      
327P0V8_PEX2        PC152 -1          A01X+135457Y+118306X0950Y1110R090 S1      
327P0V8_PEX2        PC169 -1          A01X+132764Y+118306X0950Y1110R090 S1      
327P0V8_PEX2        PC163 -1          A01X+137686Y+115833X0198Y0197R270 S1      
327P0V8_PEX2        PL13  -2          A01X+136106Y+116776X1220Y1320R180 S1      
327P0V8_PEX2        PL12  -2          A01X+133324Y+116776X1220Y1320R180 S1      
327P0V8_PEX2        PC147 -1          A01X+131744Y+115833X0198Y0197R270 S1      
327P0V8_PEX2        C4320 -1          A18X+134006Y+121659X0120Y0150R090 S2      
327P0V8_PEX2        C4321 -1          A18X+133691Y+121659X0120Y0150R090 S2      
327P0V8_PEX2        C4316 -1          A18X+132392Y+121791X0280Y0320R180 S2      
327P0V8_PEX2        C4302 -1          A18X+132935Y+121791X0280Y0320R180 S2      
327P0V8_PEX2        C4318 -1          A18X+131701Y+121791X0280Y0320R180 S2      
327P0V8_PEX2        C4317 -1          A18X+134433Y+121791X0280Y0320R180 S2      
327P0V8_PEX2        C4305 -1          A18X+135763Y+121791X0280Y0320R180 S2      
327P0V8_PEX2        C4304 -1   M      A18X+131170Y+125150X0280Y0320R180 S2      
327P0V8_PEX2        C4307 -1          A18X+133373Y+121660X0120Y0150R090 S2      
327P0V8_PEX2        C4306 -1          A18X+131296Y+121571X0120Y0150R090 S2      
327P0V8_PEX2        L64   -1   M      A18X+132869Y+125185X0460Y3860R270 S2      
327P0V8_PEX2        R5793 -1A  M      A18X+132869Y+125087X0590Y0790R270 S2      
327P0V8_PEX2        R5793 -1B  M      A18X+132869Y+125332X0100Y0200R270 S2      
327P0V8_PEX2        L61   -1   M      A18X+135229Y+123473X0460Y3860R180 S2      
327P0V8_PEX2        R5792 -1A  M      A18X+135180Y+123473X0590Y0790R180 S2      
327P0V8_PEX2        R5792 -1B  M      A18X+135425Y+123473X0100Y0200R180 S2      
327P0V8_PEX2        PR125 -1          A18X+136980Y+119347X0198Y0197R180 S2      
327P0V8_PEX2        PR12  -1   M      A18X+135216Y+121791X0280Y0320R180 S2      
327P0V8_PEX2        PC149 -1          A18X+134111Y+119197X0400Y0500R090 S2      
327P0V8_PEX2        PC168 -1          A18X+132764Y+119197X0400Y0500R090 S2      
327P0V8_PEX2        PC151 -1          A18X+136106Y+116874X0950Y1110R090 S2      
327P0V8_PEX2        PC148 -1          A18X+134715Y+115904X0400Y0500R270 S2      
327P0V8_PEX2        PC165 -1          A18X+133324Y+116874X0950Y1110R090 S2      
317P0V8_PEX2        VIA   -    MD0100PA00X+137686Y+116083X0200Y         S0      
317P0V8_PEX2        VIA   -    MD0100PA00X+135115Y+115820X0200Y         S0      
317P0V8_PEX2        VIA   -    MD0100PA00X+131524Y+122143X0200Y         S0      
317P0V8_PEX2        VIA   -    MD0100PA00X+131124Y+122143X0200Y         S0      
317P0V8_PEX2        VIA   -    MD0100PA00X+131818Y+119012X0200Y    R180 S0      
317P0V8_PEX2        VIA   -    MD0100PA00X+131818Y+119262X0200Y    R180 S0      
317P0V8_PEX2        VIA   -    MD0100PA00X+131744Y+116083X0200Y         S0      
317P0V8_PEX2        VIA   -    MD0100PA00X+131924Y+124143X0200Y         S0      
317P0V8_PEX2        VIA   -    MD0100PA00X+131524Y+124143X0200Y         S0      
317P0V8_PEX2        VIA   -    M      A01X+131924Y+122543X0200Y         S2      
017P0V8_PEX2        VIA   -    M      A18X+131924Y+122543X0260Y         S2      
017P0V8_PEX2              -    MD0100PA00X+131924Y+122543                       
317P0V8_PEX2        VIA   -    MD0100PA00X+131924Y+122943X0200Y         S0      
317P0V8_PEX2        VIA   -    MD0100PA00X+131924Y+123343X0200Y         S0      
317P0V8_PEX2        VIA   -    MD0100PA00X+131924Y+123743X0200Y         S0      
317P0V8_PEX2        VIA   -    MD0100PA00X+131524Y+122543X0200Y         S0      
317P0V8_PEX2        VIA   -    MD0100PA00X+131524Y+122943X0200Y         S0      
317P0V8_PEX2        VIA   -    MD0100PA00X+131524Y+123343X0200Y         S0      
317P0V8_PEX2        VIA   -    MD0100PA00X+131524Y+123743X0200Y         S0      
317P0V8_PEX2        VIA   -    MD0100PA00X+131124Y+122543X0200Y         S0      
317P0V8_PEX2        VIA   -    MD0100PA00X+131124Y+122943X0200Y         S0      
317P0V8_PEX2        VIA   -    MD0100PA00X+131124Y+123343X0200Y         S0      
317P0V8_PEX2        VIA   -    MD0100PA00X+131924Y+122143X0200Y         S0      
317P0V8_PEX2        VIA   -    MD0100PA00X+133524Y+124543X0200Y         S0      
317P0V8_PEX2        VIA   -    MD0100PA00X+133124Y+124143X0200Y         S0      
317P0V8_PEX2        VIA   -    MD0100PA00X+133124Y+124543X0200Y         S0      
317P0V8_PEX2        VIA   -    MD0100PA00X+132724Y+124143X0200Y         S0      
317P0V8_PEX2        VIA   -    MD0100PA00X+132724Y+124543X0200Y         S0      
317P0V8_PEX2        VIA   -    MD0100PA00X+132324Y+122543X0200Y         S0      
317P0V8_PEX2        VIA   -    MD0100PA00X+132324Y+122943X0200Y         S0      
317P0V8_PEX2        VIA   -    MD0100PA00X+132324Y+123343X0200Y         S0      
317P0V8_PEX2        VIA   -    M      A01X+132324Y+123743X0200Y         S2      
017P0V8_PEX2        VIA   -    M      A18X+132324Y+123743X0260Y         S2      
017P0V8_PEX2              -    MD0100PA00X+132324Y+123743                       
317P0V8_PEX2        VIA   -    MD0100PA00X+133524Y+122543X0200Y         S0      
317P0V8_PEX2        VIA   -    MD0100PA00X+133524Y+122943X0200Y         S0      
317P0V8_PEX2        VIA   -    MD0100PA00X+133524Y+123343X0200Y         S0      
317P0V8_PEX2        VIA   -    M      A01X+133524Y+123743X0200Y         S2      
017P0V8_PEX2        VIA   -    M      A18X+133524Y+123743X0260Y         S2      
017P0V8_PEX2              -    MD0100PA00X+133524Y+123743                       
317P0V8_PEX2        VIA   -    MD0100PA00X+133124Y+122543X0200Y         S0      
317P0V8_PEX2        VIA   -    M      A01X+133124Y+122943X0200Y         S2      
017P0V8_PEX2        VIA   -    M      A18X+133124Y+122943X0260Y         S2      
017P0V8_PEX2              -    MD0100PA00X+133124Y+122943                       
317P0V8_PEX2        VIA   -    MD0100PA00X+133124Y+123343X0200Y         S0      
317P0V8_PEX2        VIA   -    MD0100PA00X+133124Y+123743X0200Y         S0      
317P0V8_PEX2        VIA   -    MD0100PA00X+132724Y+122543X0200Y         S0      
317P0V8_PEX2        VIA   -    MD0100PA00X+132724Y+122943X0200Y         S0      
317P0V8_PEX2        VIA   -    MD0100PA00X+132724Y+123343X0200Y         S0      
317P0V8_PEX2        VIA   -    MD0100PA00X+132724Y+123743X0200Y         S0      
317P0V8_PEX2        VIA   -    MD0100PA00X+132324Y+122143X0200Y         S0      
317P0V8_PEX2        VIA   -    MD0100PA00X+133524Y+122143X0200Y         S0      
317P0V8_PEX2        VIA   -    MD0100PA00X+133124Y+122143X0200Y         S0      
317P0V8_PEX2        VIA   -    MD0100PA00X+132724Y+122143X0200Y         S0      
317P0V8_PEX2        VIA   -    MD0100PA00X+133164Y+119012X0200Y    R180 S0      
317P0V8_PEX2        VIA   -    MD0100PA00X+133164Y+119262X0200Y    R180 S0      
317P0V8_PEX2        VIA   -    MD0100PA00X+132314Y+117488X0200Y         S0      
317P0V8_PEX2        VIA   -    MD0100PA00X+132564Y+117488X0200Y         S0      
317P0V8_PEX2        VIA   -    MD0100PA00X+132049Y+117921X0200Y         S0      
317P0V8_PEX2        VIA   -    MD0100PA00X+132049Y+118171X0200Y         S0      
317P0V8_PEX2        VIA   -    MD0100PA00X+132049Y+118421X0200Y         S0      
317P0V8_PEX2        VIA   -    MD0100PA00X+132049Y+118671X0200Y         S0      
317P0V8_PEX2        VIA   -    MD0100PA00X+133479Y+118692X0200Y    R180 S0      
317P0V8_PEX2        VIA   -    MD0100PA00X+133479Y+118442X0200Y    R180 S0      
317P0V8_PEX2        VIA   -    MD0100PA00X+133479Y+118192X0200Y    R180 S0      
317P0V8_PEX2        VIA   -    MD0100PA00X+133479Y+117942X0200Y    R180 S0      
317P0V8_PEX2        VIA   -    MD0100PA00X+132314Y+116988X0200Y         S0      
317P0V8_PEX2        VIA   -    MD0100PA00X+132314Y+116738X0200Y         S0      
317P0V8_PEX2        VIA   -    MD0100PA00X+132314Y+116488X0200Y         S0      
317P0V8_PEX2        VIA   -    MD0100PA00X+132314Y+116238X0200Y         S0      
317P0V8_PEX2        VIA   -    MD0100PA00X+132314Y+117238X0200Y         S0      
317P0V8_PEX2        VIA   -    MD0100PA00X+132564Y+116988X0200Y         S0      
317P0V8_PEX2        VIA   -    MD0100PA00X+132564Y+116738X0200Y         S0      
317P0V8_PEX2        VIA   -    MD0100PA00X+132564Y+116488X0200Y         S0      
317P0V8_PEX2        VIA   -    MD0100PA00X+132564Y+116238X0200Y         S0      
317P0V8_PEX2        VIA   -    MD0100PA00X+132564Y+117238X0200Y         S0      
317P0V8_PEX2        VIA   -    MD0100PA00X+132324Y+124143X0200Y         S0      
317P0V8_PEX2        VIA   -    MD0100PA00X+132324Y+124543X0200Y         S0      
317P0V8_PEX2        VIA   -    MD0100PA00X+133524Y+124143X0200Y         S0      
317P0V8_PEX2        VIA   -    MD0100PA00X+134424Y+110630X0200Y         S0      
317P0V8_PEX2        VIA   -    MD0100PA00X+133924Y+124143X0200Y         S0      
317P0V8_PEX2        VIA   -    MD0100PA00X+133924Y+124543X0200Y         S0      
317P0V8_PEX2        VIA   -    MD0100PA00X+134324Y+124543X0200Y         S0      
317P0V8_PEX2        VIA   -    M      A01X+134324Y+124143X0200Y         S2      
017P0V8_PEX2        VIA   -    M      A18X+134324Y+124143X0260Y         S2      
017P0V8_PEX2              -    MD0100PA00X+134324Y+124143                       
317P0V8_PEX2        VIA   -    MD0100PA00X+134724Y+124143X0200Y         S0      
317P0V8_PEX2        VIA   -    MD0100PA00X+134724Y+124543X0200Y         S0      
317P0V8_PEX2        VIA   -    MD0100PA00X+133924Y+122543X0200Y         S0      
317P0V8_PEX2        VIA   -    MD0100PA00X+133924Y+122943X0200Y         S0      
317P0V8_PEX2        VIA   -    MD0100PA00X+133924Y+123343X0200Y         S0      
317P0V8_PEX2        VIA   -    MD0100PA00X+133924Y+123743X0200Y         S0      
317P0V8_PEX2        VIA   -    MD0100PA00X+134324Y+123743X0200Y         S0      
317P0V8_PEX2        VIA   -    MD0100PA00X+134324Y+123343X0200Y         S0      
317P0V8_PEX2        VIA   -    MD0100PA00X+134324Y+122943X0200Y         S0      
317P0V8_PEX2        VIA   -    MD0100PA00X+134724Y+122943X0200Y         S0      
317P0V8_PEX2        VIA   -    MD0100PA00X+134724Y+123343X0200Y         S0      
317P0V8_PEX2        VIA   -    MD0100PA00X+134724Y+123743X0200Y         S0      
317P0V8_PEX2        VIA   -    MD0100PA00X+133924Y+122143X0200Y         S0      
317P0V8_PEX2        VIA   -    MD0100PA00X+134324Y+122143X0200Y         S0      
317P0V8_PEX2        VIA   -    MD0100PA00X+134724Y+122143X0200Y         S0      
317P0V8_PEX2        VIA   -    MD0100PA00X+134511Y+119262X0200Y    R180 S0      
317P0V8_PEX2        VIA   -    MD0100PA00X+134511Y+119012X0200Y    R180 S0      
317P0V8_PEX2        VIA   -    MD0100PA00X+133711Y+119012X0200Y         S0      
317P0V8_PEX2        VIA   -    MD0100PA00X+133711Y+119262X0200Y         S0      
317P0V8_PEX2        VIA   -    MD0100PA00X+135096Y+117488X0200Y         S0      
317P0V8_PEX2        VIA   -    MD0100PA00X+134140Y+117488X0200Y         S0      
317P0V8_PEX2        VIA   -    MD0100PA00X+134390Y+117488X0200Y         S0      
317P0V8_PEX2        VIA   -    MD0100PA00X+134742Y+117921X0200Y         S0      
317P0V8_PEX2        VIA   -    MD0100PA00X+134742Y+118171X0200Y         S0      
317P0V8_PEX2        VIA   -    MD0100PA00X+134742Y+118421X0200Y         S0      
317P0V8_PEX2        VIA   -    MD0100PA00X+134742Y+118671X0200Y         S0      
317P0V8_PEX2        VIA   -    MD0100PA00X+135096Y+116238X0200Y         S0      
317P0V8_PEX2        VIA   -    MD0100PA00X+135096Y+116488X0200Y         S0      
317P0V8_PEX2        VIA   -    MD0100PA00X+135096Y+116738X0200Y         S0      
317P0V8_PEX2        VIA   -    MD0100PA00X+135096Y+116988X0200Y         S0      
317P0V8_PEX2        VIA   -    MD0100PA00X+135096Y+117238X0200Y         S0      
317P0V8_PEX2        VIA   -    MD0100PA00X+134140Y+116238X0200Y         S0      
317P0V8_PEX2        VIA   -    MD0100PA00X+134140Y+116488X0200Y         S0      
317P0V8_PEX2        VIA   -    MD0100PA00X+134140Y+116738X0200Y         S0      
317P0V8_PEX2        VIA   -    MD0100PA00X+134140Y+116988X0200Y         S0      
317P0V8_PEX2        VIA   -    MD0100PA00X+134140Y+117238X0200Y         S0      
317P0V8_PEX2        VIA   -    MD0100PA00X+134390Y+117238X0200Y         S0      
317P0V8_PEX2        VIA   -    MD0100PA00X+134390Y+116988X0200Y         S0      
317P0V8_PEX2        VIA   -    MD0100PA00X+134390Y+116738X0200Y         S0      
317P0V8_PEX2        VIA   -    MD0100PA00X+134390Y+116488X0200Y         S0      
317P0V8_PEX2        VIA   -    MD0100PA00X+134390Y+116238X0200Y         S0      
317P0V8_PEX2        VIA   -    MD0100PA00X+135346Y+117488X0200Y         S0      
317P0V8_PEX2        VIA   -    MD0100PA00X+136172Y+118692X0200Y    R180 S0      
317P0V8_PEX2        VIA   -    MD0100PA00X+136172Y+118442X0200Y    R180 S0      
317P0V8_PEX2        VIA   -    MD0100PA00X+136172Y+118192X0200Y    R180 S0      
317P0V8_PEX2        VIA   -    MD0100PA00X+136172Y+117942X0200Y    R180 S0      
317P0V8_PEX2        VIA   -    MD0100PA00X+135346Y+116238X0200Y         S0      
317P0V8_PEX2        VIA   -    MD0100PA00X+135346Y+116488X0200Y         S0      
317P0V8_PEX2        VIA   -    MD0100PA00X+135346Y+116738X0200Y         S0      
317P0V8_PEX2        VIA   -    MD0100PA00X+135346Y+116988X0200Y         S0      
317P0V8_PEX2        VIA   -    MD0100PA00X+135346Y+117238X0200Y         S0      
317P0V8_PEX2        VIA   -    MD0100PA00X+136404Y+119262X0200Y         S0      
317P0V8_PEX2        VIA   -    MD0100PA00X+136404Y+119012X0200Y         S0      
317P0V8_PEX2        VIA   -    MD0100PA00X+137173Y+117488X0200Y         S0      
317P0V8_PEX2        VIA   -    MD0100PA00X+136923Y+117488X0200Y         S0      
317P0V8_PEX2        VIA   -    MD0100PA00X+136923Y+116738X0200Y         S0      
317P0V8_PEX2        VIA   -    MD0100PA00X+136923Y+116488X0200Y         S0      
317P0V8_PEX2        VIA   -    MD0100PA00X+136923Y+116238X0200Y         S0      
317P0V8_PEX2        VIA   -    MD0100PA00X+137173Y+116238X0200Y         S0      
317P0V8_PEX2        VIA   -    MD0100PA00X+137709Y+110636X0200Y         S0      
317P0V8_PEX2        VIA   -    MD0100PA00X+137173Y+116488X0200Y         S0      
317P0V8_PEX2        VIA   -    MD0100PA00X+137173Y+116738X0200Y         S0      
317P0V8_PEX2        VIA   -    MD0100PA00X+137173Y+116988X0200Y         S0      
317P0V8_PEX2        VIA   -    MD0100PA00X+137173Y+117238X0200Y         S0      
317P0V8_PEX2        VIA   -    MD0100PA00X+136923Y+117238X0200Y         S0      
317P0V8_PEX2        VIA   -    MD0100PA00X+136923Y+116988X0200Y         S0      
327P0V8_PEX2        PEX2  -AF14       A01X+110787Y+116122X0180Y         S1      
327P0V8_PEX2        PEX2  -AC33       A01X+117894Y+117244X0180Y         S1      
327P0V8_PEX2        PEX2  -AC25       A01X+114902Y+117244X0180Y         S1      
327P0V8_PEX2        PEX2  -AA15       A01X+111161Y+117992X0180Y         S1      
327P0V8_PEX2        PEX2  -Y14 M      A01X+110787Y+118366X0180Y         S1      
327P0V8_PEX2        PEX2  -AC17       A01X+111909Y+117244X0180Y         S1      
327P0V8_PEX2        PEX2  -AD30M      A01X+116772Y+116870X0180Y         S1      
327P0V8_PEX2        PEX2  -AE29       A01X+116398Y+116496X0180Y         S1      
327P0V8_PEX2        PEX2  -AC31M      A01X+117146Y+117244X0180Y         S1      
327P0V8_PEX2        PEX2  -AE27       A01X+115650Y+116496X0180Y         S1      
327P0V8_PEX2        PEX2  -AC29M      A01X+116398Y+117244X0180Y         S1      
327P0V8_PEX2        PEX2  -AD28M      A01X+116024Y+116870X0180Y         S1      
327P0V8_PEX2        PEX2  -AE31       A01X+117146Y+116496X0180Y         S1      
327P0V8_PEX2        PEX2  -AC23M      A01X+114154Y+117244X0180Y         S1      
327P0V8_PEX2        PEX2  -AD24       A01X+114528Y+116870X0180Y         S1      
327P0V8_PEX2        PEX2  -AE25       A01X+114902Y+116496X0180Y         S1      
327P0V8_PEX2        PEX2  -AC27M      A01X+115650Y+117244X0180Y         S1      
327P0V8_PEX2        PEX2  -AD26       A01X+115276Y+116870X0180Y         S1      
327P0V8_PEX2        PEX2  -AE23       A01X+114154Y+116496X0180Y         S1      
327P0V8_PEX2        PEX2  -AD22M      A01X+113780Y+116870X0180Y         S1      
327P0V8_PEX2        PEX2  -AC21M      A01X+113405Y+117244X0180Y         S1      
327P0V8_PEX2        PEX2  -AE21       A01X+113405Y+116496X0180Y         S1      
327P0V8_PEX2        PEX2  -AD20M      A01X+113031Y+116870X0180Y         S1      
327P0V8_PEX2        PEX2  -AC19M      A01X+112657Y+117244X0180Y         S1      
327P0V8_PEX2        PEX2  -AD14M      A01X+110787Y+116870X0180Y         S1      
327P0V8_PEX2        PEX2  -AE15       A01X+111161Y+116496X0180Y         S1      
327P0V8_PEX2        PEX2  -AE17       A01X+111909Y+116496X0180Y         S1      
327P0V8_PEX2        PEX2  -AD16M      A01X+111535Y+116870X0180Y         S1      
327P0V8_PEX2        PEX2  -AC15M      A01X+111161Y+117244X0180Y         S1      
327P0V8_PEX2        PEX2  -AB14M      A01X+110787Y+117618X0180Y         S1      
327P0V8_PEX2        PEX2  -AE19       A01X+112657Y+116496X0180Y         S1      
327P0V8_PEX2        PEX2  -AD18M      A01X+112283Y+116870X0180Y         S1      
327P0V8_PEX2        PEX2  -AG33       A01X+117894Y+115748X0180Y         S1      
327P0V8_PEX2        PEX2  -AF30       A01X+116772Y+116122X0180Y         S1      
327P0V8_PEX2        PEX2  -AG31M      A01X+117146Y+115748X0180Y         S1      
327P0V8_PEX2        PEX2  -AG29M      A01X+116398Y+115748X0180Y         S1      
327P0V8_PEX2        PEX2  -AF28       A01X+116024Y+116122X0180Y         S1      
327P0V8_PEX2        PEX2  -AG27M      A01X+115650Y+115748X0180Y         S1      
327P0V8_PEX2        PEX2  -AF26       A01X+115276Y+116122X0180Y         S1      
327P0V8_PEX2        PEX2  -AG25       A01X+114902Y+115748X0180Y         S1      
327P0V8_PEX2        PEX2  -AG23M      A01X+114154Y+115748X0180Y         S1      
327P0V8_PEX2        PEX2  -AF24       A01X+114528Y+116122X0180Y         S1      
327P0V8_PEX2        PEX2  -AF22       A01X+113780Y+116122X0180Y         S1      
327P0V8_PEX2        PEX2  -AG21M      A01X+113405Y+115748X0180Y         S1      
327P0V8_PEX2        PEX2  -AF20       A01X+113031Y+116122X0180Y         S1      
327P0V8_PEX2        PEX2  -AG19M      A01X+112657Y+115748X0180Y         S1      
327P0V8_PEX2        PEX2  -AH14M      A01X+110787Y+115374X0180Y         S1      
327P0V8_PEX2        PEX2  -AG15M      A01X+111161Y+115748X0180Y         S1      
327P0V8_PEX2        PEX2  -AF16       A01X+111535Y+116122X0180Y         S1      
327P0V8_PEX2        PEX2  -AK14M      A01X+110787Y+114626X0180Y         S1      
327P0V8_PEX2        PEX2  -AJ15       A01X+111161Y+115000X0180Y         S1      
327P0V8_PEX2        PEX2  -AF18       A01X+112283Y+116122X0180Y         S1      
327P0V8_PEX2        PEX2  -AG17M      A01X+111909Y+115748X0180Y         S1      
327m3347            VIA   -    M      A18X+130177Y+129515X0260Y         S2      
327m3347            PJ23  -1          A18X+130974Y+129531X0200Y0400R090 S2      
317m3347            VIA   -    MD0080PA00X+119951Y+118927X0160Y         S0      
327m3347            PEX2  -W39        A01X+120138Y+118740X0180Y         S1      
327m3348            R838  -2          A01X+142319Y+103077X0198Y0197R180 S1      
327m3348            VIA   -    M      A01X+141040Y+102710X0300Y         S1      
327m3348            PU11  -20         A01X+139912Y+102439X0070Y0240R090 S1      
327m3348            C836  -2   M      A01X+141519Y+103077X0198Y0197R180 S1      
327P1V8_VDDA_PEX0   VIA   -           A18X+018248Y+119492X0260Y         S2      
327P1V8_VDDA_PEX0   C2995 -1   M      A18X+019019Y+119301X0120Y0150     S2      
327P1V8_VDDA_PEX0   C3011 -1          A18X+019347Y+119301X0120Y0150R180 S2      
327P1V8_VDDA_PEX0   C2988 -1          A18X+019117Y+118909X0280Y0320R090 S2      
327P1V8_VDDA_PEX0   VIA   -           A18X+028610Y+112810X0260Y         S2      
327P1V8_VDDA_PEX0   C2997 -1          A18X+027247Y+113317X0120Y0150     S2      
327P1V8_VDDA_PEX0   C2996 -1          A18X+027247Y+112943X0120Y0150     S2      
317P1V8_VDDA_PEX0   VIA   -    MD0080PA00X+028159Y+118179X0160Y         S0      
327P1V8_VDDA_PEX0   PEX0  -AA37       A01X+027972Y+117992X0180Y         S1      
327P1V8_VDDA_PEX0   C2989 -1          A18X+027995Y+118179X0120Y0150     S2      
327P1V8_VDDA_PEX0   C3012 -1          A18X+028323Y+118179X0120Y0150R180 S2      
327P1V8_VDDA_PEX0   C3010 -1          A18X+019265Y+113691X0120Y0150R180 S2      
327P1V8_VDDA_PEX0   C2998 -1          A18X+027411Y+120213X0120Y0150R270 S2      
327P1V8_VDDA_PEX0   C3014 -1          A18X+027411Y+119885X0120Y0150R090 S2      
327P1V8_VDDA_PEX0   C3013 -1          A18X+027119Y+118179X0120Y0150R180 S2      
327P1V8_VDDA_PEX0   VIA   -           A18X+016899Y+117009X0260Y         S2      
317P1V8_VDDA_PEX0   VIA   -    MD0080PA00X+017687Y+118179X0160Y         S0      
317P1V8_VDDA_PEX0   VIA   -    MD0080PA00X+017687Y+117805X0160Y         S0      
317P1V8_VDDA_PEX0   VIA   -    MD0080PA00X+017687Y+117431X0160Y         S0      
317P1V8_VDDA_PEX0   VIA   -    MD0080PA00X+019183Y+119301X0160Y    R270 S0      
317P1V8_VDDA_PEX0   VIA   -    MD0080PA00X+019183Y+113691X0160Y         S0      
317P1V8_VDDA_PEX0   VIA   -    MD0080PA00X+027411Y+112943X0160Y         S0      
317P1V8_VDDA_PEX0   VIA   -    MD0080PA00X+027411Y+120049X0160Y    R180 S0      
317P1V8_VDDA_PEX0   VIA   -    MD0080PA00X+027037Y+118179X0160Y         S0      
327P1V8_VDDA_PEX0   C3070 -1          A01X+010267Y+102766X0280Y0320R090 S1      
327P1V8_VDDA_PEX0   L97   -2          A01X+010396Y+102178X0440Y0540R270 S1      
327P1V8_VDDA_PEX0   R4567 -1          A01X+010823Y+102736X0198Y0197     S1      
317P1V8_VDDA_PEX0   VIA   -    MD0100PA00X+010597Y+102574X0200Y         S0      
327P1V8_VDDA_PEX0   C3072 -1          A18X+010001Y+102103X0120Y0150     S2      
327P1V8_VDDA_PEX0   C3071 -1          A18X+009994Y+102414X0120Y0150     S2      
327P1V8_VDDA_PEX0   PEX0  -T35        A01X+027224Y+119862X0180Y         S1      
327P1V8_VDDA_PEX0   PEX0  -V14        A01X+019370Y+119114X0180Y         S1      
327P1V8_VDDA_PEX0   PEX0  -AA34       A01X+026850Y+117992X0180Y         S1      
327P1V8_VDDA_PEX0   PEX0  -AM14       A01X+019370Y+113878X0180Y         S1      
327P1V8_VDDA_PEX0   PEX0  -AP35       A01X+027224Y+113130X0180Y         S1      
327P1V8_VDDA_PEX0   C3009 -1          A18X+017605Y+117805X0120Y0150     S2      
327P1V8_VDDA_PEX0   C3008 -1          A18X+017605Y+118179X0120Y0150     S2      
327P1V8_VDDA_PEX0   C3007 -1   M      A18X+017605Y+117431X0120Y0150     S2      
327P1V8_VDDA_PEX0   PEX0  -AA10M      A01X+017874Y+117992X0180Y         S1      
327P1V8_VDDA_PEX0   PEX0  -AB10M      A01X+017874Y+117618X0180Y         S1      
327P1V8_VDDA_PEX0   PEX0  -AC10       A01X+017874Y+117244X0180Y         S1      
327m3349            R837  -2          A01X+140226Y+099534X0198Y0197R090 S1      
327m3349            PU11  -9          A01X+139518Y+100785X0070Y0240     S1      
327m3349            VIA   -    M      A01X+139867Y+100147X0300Y         S1      
317m3350            VIA   -    MD0100PA00X+049058Y+110690X0200Y    R090 S0      
327m3350            PU9   -38         A01X+048886Y+111023X0090Y0240R180 S1      
327m3350            PU6   -30         A01X+046841Y+102675X0070Y0240     S1      
317m3350            VIA   -    M      A01X+047176Y+103866X0200Y    R090 S2      
017m3350            VIA   -    M      A18X+047176Y+103866X0260Y    R090 S2      
017m3350                  -    MD0100PA00X+047176Y+103866                       
317P0V8_PEX2_VDD    VIA   -    MD0100PA00X+137353Y+100468X0200Y         S0      
327P0V8_PEX2_VDD    VIA   -           A18X+137353Y+099676X0260Y    R090 S2      
327P0V8_PEX2_VDD    PC124 -1          A18X+137348Y+100732X0198Y0197R180 S2      
327P0V8_PEX2_VDD    PR116 -2   M      A18X+137353Y+100218X0198Y0197R180 S2      
327P0V8_PEX2_VDD    PU11  -39         A01X+138022Y+101179X0070Y0240R090 S1      
327P0V8_PEX2_VDD    PC126 -1   M      A01X+137353Y+100718X0198Y0197R180 S1      
327m3351            PR144 -1          A18X+137055Y+102362X0198Y0197R270 S2      
317m3351            VIA   -    M      A01X+137406Y+101886X0200Y         S2      
017m3351            VIA   -    M      A18X+137406Y+101886X0260Y         S2      
017m3351                  -    MD0100PA00X+137406Y+101886                       
327m3351            PU11  -35         A01X+138022Y+101809X0070Y0240R090 S1      
327m3351            PC135 -1   M      A18X+137455Y+102362X0198Y0197R270 S2      
327m3352            VIA   -    M      A18X+129679Y+129122X0260Y         S2      
327m3352            PJ22  -1          A18X+130974Y+129111X0200Y0400R090 S2      
317m3352            VIA   -    MD0080PA00X+120325Y+118927X0160Y         S0      
327m3352            PEX2  -V39        A01X+120138Y+119114X0180Y         S1      
327m3353            PR7170-2          A01X+141519Y+102025X0198Y0197R180 S1      
327m3353            VIA   -    M      A01X+140622Y+102049X0300Y         S1      
327m3353            PU11  -19         A01X+139912Y+102282X0070Y0240R090 S1      
327m3354            VIA   -    M      A18X+136976Y+101582X0260Y         S2      
317m3354            VIA   -    MD0100PA00X+137403Y+101582X0200Y         S0      
327m3354            PR143 -1          A01X+137103Y+101632X0198Y0197R180 S1      
327m3354            PU11  -37         A01X+138022Y+101494X0070Y0240R090 S1      
327m3354            PC134 -1   M      A18X+136476Y+101419X0198Y0197R270 S2      
327m3354            PR142 -2          A18X+135776Y+101419X0198Y0197R090 S2      
327m3354            PR145 -2   M      A18X+136126Y+101419X0198Y0197R090 S2      
327P0V8_PEX2_VCC2   PR152 -2   M      A18X+137509Y+111582X0198Y0197R090 S2      
317P0V8_PEX2_VCC2   VIA   -    MD0100PA00X+137778Y+111590X0200Y         S0      
327P0V8_PEX2_VCC2   PU13  -3          A01X+137296Y+111624X0090Y0240R270 S1      
327P0V8_PEX2_VCC2   PC155 -1   M      A01X+137759Y+111347X0198Y0197R270 S1      
327P0V8_PEX2_VCC2   R6767 -1   M      A18X+137179Y+111247X0198Y0197R090 S2      
327P0V8_PEX2_VCC2   PR7172-2          A18X+136782Y+111120X0198Y0197R180 S2      
327m3355            PC162 -1          A01X+135697Y+110570X0198Y0197R270 S1      
327m3355            PU13  -32         A01X+135895Y+111023X0090Y0240R180 S1      
327P0V8_PEX2_VCC1   PR148 -2   M      A18X+134296Y+111582X0198Y0197R090 S2      
317P0V8_PEX2_VCC1   VIA   -    MD0100PA00X+134565Y+111590X0200Y         S0      
327P0V8_PEX2_VCC1   PU12  -3          A01X+134083Y+111624X0090Y0240R270 S1      
327P0V8_PEX2_VCC1   PC145 -1   M      A01X+134546Y+111347X0198Y0197R270 S1      
327P0V8_PEX2_VCC1   R6766 -1   M      A18X+133968Y+111247X0198Y0197R090 S2      
327P0V8_PEX2_VCC1   PR7171-2          A18X+133560Y+111120X0198Y0197R180 S2      
327m3356            PU12  -10_1       A01X+133138Y+113307X0240Y1700R270 S1      
327m3356            PL12  -1          A01X+133324Y+114354X1220Y1320R180 S1      
327m3357            PR149 -2          A01X+132863Y+110256X0198Y0197R270 S1      
327m3357            PC146 -2          A01X+132484Y+110256X0198Y0197R270 S1      
327m3358            PU8   -31         A01X+044300Y+111023X0090Y0240R180 S1      
327m3359            PU7   -6          A01X+042666Y+112155X0090Y0240R270 S1      
327m3360            PR149 -1          A01X+132863Y+110570X0198Y0197R270 S1      
327m3360            PU12  -33         A01X+132859Y+111023X0090Y0240R180 S1      
327m3361            PU8   -6          A01X+045879Y+112155X0090Y0240R270 S1      
327m3362            PR153 -2          A01X+136076Y+110256X0198Y0197R270 S1      
327m3362            PC162 -2          A01X+135697Y+110256X0198Y0197R270 S1      
327m3363            PR154 -1          A18X+137709Y+111197X0198Y0197R090 S2      
327m3363            PU13  -1          A01X+137296Y+111269X0090Y0240R270 S1      
317m3363            VIA   -    MD0100PA00X+137411Y+111009X0200Y         S0      
317m3364            X9    -1    D0098PA00X+005625Y+179694X0395Y    R180 S3      
317m3364            X8    -4    D0098PA00X+030835Y+179694X0395Y         S3      
327m3365            PC146 -1          A01X+132484Y+110570X0198Y0197R270 S1      
327m3365            PU12  -32         A01X+132682Y+111023X0090Y0240R180 S1      
327m3366            PU7   -31         A01X+041087Y+111023X0090Y0240R180 S1      
317m3367            J51   -3    D0670PA00X+125005Y+176838X0850Y    R270 S3      
317m3367            J51   -2    D0670PA00X+125005Y+177838X0850Y    R270 S3      
327m3368            PR151 -1          A01X+133671Y+110192X0198Y0197R270 S1      
317m3368            VIA   -    M      A01X+133751Y+110434X0200Y         S2      
017m3368            VIA   -    M      A18X+133751Y+110434X0260Y         S2      
017m3368                  -    MD0100PA00X+133751Y+110434                       
327m3368            PU12  -37         A01X+133568Y+111023X0090Y0240R180 S1      
327m3369            PU7   -41         A01X+042322Y+112263X0120Y0180R090 S1      
327m3370            PR150 -1          A18X+134496Y+111197X0198Y0197R090 S2      
327m3370            PU12  -1          A01X+134083Y+111269X0090Y0240R270 S1      
317m3370            VIA   -    MD0100PA00X+134198Y+111009X0200Y         S0      
317m3371            X62   -1    D0098PA00X+005635Y+173794X0395Y         S3      
317m3371            X63   -4    D0098PA00X+030845Y+173794X0395Y    R180 S3      
327m3372            PR153 -1          A01X+136076Y+110570X0198Y0197R270 S1      
327m3372            PU13  -33         A01X+136072Y+111023X0090Y0240R180 S1      
327m3373            PU13  -10_1       A01X+136351Y+113307X0240Y1700R270 S1      
327m3373            PL13  -1          A01X+136106Y+114354X1220Y1320R180 S1      
327m3374            PR155 -1          A01X+136883Y+110192X0198Y0197R270 S1      
317m3374            VIA   -    M      A01X+136964Y+110434X0200Y         S2      
017m3374            VIA   -    M      A18X+136964Y+110434X0260Y         S2      
017m3374                  -    MD0100PA00X+136964Y+110434                       
327m3374            PU13  -37         A01X+136780Y+111023X0090Y0240R180 S1      
327P1V2_AUX         C2020 -1          A18X+095505Y+081883X0280Y0320R270 S2      
327P1V2_AUX         C2015 -1          A18X+095505Y+081334X0280Y0320R270 S2      
327P1V2_AUX         C2016 -1          A18X+095505Y+080786X0280Y0320R270 S2      
317P1V2_AUX         VIA   -    MD0100PA00X+007773Y+109568X0200Y         S0      
317P1V2_AUX         VIA   -    MD0100PA00X+005844Y+127226X0200Y         S0      
327P1V2_AUX         L151  -2          A18X+005104Y+154384X0440Y0540R090 S2      
317P1V2_AUX         VIA   -    MD0100PA00X+016319Y+106531X0200Y         S0      
317P1V2_AUX         VIA   -    MD0100PA00X+008637Y+084809X0200Y         S0      
327P1V2_AUX         U342  -1          A01X+099523Y+084620X0110Y0360R270 S1      
327P1V2_AUX         U342  -3          A01X+099523Y+084226X0110Y0360R270 S1      
327P1V2_AUX         U342  -2          A01X+099523Y+084423X0110Y0360R270 S1      
327P1V2_AUX         C2851 -1          A01X+098270Y+084860X0198Y0197R180 S1      
327P1V2_AUX         C2850 -1          A01X+098370Y+084266X0400Y0500     S1      
317P1V2_AUX         VIA   -    MD0100PA00X+098720Y+084894X0200Y         S0      
317P1V2_AUX         VIA   -    MD0100PA00X+098980Y+084390X0200Y    R090 S0      
327P1V2_AUX         R4432 -1          A01X+098163Y+083316X0198Y0197     S1      
317P1V2_AUX         VIA   -    MD0100PA00X+097920Y+083316X0200Y         S0      
317P1V2_AUX         VIA   -    MD0100PA00X+098732Y+084359X0200Y         S0      
317P1V2_AUX         VIA   -    MD0100PA00X+098720Y+084640X0200Y         S0      
317P1V2_AUX         VIA   -    MD0100PA00X+098970Y+084650X0200Y    R090 S0      
327P1V2_AUX         R4879 -1          A18X+083664Y+085794X0198Y0197R270 S2      
327P1V2_AUX         R4875 -1          A01X+083640Y+086357X0198Y0197R270 S1      
327P1V2_AUX         R4873 -1   M      A01X+084016Y+086341X0198Y0197     S1      
327P1V2_AUX         R4874 -1   M      A01X+084016Y+086741X0198Y0197     S1      
317P1V2_AUX         VIA   -    MD0100PA00X+083700Y+086741X0200Y         S0      
317P1V2_AUX         VIA   -    MD0100PA00X+083819Y+084749X0200Y         S0      
317P1V2_AUX         VIA   -    MD0100PA00X+084023Y+085146X0200Y         S0      
327P1V2_AUX         R4855 -1          A01X+094784Y+087822X0198Y0197R180 S1      
317P1V2_AUX         VIA   -    MD0100PA00X+095030Y+087780X0200Y         S0      
317P1V2_AUX         VIA   -    MD0100PA00X+091286Y+087364X0180Y    R270 S0      
327P1V2_AUX         U5    -M6         A01X+091129Y+087206X0160Y    R180 S1      
317P1V2_AUX         VIA   -    MD0100PA00X+090656Y+087679X0180Y    R270 S0      
327P1V2_AUX         U5    -N8         A01X+090499Y+087521X0160Y    R180 S1      
327P1V2_AUX         C2014 -1          A18X+090499Y+087521X0164Y0164R090 S2      
317P1V2_AUX         VIA   -    MD0100PA00X+090027Y+087679X0180Y    R270 S0      
327P1V2_AUX         U5    -N9         A01X+090184Y+087521X0160Y    R180 S1      
327P1V2_AUX         C2017 -1          A18X+090184Y+087521X0164Y0164R090 S2      
317P1V2_AUX         VIA   -    MD0100PA00X+089082Y+086734X0180Y    R270 S0      
327P1V2_AUX         U5    -K12        A01X+089239Y+086576X0160Y    R180 S1      
317P1V2_AUX         VIA   -    MD0100PA00X+091601Y+085474X0180Y    R270 S0      
327P1V2_AUX         U5    -G5         A01X+091444Y+085632X0160Y    R180 S1      
317P1V2_AUX         VIA   -    MD0100PA00X+091601Y+085789X0180Y    R270 S0      
327P1V2_AUX         U5    -H5         A01X+091444Y+085946X0160Y    R180 S1      
327P1V2_AUX         C2019 -1          A18X+091444Y+085946X0164Y0164     S2      
317P1V2_AUX         VIA   -    MD0100PA00X+090656Y+085159X0180Y    R270 S0      
327P1V2_AUX         U5    -F8         A01X+090499Y+085317X0160Y    R180 S1      
317P1V2_AUX         VIA   -    MD0100PA00X+090027Y+085159X0180Y    R270 S0      
327P1V2_AUX         U5    -F9         A01X+090184Y+085317X0160Y    R180 S1      
327P1V2_AUX         C3623 -1          A18X+090184Y+085317X0164Y0164R270 S2      
317P1V2_AUX         VIA   -    MD0100PA00X+089082Y+085789X0180Y    R270 S0      
327P1V2_AUX         U5    -H12        A01X+089239Y+085946X0160Y    R180 S1      
327P1V2_AUX         C2013 -1          A18X+089239Y+085946X0164Y0164R180 S2      
317P1V2_AUX         VIA   -    MD0100PA00X+089082Y+086419X0180Y    R270 S0      
327P1V2_AUX         U5    -J12        A01X+089239Y+086262X0160Y    R180 S1      
327P1V2_AUX         C2018 -1          A18X+089239Y+086262X0164Y0164R180 S2      
317P1V2_AUX         VIA   -    MD0100PA00X+089712Y+085159X0180Y    R270 S0      
327P1V2_AUX         U5    -F10        A01X+089869Y+085317X0160Y    R180 S1      
327P1V2_AUX         R4862 -1          A18X+084029Y+085540X0198Y0197R180 S2      
317P1V2_AUX         VIA   -    MD0100PA00X+083718Y+085546X0200Y         S0      
317P1V2_AUX         VIA   -    MD0100PA00X+094430Y+083998X0200Y         S0      
317P1V2_AUX         VIA   -    MD0100PA00X+094072Y+084007X0200Y         S0      
327P1V2_AUX         L146  -1          A18X+094203Y+084395X0280Y0320R090 S2      
327P1V2_AUX         R4854 -1          A18X+094199Y+085406X0198Y0197R270 S2      
327P1V2_AUX         L1    -2          A18X+094193Y+084937X0280Y0320R270 S2      
327P1V2_AUX         R475  -1          A18X+093512Y+083438X0198Y0197R270 S2      
317P1V2_AUX         VIA   -    MD0100PA00X+093512Y+083138X0200Y         S0      
327P1V2_AUX         C2706 -2   M      A01X+083008Y+082050X0198Y0197     S1      
317P1V2_AUX         VIA   -    M      A01X+083008Y+082300X0200Y         S2      
017P1V2_AUX         VIA   -    M      A18X+083008Y+082300X0260Y         S2      
017P1V2_AUX               -    MD0100PA00X+083008Y+082300                       
327P1V2_AUX         U119  -1          A01X+083670Y+081984X0140Y0590R270 S1      
317P1V2_AUX         VIA   -    MD0100PA00X+095179Y+080812X0200Y         S0      
317P1V2_AUX         VIA   -    MD0100PA00X+095146Y+081222X0200Y         S0      
317P1V2_AUX         VIA   -    MD0100PA00X+095171Y+081889X0200Y         S0      
327P1V2_AUX         R1512 -2   M      A01X+082692Y+081250X0198Y0197R180 S1      
327P1V2_AUX         R1511 -2          A01X+082692Y+081650X0198Y0197R180 S1      
317P1V2_AUX         VIA   -    MD0100PA00X+082450Y+081450X0200Y         S0      
327P1V2_AUX         C2556 -2   M      A01X+083008Y+080250X0198Y0197     S1      
317P1V2_AUX         VIA   -    M      A01X+083008Y+080500X0200Y         S2      
017P1V2_AUX         VIA   -    M      A18X+083008Y+080500X0260Y         S2      
017P1V2_AUX               -    MD0100PA00X+083008Y+080500                       
327P1V2_AUX         U120  -1          A01X+083670Y+080184X0140Y0590R270 S1      
327P1V2_AUX         R1518 -2          A01X+082692Y+079850X0198Y0197R180 S1      
327P1V2_AUX         R1519 -2   M      A01X+082692Y+079450X0198Y0197R180 S1      
317P1V2_AUX         VIA   -    MD0100PA00X+082450Y+079650X0200Y         S0      
317P1V2_AUX         VIA   -    M      A01X+083008Y+078700X0200Y         S2      
017P1V2_AUX         VIA   -    M      A18X+083008Y+078700X0260Y         S2      
017P1V2_AUX               -    MD0100PA00X+083008Y+078700                       
327P1V2_AUX         U121  -1          A01X+083670Y+078384X0140Y0590R270 S1      
327P1V2_AUX         C2626 -2   M      A01X+083008Y+078450X0198Y0197     S1      
317P1V2_AUX         VIA   -           A01X+081800Y+079700X0200Y         S2      
017P1V2_AUX         VIA   -           A18X+081800Y+079700X0260Y         S2      
017P1V2_AUX               -     D0100PA00X+081800Y+079700                       
327P1V2_AUX         R1525 -2          A01X+082692Y+078050X0198Y0197R180 S1      
317P1V2_AUX         VIA   -    MD0100PA00X+082450Y+077850X0200Y         S0      
327P1V2_AUX         R1526 -2   M      A01X+082692Y+077650X0198Y0197R180 S1      
317P1V2_AUX         VIA   -    M      A01X+083008Y+076900X0200Y         S2      
017P1V2_AUX         VIA   -    M      A18X+083008Y+076900X0260Y         S2      
017P1V2_AUX               -    MD0100PA00X+083008Y+076900                       
327P1V2_AUX         U122  -1          A01X+083670Y+076584X0140Y0590R270 S1      
327P1V2_AUX         C2628 -2   M      A01X+083008Y+076650X0198Y0197     S1      
327P1V2_AUX         R1532 -2          A01X+082692Y+076250X0198Y0197R180 S1      
317P1V2_AUX         VIA   -    MD0100PA00X+082450Y+076050X0200Y         S0      
327P1V2_AUX         R1533 -2   M      A01X+082692Y+075850X0198Y0197R180 S1      
327P1V2_AUX         R4878 -1          A01X+084069Y+084379X0198Y0197     S1      
327P1V2_AUX         R4880 -1   M      A01X+084069Y+084749X0198Y0197     S1      
327P1V2_AUX         R4876 -1   M      A01X+084029Y+085540X0198Y0197     S1      
327P1V2_AUX         R4877 -1          A01X+084273Y+085146X0198Y0197     S1      
317m3375            X57   -4    D0098PA00X+034311Y+175162X0395Y         S3      
317m3375            X56   -1    D0098PA00X+059531Y+175162X0395Y    R180 S3      
327m3376            PU8   -41         A01X+045534Y+112263X0120Y0180R090 S1      
317m3377            J49   -2    D0670PA00X+173407Y+180791X0850Y    R090 S3      
317m3377            J49   -3    D0670PA00X+173407Y+179791X0850Y    R090 S3      
317COUPON_GND1      X27   -3   MD0098PA00X+060531Y+180762X0785Y    R180 S3      
317COUPON_GND1      X27   -2   MD0098PA00X+060531Y+179762X0785Y    R180 S3      
317COUPON_GND1      X21   -3   MD0098PA00X+060531Y+177462X0785Y         S3      
317COUPON_GND1      X21   -2   MD0098PA00X+060531Y+178462X0785Y         S3      
317COUPON_GND1      X56   -3   MD0098PA00X+060531Y+176162X0785Y    R180 S3      
317COUPON_GND1      X56   -2   MD0098PA00X+060531Y+175162X0785Y    R180 S3      
317COUPON_GND1      X15   -3   MD0098PA00X+060539Y+172858X0785Y         S3      
317COUPON_GND1      X15   -2   MD0098PA00X+060539Y+173858X0785Y         S3      
317COUPON_GND1      X26   -3   MD0098PA00X+033321Y+179762X0785Y         S3      
317COUPON_GND1      X26   -2   MD0098PA00X+033321Y+180762X0785Y         S3      
317COUPON_GND1      X20   -3   MD0098PA00X+033321Y+178462X0785Y    R180 S3      
317COUPON_GND1      X20   -2   MD0098PA00X+033321Y+177462X0785Y    R180 S3      
317COUPON_GND1      X57   -3   MD0098PA00X+033311Y+175162X0785Y         S3      
317COUPON_GND1      X57   -2   MD0098PA00X+033311Y+176162X0785Y         S3      
317COUPON_GND1      X14   -3   MD0098PA00X+033329Y+173858X0785Y    R180 S3      
317COUPON_GND1      X14   -2   MD0098PA00X+033329Y+172858X0785Y    R180 S3      
317COUPON_GND1      J49   -1   MD0670PA00X+174725Y+180291X0850Y    R090 S3      
317COUPON_GND1      J50   -1   MD0670PA00X+123537Y+180291X0850Y    R270 S3      
317COUPON_GND1      X69   -3   MD0098PA00X+117912Y+177601X0785Y         S3      
317COUPON_GND1      X69   -2   MD0098PA00X+117912Y+178601X0785Y         S3      
317COUPON_GND1      X81   -3   MD0098PA00X+117926Y+176257X0785Y    R180 S3      
317COUPON_GND1      X81   -2   MD0098PA00X+117926Y+175257X0785Y    R180 S3      
317COUPON_GND1      X68   -3   MD0098PA00X+090707Y+178601X0785Y    R180 S3      
317COUPON_GND1      X68   -2   MD0098PA00X+090707Y+177601X0785Y    R180 S3      
317COUPON_GND1      X80   -3   MD0098PA00X+090716Y+175257X0785Y         S3      
317COUPON_GND1      X80   -2   MD0098PA00X+090716Y+176257X0785Y         S3      
317COUPON_GND1      X72   -3   MD0098PA00X+117933Y+172899X0785Y         S3      
317COUPON_GND1      X72   -2   MD0098PA00X+117933Y+173899X0785Y         S3      
317COUPON_GND1      X73   -3   MD0098PA00X+090728Y+173899X0785Y    R180 S3      
317COUPON_GND1      X73   -2   MD0098PA00X+090728Y+172899X0785Y    R180 S3      
317COUPON_GND1      X79   -3   MD0098PA00X+089152Y+180884X0785Y    R180 S3      
317COUPON_GND1      X79   -2   MD0098PA00X+089152Y+179884X0785Y    R180 S3      
317COUPON_GND1      X70   -3   MD0098PA00X+089176Y+177544X0785Y         S3      
317COUPON_GND1      X70   -2   MD0098PA00X+089176Y+178544X0785Y         S3      
317COUPON_GND1      X77   -3   MD0098PA00X+089191Y+176176X0785Y    R180 S3      
317COUPON_GND1      X77   -2   MD0098PA00X+089191Y+175176X0785Y    R180 S3      
317COUPON_GND1      X67   -3   MD0098PA00X+089218Y+172829X0785Y         S3      
317COUPON_GND1      X67   -2   MD0098PA00X+089218Y+173829X0785Y         S3      
317COUPON_GND1      X74   -3   MD0098PA00X+117922Y+181044X0785Y    R180 S3      
317COUPON_GND1      X74   -2   MD0098PA00X+117922Y+180044X0785Y    R180 S3      
317COUPON_GND1      X78   -3   MD0098PA00X+061948Y+179884X0785Y         S3      
317COUPON_GND1      X78   -2   MD0098PA00X+061948Y+180884X0785Y         S3      
317COUPON_GND1      X71   -3   MD0098PA00X+061971Y+178544X0785Y    R180 S3      
317COUPON_GND1      X71   -2   MD0098PA00X+061971Y+177544X0785Y    R180 S3      
317COUPON_GND1      X76   -3   MD0098PA00X+061986Y+175176X0785Y         S3      
317COUPON_GND1      X76   -2   MD0098PA00X+061986Y+176176X0785Y         S3      
317COUPON_GND1      X66   -3   MD0098PA00X+062008Y+173829X0785Y    R180 S3      
317COUPON_GND1      X66   -2   MD0098PA00X+062008Y+172829X0785Y    R180 S3      
317COUPON_GND1      X75   -3   MD0098PA00X+090717Y+180044X0785Y         S3      
317COUPON_GND1      X75   -2   MD0098PA00X+090717Y+181044X0785Y         S3      
317COUPON_GND1      J52   -1   MD0670PA00X+174725Y+177338X0850Y    R090 S3      
317COUPON_GND1      J48   -1   MD0670PA00X+174725Y+174421X0850Y    R090 S3      
317COUPON_GND1      J46   -1   MD0670PA00X+174725Y+171519X0850Y    R090 S3      
317COUPON_GND1      J47   -1   MD0670PA00X+123687Y+174421X0850Y    R270 S3      
317COUPON_GND1      J51   -1   MD0670PA00X+123686Y+177338X0850Y    R270 S3      
317COUPON_GND1      J53   -1   MD0670PA00X+123687Y+171519X0850Y    R270 S3      
317COUPON_GND1      X8    -3   MD0098PA00X+031835Y+179694X0785Y         S3      
317COUPON_GND1      X8    -2   MD0098PA00X+031835Y+180694X0785Y         S3      
317COUPON_GND1      X3    -3   MD0098PA00X+031845Y+175094X0785Y         S3      
317COUPON_GND1      X3    -2   MD0098PA00X+031845Y+176094X0785Y         S3      
317COUPON_GND1      X65   -3   MD0098PA00X+031845Y+178394X0785Y    R180 S3      
317COUPON_GND1      X65   -2   MD0098PA00X+031845Y+177394X0785Y    R180 S3      
317COUPON_GND1      X63   -3   MD0098PA00X+031845Y+173794X0785Y    R180 S3      
317COUPON_GND1      X63   -2   MD0098PA00X+031845Y+172794X0785Y    R180 S3      
317COUPON_GND1      X9    -3   MD0098PA00X+004625Y+180694X0785Y    R180 S3      
317COUPON_GND1      X9    -2   MD0098PA00X+004625Y+179694X0785Y    R180 S3      
317COUPON_GND1      X64   -3   MD0098PA00X+004635Y+177394X0785Y         S3      
317COUPON_GND1      X64   -2   MD0098PA00X+004635Y+178394X0785Y         S3      
317COUPON_GND1      X2    -3   MD0098PA00X+004625Y+176094X0785Y    R180 S3      
317COUPON_GND1      X2    -2   MD0098PA00X+004625Y+175094X0785Y    R180 S3      
317COUPON_GND1      X62   -3   MD0098PA00X+004635Y+172794X0785Y         S3      
317COUPON_GND1      X62   -2   MD0098PA00X+004635Y+173794X0785Y         S3      
317m3378            J53   -3    D0670PA00X+125006Y+171019X0850Y    R270 S3      
317m3378            J53   -2    D0670PA00X+125006Y+172019X0850Y    R270 S3      
317m3379            X2    -4    D0098PA00X+005625Y+176094X0395Y    R180 S3      
317m3379            X3    -1    D0098PA00X+030845Y+176094X0395Y         S3      
317m3380            J48   -3    D0670PA00X+173407Y+174921X0850Y    R090 S3      
317m3380            J48   -2    D0670PA00X+173407Y+173921X0850Y    R090 S3      
317m3381            X26   -4    D0098PA00X+034321Y+179762X0395Y         S3      
317m3381            X27   -1    D0098PA00X+059531Y+179762X0395Y    R180 S3      
317m3382            X64   -4    D0098PA00X+005635Y+177394X0395Y         S3      
317m3382            X65   -1    D0098PA00X+030845Y+177394X0395Y    R180 S3      
317m3383            X26   -1    D0098PA00X+034321Y+180762X0395Y         S3      
317m3383            X27   -4    D0098PA00X+059531Y+180762X0395Y    R180 S3      
317m3384            J47   -2    D0670PA00X+125006Y+173921X0850Y    R270 S3      
317m3384            J47   -3    D0670PA00X+125006Y+174921X0850Y    R270 S3      
317m3385            X14   -4    D0098PA00X+034329Y+173858X0395Y    R180 S3      
317m3385            X15   -1    D0098PA00X+059539Y+173858X0395Y         S3      
317m3386            X2    -1    D0098PA00X+005625Y+175094X0395Y    R180 S3      
317m3386            X3    -4    D0098PA00X+030845Y+175094X0395Y         S3      
317m3387            X20   -1    D0098PA00X+034321Y+177462X0395Y    R180 S3      
317m3387            X21   -4    D0098PA00X+059531Y+177462X0395Y         S3      
317m3388            J50   -2    D0670PA00X+124856Y+180791X0850Y    R270 S3      
317m3388            J50   -3    D0670PA00X+124856Y+179791X0850Y    R270 S3      
317m3389            X9    -4    D0098PA00X+005625Y+180694X0395Y    R180 S3      
317m3389            X8    -1    D0098PA00X+030835Y+180694X0395Y         S3      
327P1V25_PEX0_CS    PU16  -3          A01X+004576Y+120268X0070Y0320R270 S1      
317P1V25_PEX0_CS    VIA   -    M      A01X+005102Y+120142X0200Y         S2      
017P1V25_PEX0_CS    VIA   -    M      A18X+005102Y+120142X0260Y         S2      
017P1V25_PEX0_CS          -    MD0100PA00X+005102Y+120142                       
327P1V25_PEX0_CS    PR167 -1          A01X+005374Y+119998X0198Y0197R270 S1      
327P1V25_PEX0_VCC   PU16  -19         A01X+003473Y+119914X0120Y0320R090 S1      
327P1V25_PEX0_VCC   R841  -1          A18X+006398Y+121205X0198Y0197R270 S2      
327P1V25_PEX0_VCC   PC220 -1          A01X+002913Y+119862X0198Y0197R090 S1      
317P1V25_PEX0_VCC   VIA   -    M      A01X+003163Y+119865X0200Y         S2      
017P1V25_PEX0_VCC   VIA   -    M      A18X+003163Y+119865X0260Y         S2      
017P1V25_PEX0_VCC         -    MD0100PA00X+003163Y+119865                       
327m3390            PU16  -6          A01X+004576Y+120741X0070Y0320R270 S1      
317m3390            VIA   -    M      A01X+005519Y+120518X0200Y         S2      
017m3390            VIA   -    M      A18X+005519Y+120518X0260Y         S2      
017m3390                  -    MD0100PA00X+005519Y+120518                       
327m3390            PJ10  -1          A01X+006538Y+120156X0200Y0400R090 S1      
327m3390            PC978 -2   M      A01X+006138Y+120240X0198Y0197R270 S1      
327m3390            PC222 -2   M      A01X+005755Y+120581X0198Y0197R090 S1      
327m3390            PR168 -1   M      A01X+005306Y+120679X0198Y0197R090 S1      
317m3391            X62   -4    D0098PA00X+005635Y+172794X0395Y         S3      
317m3391            X63   -1    D0098PA00X+030845Y+172794X0395Y    R180 S3      
327m3392            PU16  -10         A01X+004142Y+121095X0120Y0790R180 S1      
327m3392            PU16  -21         A01X+004142Y+120072X0120Y0790R180 S1      
327m3392            PC1007-1          A01X+004141Y+124120X0400Y0500     S1      
327m3392            PL17  -2          A01X+004742Y+124262X0280Y0320R180 S1      
327m3392            PC205 -1          A01X+004141Y+123430X0400Y0500     S1      
327m3392            PC208 -1          A01X+004141Y+122740X0400Y0500     S1      
327m3392            PC206 -1          A01X+004775Y+122889X0400Y0500R180 S1      
327m3392            PC207 -1          A01X+004775Y+123579X0400Y0500R180 S1      
327m3392            PC204 -1          A01X+004141Y+122050X0400Y0500     S1      
327m3392            PC209 -1          A01X+004775Y+122199X0400Y0500R180 S1      
327m3392            PC210 -1          A01X+004181Y+119326X0198Y0197     S1      
317m3393            J52   -3    D0670PA00X+173406Y+177838X0850Y    R090 S3      
317m3393            J52   -2    D0670PA00X+173406Y+176838X0850Y    R090 S3      
327m3394            PU16  -9          A01X+004576Y+121253X0120Y0320R270 S1      
327m3394            R4435 -2          A18X+006401Y+121950X0198Y0197R090 S2      
327m3394            R841  -2   M      A18X+006398Y+121520X0198Y0197R270 S2      
317m3394            VIA   -    M      A01X+005348Y+121626X0200Y         S2      
017m3394            VIA   -    M      A18X+005348Y+121626X0260Y         S2      
017m3394                  -    MD0100PA00X+005348Y+121626                       
317m3395            X20   -4    D0098PA00X+034321Y+178462X0395Y    R180 S3      
317m3395            X21   -1    D0098PA00X+059531Y+178462X0395Y         S3      
327m3396            PU16  -20         A01X+003906Y+120072X0120Y0790R180 S1      
327m3396            PC211 -2          A01X+005200Y+119225X0198Y0197     S1      
327m3396            PL18  -1          A01X+003796Y+118065X1160Y1460R270 S1      
317m3397            J46   -3    D0670PA00X+173407Y+172019X0850Y    R090 S3      
317m3397            J46   -2    D0670PA00X+173407Y+171019X0850Y    R090 S3      
327P1V25_PEX0_FB    PU16  -7          A01X+004576Y+120898X0070Y0320R270 S1      
317P1V25_PEX0_FB    VIA   -    M      A01X+005560Y+121047X0200Y         S2      
017P1V25_PEX0_FB    VIA   -    M      A18X+005560Y+121047X0260Y         S2      
017P1V25_PEX0_FB          -    MD0100PA00X+005560Y+121047                       
327P1V25_PEX0_FB    PR168 -2   M      A01X+005306Y+120994X0198Y0197R090 S1      
327P1V25_PEX0_FB    PR166 -2          A01X+005821Y+121372X0198Y0197R180 S1      
327P1V25_PEX0_FB    PC219 -1   M      A01X+005821Y+120972X0198Y0197     S1      
317m3398            X57   -1    D0098PA00X+034311Y+176162X0395Y         S3      
317m3398            X56   -4    D0098PA00X+059531Y+176162X0395Y    R180 S3      
327m3399            PU16  -1          A01X+004556Y+119914X0120Y0360R270 S1      
327m3399            PC211 -1          A01X+004885Y+119225X0198Y0197     S1      
317m3400            X14   -1    D0098PA00X+034329Y+172858X0395Y    R180 S3      
317m3400            X15   -4    D0098PA00X+059539Y+172858X0395Y         S3      
327P1V25_PEX0_EN    PU16  -8          A01X+004576Y+121056X0070Y0320R270 S1      
317P1V25_PEX0_EN    VIA   -    M      A01X+004884Y+121111X0200Y         S2      
017P1V25_PEX0_EN    VIA   -    M      A18X+004884Y+121111X0260Y         S2      
017P1V25_PEX0_EN          -    MD0100PA00X+004884Y+121111                       
327P1V25_PEX0_EN    R842  -1          A01X+005134Y+121371X0198Y0197     S1      
317m3401            VIA   -    M      A01X+006309Y+120760X0200Y         S2      
017m3401            VIA   -    M      A18X+006309Y+120760X0260Y         S2      
017m3401                  -    MD0100PA00X+006309Y+120760                       
327m3401            PJ9   -1          A01X+006538Y+120584X0200Y0400R090 S1      
327m3401            PC978 -1   M      A01X+006138Y+120555X0198Y0197R270 S1      
327m3401            PC219 -2   M      A01X+006136Y+120972X0198Y0197     S1      
327m3401            PR166 -1          A01X+006136Y+121372X0198Y0197R180 S1      
317m3402            X64   -1    D0098PA00X+005635Y+178394X0395Y         S3      
317m3402            X65   -4    D0098PA00X+030845Y+178394X0395Y    R180 S3      
327P1V25_PEX0_REF   PU16  -5          A01X+004576Y+120583X0070Y0320R270 S1      
317P1V25_PEX0_REF   VIA   -           A01X+006027Y+119882X0200Y    R180 S2      
017P1V25_PEX0_REF   VIA   -           A18X+006027Y+119882X0260Y    R180 S2      
017P1V25_PEX0_REF         -     D0100PA00X+006027Y+119882                       
327P1V25_PEX0_REF   PC222 -1   M      A01X+005755Y+120266X0198Y0197R090 S1      
327P1V25_PEX0_REF   PC221 -1   M      A01X+005770Y+119882X0198Y0197R270 S1      
327m3403            PR159 -1          A01X+140229Y+110192X0198Y0197R270 S1      
317m3403            VIA   -    M      A01X+140310Y+110434X0200Y         S2      
017m3403            VIA   -    M      A18X+140310Y+110434X0260Y         S2      
017m3403                  -    MD0100PA00X+140310Y+110434                       
327m3403            PU14  -37         A01X+140126Y+111023X0090Y0240R180 S1      
327m3404            PU10  -6          A01X+052438Y+112155X0090Y0240R270 S1      
327m3405            PU14  -10_1       A01X+139697Y+113307X0240Y1700R270 S1      
327m3405            PL15  -1          A01X+139882Y+114354X1220Y1320R180 S1      
327m3406            PU10  -31         A01X+050859Y+111023X0090Y0240R180 S1      
327m3407            PR158 -1          A18X+141055Y+111197X0198Y0197R090 S2      
327m3407            PU14  -1          A01X+140642Y+111269X0090Y0240R270 S1      
317m3407            VIA   -    MD0100PA00X+140757Y+111009X0200Y         S0      
327m3408            PU15  -10_1       A01X+142910Y+113307X0240Y1700R270 S1      
327m3408            PL16  -1          A01X+142665Y+114354X1220Y1320R180 S1      
327m3409            PC179 -1          A01X+139043Y+110570X0198Y0197R270 S1      
327m3409            PU14  -32         A01X+139240Y+111023X0090Y0240R180 S1      
327m3410            PR163 -1          A01X+143442Y+110192X0198Y0197R270 S1      
317m3410            VIA   -    M      A01X+143523Y+110434X0200Y         S2      
017m3410            VIA   -    M      A18X+143523Y+110434X0260Y         S2      
017m3410                  -    MD0100PA00X+143523Y+110434                       
327m3410            PU15  -37         A01X+143339Y+111023X0090Y0240R180 S1      
327m3411            PU9   -41         A01X+048880Y+112263X0120Y0180R090 S1      
327m3412            PU10  -41         A01X+052093Y+112263X0120Y0180R090 S1      
327m3413            PR161 -1          A01X+142634Y+110570X0198Y0197R270 S1      
327m3413            PU15  -33         A01X+142630Y+111023X0090Y0240R180 S1      
327m3414            PU9   -31         A01X+047646Y+111023X0090Y0240R180 S1      
327P0V8_PEX3_VCC1   PR156 -2   M      A18X+140855Y+111582X0198Y0197R090 S2      
317P0V8_PEX3_VCC1   VIA   -    MD0100PA00X+141124Y+111590X0200Y         S0      
327P0V8_PEX3_VCC1   PU14  -3          A01X+140642Y+111624X0090Y0240R270 S1      
327P0V8_PEX3_VCC1   PC178 -1   M      A01X+141105Y+111347X0198Y0197R270 S1      
327P0V8_PEX3_VCC1   R6768 -1   M      A18X+140519Y+111247X0198Y0197R090 S2      
327P0V8_PEX3_VCC1   PR7173-2          A18X+140126Y+111126X0198Y0197R180 S2      
327P0V8_PEX3_VCC2   R6769 -1   M      A18X+143735Y+111249X0198Y0197R090 S2      
327P0V8_PEX3_VCC2   PR7174-2          A18X+143351Y+111120X0198Y0197R180 S2      
317P0V8_PEX3_VCC2   VIA   -    MD0100PA00X+144336Y+111590X0200Y         S0      
327P0V8_PEX3_VCC2   PR160 -2   M      A18X+144067Y+111582X0198Y0197R090 S2      
327P0V8_PEX3_VCC2   PU15  -3          A01X+143855Y+111624X0090Y0240R270 S1      
327P0V8_PEX3_VCC2   PC194 -1   M      A01X+144317Y+111347X0198Y0197R270 S1      
327m3415            PR157 -2          A01X+139422Y+110256X0198Y0197R270 S1      
327m3415            PC179 -2          A01X+139043Y+110256X0198Y0197R270 S1      
327m3416            PR161 -2          A01X+142634Y+110256X0198Y0197R270 S1      
327m3416            PC195 -2          A01X+142256Y+110256X0198Y0197R270 S1      
327m3417            PR162 -1          A18X+144267Y+111197X0198Y0197R090 S2      
327m3417            PU15  -1          A01X+143855Y+111269X0090Y0240R270 S1      
317m3417            VIA   -    MD0100PA00X+143970Y+111009X0200Y         S0      
327m3418            C1930 -1          A18X+163416Y+115853X0120Y0150R090 S2      
327m3418            C1929 -1          A18X+164245Y+117057X0120Y0150R180 S2      
327m3418            C1928 -1          A18X+164245Y+116683X0120Y0150R180 S2      
327m3418            C1927 -1          A18X+164245Y+115935X0120Y0150R180 S2      
327m3418            C1948 -1          A18X+163415Y+117139X0120Y0150R270 S2      
327m3418            C1936 -1          A18X+163707Y+116683X0120Y0150     S2      
327m3418            C1935 -1          A18X+163602Y+115105X0120Y0150R090 S2      
327m3418            C1960 -1          A18X+163228Y+115105X0120Y0150R090 S2      
327m3418            C1933 -1          A18X+162854Y+115105X0120Y0150R090 S2      
327m3418            C1959 -1          A18X+163602Y+114357X0120Y0150R090 S2      
327m3418            C1947 -1          A18X+163228Y+114357X0120Y0150R090 S2      
327m3418            C1958 -1          A18X+162854Y+114357X0120Y0150R090 S2      
327m3418            C1991 -1          A18X+162480Y+115105X0120Y0150R090 S2      
327m3418            C2003 -1          A18X+162480Y+114357X0120Y0150R090 S2      
327m3418            C1979 -1          A18X+162106Y+115105X0120Y0150R090 S2      
327m3418            C1978 -1          A18X+161732Y+115105X0120Y0150R090 S2      
327m3418            C1963 -1          A18X+161358Y+115105X0120Y0150R090 S2      
327m3418            C1966 -1          A18X+162106Y+114357X0120Y0150R090 S2      
327m3418            C1965 -1          A18X+161732Y+114357X0120Y0150R090 S2      
327m3418            C1975 -1          A18X+161358Y+114357X0120Y0150R090 S2      
327m3418            C2001 -1          A18X+160984Y+115105X0120Y0150R090 S2      
327m3418            C1962 -1          A18X+160984Y+114357X0120Y0150R090 S2      
327m3418            C1988 -1          A18X+160610Y+115105X0120Y0150R090 S2      
327m3418            C1926 -1          A18X+160236Y+115105X0120Y0150R090 S2      
327m3418            C1997 -1          A18X+159862Y+115105X0120Y0150R090 S2      
327m3418            C2000 -1          A18X+160610Y+114357X0120Y0150R090 S2      
327m3418            C1938 -1          A18X+160236Y+114357X0120Y0150R090 S2      
327m3418            C1971 -1          A18X+159862Y+114357X0120Y0150R090 S2      
327m3418            C1996 -1          A18X+159488Y+115105X0120Y0150R090 S2      
327m3418            C1984 -1          A18X+159114Y+115105X0120Y0150R090 S2      
327m3418            C1970 -1          A18X+159488Y+114357X0120Y0150R090 S2      
327m3418            C1995 -1          A18X+159114Y+114357X0120Y0150R090 S2      
327m3418            C1983 -1          A18X+158740Y+115105X0120Y0150R090 S2      
327m3418            C1981 -1          A18X+158366Y+115105X0120Y0150R090 S2      
327m3418            C1955 -1          A18X+157992Y+115105X0120Y0150R090 S2      
327m3418            C1982 -1          A18X+158740Y+114357X0120Y0150R090 S2      
327m3418            C1968 -1          A18X+158366Y+114357X0120Y0150R090 S2      
327m3418            C1953 -1          A18X+157992Y+114357X0120Y0150R090 S2      
327m3418            C1942 -1          A18X+157618Y+115105X0120Y0150R090 S2      
327m3418            C1941 -1          A18X+157618Y+114357X0120Y0150R090 S2      
327m3418            C1954 -1          A18X+157244Y+115105X0120Y0150R090 S2      
327m3418            C1940 -1          A18X+157244Y+114357X0120Y0150R090 S2      
327m3418            C1931 -1          A18X+163953Y+117805X0120Y0150R180 S2      
327m3418            C1950 -1          A18X+163602Y+118635X0120Y0150R270 S2      
327m3418            C1937 -1          A18X+163228Y+118635X0120Y0150R270 S2      
327m3418            C1946 -1          A18X+162854Y+118635X0120Y0150R270 S2      
327m3418            C1961 -1          A18X+163602Y+117887X0120Y0150R270 S2      
327m3418            C1949 -1          A18X+163228Y+117887X0120Y0150R270 S2      
327m3418            C1934 -1          A18X+162854Y+117887X0120Y0150R270 S2      
327m3418            C1993 -1          A18X+162480Y+118635X0120Y0150R270 S2      
327m3418            C2005 -1          A18X+162480Y+117887X0120Y0150R270 S2      
327m3418            C1980 -1          A18X+162106Y+118635X0120Y0150R270 S2      
327m3418            C1967 -1          A18X+161732Y+118635X0120Y0150R270 S2      
327m3418            C2002 -1          A18X+161358Y+118635X0120Y0150R270 S2      
327m3418            C2004 -1          A18X+162106Y+117887X0120Y0150R270 S2      
327m3418            C1992 -1          A18X+161732Y+117887X0120Y0150R270 S2      
327m3418            C1977 -1          A18X+161358Y+117887X0120Y0150R270 S2      
327m3418            C1990 -1          A18X+160984Y+118635X0120Y0150R270 S2      
327m3418            C1943 -1          A18X+160984Y+117887X0120Y0150R270 S2      
327m3418            C1989 -1          A18X+160610Y+118635X0120Y0150R270 S2      
327m3418            C1951 -1          A18X+160236Y+118635X0120Y0150R270 S2      
327m3418            C1999 -1          A18X+159862Y+118635X0120Y0150R270 S2      
327m3418            C1976 -1          A18X+160610Y+117887X0120Y0150R270 S2      
327m3418            C1964 -1          A18X+160236Y+117887X0120Y0150R270 S2      
327m3418            C1939 -1          A18X+159862Y+117887X0120Y0150R270 S2      
327m3418            C1987 -1          A18X+159488Y+118635X0120Y0150R270 S2      
327m3418            C1986 -1          A18X+159114Y+118635X0120Y0150R270 S2      
327m3418            C1973 -1          A18X+159488Y+117887X0120Y0150R270 S2      
327m3418            C1998 -1          A18X+159114Y+117887X0120Y0150R270 S2      
327m3418            C1974 -1          A18X+158740Y+118635X0120Y0150R270 S2      
327m3418            C1969 -1          A18X+158366Y+118635X0120Y0150R270 S2      
327m3418            C1945 -1          A18X+157992Y+118635X0120Y0150R270 S2      
327m3418            C1985 -1          A18X+158740Y+117887X0120Y0150R270 S2      
327m3418            C1972 -1          A18X+158366Y+117887X0120Y0150R270 S2      
327m3418            C1994 -1          A18X+157992Y+117887X0120Y0150R270 S2      
327m3418            C1932 -1          A18X+157618Y+118635X0120Y0150R270 S2      
327m3418            C1956 -1          A18X+157618Y+117887X0120Y0150R270 S2      
327m3418            C1957 -1          A18X+157244Y+118635X0120Y0150R270 S2      
327m3418            C1952 -1          A18X+156876Y+118635X0120Y0150R270 S2      
327m3418            C1944 -1          A18X+157244Y+117887X0120Y0150R270 S2      
317m3418            VIA   -    MD0080PA00X+157057Y+117805X0160Y         S0      
317m3418            VIA   -    MD0080PA00X+157431Y+117805X0160Y         S0      
317m3418            VIA   -    MD0080PA00X+157805Y+117805X0160Y         S0      
317m3418            VIA   -    MD0080PA00X+157805Y+118553X0160Y         S0      
317m3418            VIA   -    MD0080PA00X+157057Y+118553X0160Y         S0      
317m3418            VIA   -    MD0080PA00X+157431Y+118553X0160Y         S0      
317m3418            VIA   -    MD0080PA00X+157057Y+115187X0160Y         S0      
317m3418            VIA   -    MD0080PA00X+157431Y+115187X0160Y         S0      
317m3418            VIA   -    MD0080PA00X+157805Y+115187X0160Y         S0      
317m3418            VIA   -    MD0080PA00X+157057Y+114439X0160Y         S0      
317m3418            VIA   -    MD0080PA00X+157431Y+114439X0160Y         S0      
317m3418            VIA   -    MD0080PA00X+157805Y+114439X0160Y         S0      
317m3418            VIA   -    MD0080PA00X+158553Y+117805X0160Y         S0      
317m3418            VIA   -    MD0080PA00X+158927Y+117805X0160Y         S0      
317m3418            VIA   -    MD0080PA00X+159301Y+117805X0160Y         S0      
317m3418            VIA   -    MD0080PA00X+158179Y+117805X0160Y         S0      
317m3418            VIA   -    MD0080PA00X+159301Y+118553X0160Y         S0      
317m3418            VIA   -    MD0080PA00X+158179Y+118553X0160Y         S0      
317m3418            VIA   -    MD0080PA00X+158553Y+118553X0160Y         S0      
317m3418            VIA   -    MD0080PA00X+158927Y+118553X0160Y         S0      
317m3418            VIA   -    MD0080PA00X+158179Y+115187X0160Y         S0      
317m3418            VIA   -    MD0080PA00X+158553Y+115187X0160Y         S0      
317m3418            VIA   -    MD0080PA00X+158927Y+115187X0160Y         S0      
317m3418            VIA   -    MD0080PA00X+159301Y+115187X0160Y         S0      
317m3418            VIA   -    MD0080PA00X+158927Y+114439X0160Y         S0      
317m3418            VIA   -    MD0080PA00X+159301Y+114439X0160Y         S0      
317m3418            VIA   -    MD0080PA00X+158179Y+114439X0160Y         S0      
317m3418            VIA   -    MD0080PA00X+158553Y+114439X0160Y         S0      
317m3418            VIA   -    MD0080PA00X+160797Y+117805X0160Y         S0      
317m3418            VIA   -    MD0080PA00X+161171Y+117805X0160Y         S0      
317m3418            VIA   -    MD0080PA00X+160797Y+118553X0160Y         S0      
317m3418            VIA   -    MD0080PA00X+161171Y+118553X0160Y         S0      
317m3418            VIA   -    MD0080PA00X+159675Y+117805X0160Y         S0      
317m3418            VIA   -    MD0080PA00X+160049Y+117805X0160Y         S0      
317m3418            VIA   -    MD0080PA00X+159675Y+118553X0160Y         S0      
317m3418            VIA   -    MD0080PA00X+160049Y+118553X0160Y         S0      
317m3418            VIA   -    MD0080PA00X+159675Y+115187X0160Y         S0      
317m3418            VIA   -    MD0080PA00X+160049Y+115187X0160Y         S0      
317m3418            VIA   -    MD0080PA00X+160797Y+114439X0160Y         S0      
317m3418            VIA   -    MD0080PA00X+161171Y+114439X0160Y         S0      
317m3418            VIA   -    MD0080PA00X+160797Y+115187X0160Y         S0      
317m3418            VIA   -    MD0080PA00X+161171Y+115187X0160Y         S0      
317m3418            VIA   -    MD0080PA00X+159675Y+114439X0160Y         S0      
317m3418            VIA   -    MD0080PA00X+160049Y+114439X0160Y         S0      
317m3418            VIA   -    MD0080PA00X+161545Y+118553X0160Y         S0      
317m3418            VIA   -    MD0080PA00X+162667Y+114439X0160Y         S0      
317m3418            VIA   -    MD0080PA00X+161919Y+114439X0160Y         S0      
317m3418            VIA   -    MD0080PA00X+161545Y+114439X0160Y         S0      
317m3418            VIA   -    MD0080PA00X+162293Y+114439X0160Y         S0      
317m3418            VIA   -    MD0080PA00X+162293Y+115187X0160Y         S0      
317m3418            VIA   -    MD0080PA00X+162667Y+115187X0160Y         S0      
317m3418            VIA   -    MD0080PA00X+161919Y+115187X0160Y         S0      
317m3418            VIA   -    MD0080PA00X+161545Y+115187X0160Y         S0      
317m3418            VIA   -    MD0080PA00X+162667Y+117805X0160Y         S0      
317m3418            VIA   -    MD0080PA00X+161919Y+117805X0160Y         S0      
317m3418            VIA   -    MD0080PA00X+161545Y+117805X0160Y         S0      
317m3418            VIA   -    MD0080PA00X+162293Y+117805X0160Y         S0      
317m3418            VIA   -    MD0080PA00X+162293Y+118553X0160Y         S0      
317m3418            VIA   -    MD0080PA00X+162667Y+118553X0160Y         S0      
317m3418            VIA   -    MD0080PA00X+161919Y+118553X0160Y         S0      
317m3418            VIA   -    MD0080PA00X+163789Y+114439X0160Y         S0      
317m3418            VIA   -    MD0080PA00X+163041Y+114439X0160Y         S0      
317m3418            VIA   -    MD0080PA00X+163415Y+114439X0160Y         S0      
317m3418            VIA   -    MD0080PA00X+163415Y+115187X0160Y         S0      
317m3418            VIA   -    MD0080PA00X+163789Y+115187X0160Y         S0      
317m3418            VIA   -    MD0080PA00X+163041Y+115187X0160Y         S0      
317m3418            VIA   -    MD0080PA00X+163789Y+117805X0160Y         S0      
317m3418            VIA   -    MD0080PA00X+163789Y+118553X0160Y         S0      
317m3418            VIA   -    MD0080PA00X+163415Y+117805X0160Y         S0      
317m3418            VIA   -    MD0080PA00X+163041Y+117805X0160Y         S0      
317m3418            VIA   -    MD0080PA00X+163415Y+118553X0160Y         S0      
317m3418            VIA   -    MD0080PA00X+163041Y+118553X0160Y         S0      
317m3418            VIA   -    MD0080PA00X+163415Y+115935X0160Y         S0      
317m3418            VIA   -    MD0080PA00X+164163Y+115935X0160Y         S0      
317m3418            VIA   -    MD0080PA00X+163789Y+115935X0160Y         S0      
317m3418            VIA   -    MD0080PA00X+163789Y+116683X0160Y         S0      
317m3418            VIA   -    MD0080PA00X+164163Y+116683X0160Y         S0      
317m3418            VIA   -    MD0080PA00X+163415Y+117057X0160Y         S0      
317m3418            VIA   -    MD0080PA00X+164163Y+117057X0160Y         S0      
317m3418            VIA   -    MD0080PA00X+163789Y+117057X0160Y         S0      
327m3418            VIA   -           A18X+138467Y+122378X0260Y         S2      
327m3418            VIA   -           A18X+138086Y+123015X0260Y         S2      
327m3418            VIA   -           A18X+138208Y+123878X0260Y         S2      
327m3418            C4379 -1          A18X+138159Y+124411X0120Y0150     S2      
327m3418            C4365 -1          A18X+138159Y+124751X0120Y0150     S2      
327m3418            C4378 -1          A18X+138159Y+125081X0120Y0150     S2      
327m3418            C4364 -1          A18X+138159Y+125410X0120Y0150     S2      
327m3418            R6540 -1   M      A18X+144438Y+126554X0198Y0197R270 S2      
327m3418            R6539 -1   M      A18X+144041Y+126554X0198Y0197R270 S2      
327m3418            R6547 -1   M      A18X+143644Y+126556X0198Y0197R270 S2      
327m3418            R6548 -1   M      A18X+141945Y+126548X0198Y0197R270 S2      
327m3418            R6545 -1   M      A18X+141518Y+126554X0198Y0197R270 S2      
327m3418            R6537 -1   M      A18X+141118Y+126554X0198Y0197R270 S2      
327m3418            R6546 -1          A18X+140692Y+126554X0198Y0197R270 S2      
327m3418            R6538 -1          A18X+140143Y+126280X0198Y0197R270 S2      
327m3418            R6544 -1          A18X+139630Y+126280X0198Y0197R270 S2      
327m3418            R6543 -1          A18X+139127Y+126280X0198Y0197R270 S2      
327m3418            R6535 -1          A18X+138612Y+126284X0198Y0197R270 S2      
327m3418            R6536 -1          A18X+138094Y+126278X0198Y0197R270 S2      
327m3418            R5796 -2B  M      A18X+142700Y+126230X0100Y0200R270 S2      
327m3418            R5796 -2A  M      A18X+142700Y+126475X0590Y0790R270 S2      
327m3418            C1925 -1          A18X+139710Y+121791X0280Y0320R180 S2      
327m3418            C1922 -1   M      A18X+139066Y+121791X0280Y0320R180 S2      
327m3418            C1923 -1          A18X+138554Y+121791X0280Y0320R180 S2      
327m3418            C1924 -1          A18X+138037Y+121791X0280Y0320R180 S2      
327m3418            L77   -2   M      A18X+142700Y+126425X0460Y3860R270 S2      
327m3418            L76   -2   M      A18X+139100Y+123473X0460Y3860     S2      
327m3418            R5797 -2A  M      A18X+139051Y+123473X0590Y0790     S2      
327m3418            R5797 -2B  M      A18X+139296Y+123473X0100Y0200     S2      
327m3418            L75   -2   M      A01X+142700Y+126425X0460Y3860R090 S1      
327m3418            R5798 -2A  M      A01X+142700Y+126425X0590Y0790R090 S1      
327m3418            R5798 -2B  M      A01X+142700Y+126180X0100Y0200R090 S1      
327m3418            L78   -2   M      A01X+139100Y+123473X0460Y3860R180 S1      
327m3418            R5795 -2A  M      A01X+139051Y+123473X0590Y0790R180 S1      
327m3418            R5795 -2B  M      A01X+139296Y+123473X0100Y0200R180 S1      
317m3418            VIA   -    MD0100PA00X+142182Y+126016X0200Y         S0      
317m3418            VIA   -    MD0100PA00X+141882Y+126016X0200Y         S0      
317m3418            VIA   -    MD0100PA00X+141882Y+125716X0200Y         S0      
317m3418            VIA   -    MD0100PA00X+142182Y+125716X0200Y         S0      
317m3418            VIA   -    MD0100PA00X+140682Y+126016X0200Y         S0      
317m3418            VIA   -    MD0100PA00X+140382Y+126016X0200Y         S0      
317m3418            VIA   -    MD0100PA00X+141582Y+125716X0200Y         S0      
317m3418            VIA   -    MD0100PA00X+141582Y+126016X0200Y         S0      
317m3418            VIA   -    MD0100PA00X+140382Y+125716X0200Y         S0      
317m3418            VIA   -    MD0100PA00X+140682Y+125716X0200Y         S0      
317m3418            VIA   -    MD0100PA00X+140982Y+125716X0200Y         S0      
317m3418            VIA   -    MD0100PA00X+141282Y+125716X0200Y         S0      
317m3418            VIA   -    MD0100PA00X+141282Y+126016X0200Y         S0      
317m3418            VIA   -    MD0100PA00X+140982Y+126016X0200Y         S0      
317m3418            VIA   -    MD0100PA00X+139182Y+126016X0200Y         S0      
317m3418            VIA   -    MD0100PA00X+139482Y+126016X0200Y         S0      
317m3418            VIA   -    MD0100PA00X+138882Y+126016X0200Y         S0      
317m3418            VIA   -    MD0100PA00X+140082Y+125716X0200Y         S0      
317m3418            VIA   -    MD0100PA00X+140082Y+126016X0200Y         S0      
317m3418            VIA   -    MD0100PA00X+139782Y+125716X0200Y         S0      
317m3418            VIA   -    MD0100PA00X+139782Y+126016X0200Y         S0      
317m3418            VIA   -    MD0100PA00X+138882Y+125716X0200Y         S0      
317m3418            VIA   -    MD0100PA00X+138582Y+125716X0200Y         S0      
317m3418            VIA   -    MD0100PA00X+139482Y+125716X0200Y         S0      
317m3418            VIA   -    MD0100PA00X+139182Y+125716X0200Y         S0      
317m3418            VIA   -    MD0100PA00X+138582Y+126016X0200Y         S0      
327m3418            PEX3  -Y33        A01X+163602Y+118366X0180Y         S1      
327m3418            PEX3  -AB33       A01X+163602Y+117618X0180Y         S1      
327m3418            PEX3  -Y25        A01X+160610Y+118366X0180Y         S1      
327m3418            PEX3  -Y29 M      A01X+162106Y+118366X0180Y         S1      
327m3418            PEX3  -Y27 M      A01X+161358Y+118366X0180Y         S1      
327m3418            PEX3  -Y28 M      A01X+161732Y+118366X0180Y         S1      
327m3418            PEX3  -Y31 M      A01X+162854Y+118366X0180Y         S1      
327m3418            PEX3  -Y32 M      A01X+163228Y+118366X0180Y         S1      
327m3418            PEX3  -Y30 M      A01X+162480Y+118366X0180Y         S1      
327m3418            PEX3  -Y26 M      A01X+160984Y+118366X0180Y         S1      
327m3418            PEX3  -AB25       A01X+160610Y+117618X0180Y         S1      
327m3418            PEX3  -AB27M      A01X+161358Y+117618X0180Y         S1      
327m3418            PEX3  -AB28M      A01X+161732Y+117618X0180Y         S1      
327m3418            PEX3  -AB29M      A01X+162106Y+117618X0180Y         S1      
327m3418            PEX3  -AB30M      A01X+162480Y+117618X0180Y         S1      
327m3418            PEX3  -AB31M      A01X+162854Y+117618X0180Y         S1      
327m3418            PEX3  -AB32M      A01X+163228Y+117618X0180Y         S1      
327m3418            PEX3  -AB26M      A01X+160984Y+117618X0180Y         S1      
327m3418            PEX3  -Y16 M      A01X+157244Y+118366X0180Y         S1      
327m3418            PEX3  -Y17 M      A01X+157618Y+118366X0180Y         S1      
327m3418            PEX3  -Y22 M      A01X+159488Y+118366X0180Y         S1      
327m3418            PEX3  -Y23 M      A01X+159862Y+118366X0180Y         S1      
327m3418            PEX3  -Y24        A01X+160236Y+118366X0180Y         S1      
327m3418            PEX3  -Y21 M      A01X+159114Y+118366X0180Y         S1      
327m3418            PEX3  -Y20 M      A01X+158740Y+118366X0180Y         S1      
327m3418            PEX3  -Y19 M      A01X+158366Y+118366X0180Y         S1      
327m3418            PEX3  -Y18 M      A01X+157992Y+118366X0180Y         S1      
327m3418            PEX3  -AB16M      A01X+157244Y+117618X0180Y         S1      
327m3418            PEX3  -AB17M      A01X+157618Y+117618X0180Y         S1      
327m3418            PEX3  -AB18M      A01X+157992Y+117618X0180Y         S1      
327m3418            PEX3  -AB19M      A01X+158366Y+117618X0180Y         S1      
327m3418            PEX3  -AB20M      A01X+158740Y+117618X0180Y         S1      
327m3418            PEX3  -AB21M      A01X+159114Y+117618X0180Y         S1      
327m3418            PEX3  -AB22M      A01X+159488Y+117618X0180Y         S1      
327m3418            PEX3  -AB24       A01X+160236Y+117618X0180Y         S1      
327m3418            PEX3  -AB23M      A01X+159862Y+117618X0180Y         S1      
327m3418            PEX3  -AD32       A01X+163228Y+116870X0180Y         S1      
327m3418            PEX3  -AD33M      A01X+163602Y+116870X0180Y         S1      
327m3418            PEX3  -AD34M      A01X+163976Y+116870X0180Y         S1      
327m3418            PEX3  -AE34M      A01X+163976Y+116496X0180Y         S1      
327m3418            PEX3  -AE33       A01X+163602Y+116496X0180Y         S1      
327m3418            PEX3  -AF32       A01X+163228Y+116122X0180Y         S1      
327m3418            PEX3  -AF34M      A01X+163976Y+116122X0180Y         S1      
327m3418            PEX3  -AF33M      A01X+163602Y+116122X0180Y         S1      
327m3418            PEX3  -AH25       A01X+160610Y+115374X0180Y         S1      
327m3418            PEX3  -AH31M      A01X+162854Y+115374X0180Y         S1      
327m3418            PEX3  -AH32M      A01X+163228Y+115374X0180Y         S1      
327m3418            PEX3  -AH33M      A01X+163602Y+115374X0180Y         S1      
327m3418            PEX3  -AH27M      A01X+161358Y+115374X0180Y         S1      
327m3418            PEX3  -AH30M      A01X+162480Y+115374X0180Y         S1      
327m3418            PEX3  -AH28M      A01X+161732Y+115374X0180Y         S1      
327m3418            PEX3  -AH29M      A01X+162106Y+115374X0180Y         S1      
327m3418            PEX3  -AH26M      A01X+160984Y+115374X0180Y         S1      
327m3418            PEX3  -AK25       A01X+160610Y+114626X0180Y         S1      
327m3418            PEX3  -AK27M      A01X+161358Y+114626X0180Y         S1      
327m3418            PEX3  -AK28M      A01X+161732Y+114626X0180Y         S1      
327m3418            PEX3  -AK30M      A01X+162480Y+114626X0180Y         S1      
327m3418            PEX3  -AK29M      A01X+162106Y+114626X0180Y         S1      
327m3418            PEX3  -AK31M      A01X+162854Y+114626X0180Y         S1      
327m3418            PEX3  -AK33M      A01X+163602Y+114626X0180Y         S1      
327m3418            PEX3  -AK32M      A01X+163228Y+114626X0180Y         S1      
327m3418            PEX3  -AK26M      A01X+160984Y+114626X0180Y         S1      
327m3418            PEX3  -AH24       A01X+160236Y+115374X0180Y         S1      
327m3418            PEX3  -AH23       A01X+159862Y+115374X0180Y         S1      
327m3418            PEX3  -AH22       A01X+159488Y+115374X0180Y         S1      
327m3418            PEX3  -AH21       A01X+159114Y+115374X0180Y         S1      
327m3418            PEX3  -AH20       A01X+158740Y+115374X0180Y         S1      
327m3418            PEX3  -AH19       A01X+158366Y+115374X0180Y         S1      
327m3418            PEX3  -AH18       A01X+157992Y+115374X0180Y         S1      
327m3418            PEX3  -AH17       A01X+157618Y+115374X0180Y         S1      
327m3418            PEX3  -AH16       A01X+157244Y+115374X0180Y         S1      
327m3418            PEX3  -AK16M      A01X+157244Y+114626X0180Y         S1      
327m3418            PEX3  -AK17M      A01X+157618Y+114626X0180Y         S1      
327m3418            PEX3  -AK20M      A01X+158740Y+114626X0180Y         S1      
327m3418            PEX3  -AK19M      A01X+158366Y+114626X0180Y         S1      
327m3418            PEX3  -AK18M      A01X+157992Y+114626X0180Y         S1      
327m3418            PEX3  -AK21M      A01X+159114Y+114626X0180Y         S1      
327m3418            PEX3  -AK23M      A01X+159862Y+114626X0180Y         S1      
327m3418            PEX3  -AK24       A01X+160236Y+114626X0180Y         S1      
327m3418            PEX3  -AK22M      A01X+159488Y+114626X0180Y         S1      
327m3419            PR157 -1          A01X+139422Y+110570X0198Y0197R270 S1      
327m3419            PU14  -33         A01X+139418Y+111023X0090Y0240R180 S1      
327m3420            PU9   -6          A01X+049225Y+112155X0090Y0240R270 S1      
327m3421            C1703 -1          A18X+117894Y+118635X0120Y0150R270 S2      
327m3421            C1692 -1          A18X+117520Y+118635X0120Y0150R270 S2      
327m3421            C1694 -1          A18X+117894Y+117887X0120Y0150R270 S2      
327m3421            C1684 -1          A18X+117520Y+117887X0120Y0150R270 S2      
327m3421            C1704 -1          A18X+118245Y+117805X0120Y0150R180 S2      
327m3421            C1679 -1          A18X+117146Y+118635X0120Y0150R270 S2      
327m3421            C1717 -1          A18X+116772Y+118635X0120Y0150R270 S2      
327m3421            C1740 -1          A18X+116398Y+118635X0120Y0150R270 S2      
327m3421            C1749 -1          A18X+116024Y+118635X0120Y0150R270 S2      
327m3421            C1693 -1          A18X+117146Y+117887X0120Y0150R270 S2      
327m3421            C1722 -1          A18X+116772Y+117887X0120Y0150R270 S2      
327m3421            C1724 -1          A18X+116398Y+117887X0120Y0150R270 S2      
327m3421            C1719 -1          A18X+116024Y+117887X0120Y0150R270 S2      
327m3421            C1735 -1          A18X+115650Y+118635X0120Y0150R270 S2      
327m3421            C1716 -1          A18X+115276Y+118635X0120Y0150R270 S2      
327m3421            C1728 -1          A18X+114902Y+118635X0120Y0150R270 S2      
327m3421            C1683 -1          A18X+114528Y+118635X0120Y0150R270 S2      
327m3421            C1737 -1          A18X+114154Y+118635X0120Y0150R270 S2      
327m3421            C1745 -1          A18X+115650Y+117887X0120Y0150R270 S2      
327m3421            C1713 -1          A18X+115276Y+117887X0120Y0150R270 S2      
327m3421            C1718 -1          A18X+114902Y+117887X0120Y0150R270 S2      
327m3421            C1701 -1          A18X+114528Y+117887X0120Y0150R270 S2      
327m3421            C1747 -1          A18X+114154Y+117887X0120Y0150R270 S2      
327m3421            C1736 -1          A18X+113780Y+118635X0120Y0150R270 S2      
327m3421            C1733 -1          A18X+113405Y+118635X0120Y0150R270 S2      
327m3421            C1712 -1          A18X+113031Y+118635X0120Y0150R270 S2      
327m3421            C1714 -1          A18X+112657Y+118635X0120Y0150R270 S2      
327m3421            C1709 -1          A18X+113780Y+117887X0120Y0150R270 S2      
327m3421            C1729 -1          A18X+113405Y+117887X0120Y0150R270 S2      
327m3421            C1723 -1          A18X+113031Y+117887X0120Y0150R270 S2      
327m3421            C1710 -1          A18X+112657Y+117887X0120Y0150R270 S2      
327m3421            C1687 -1          A18X+112283Y+118635X0120Y0150R270 S2      
327m3421            C1696 -1          A18X+111909Y+118635X0120Y0150R270 S2      
327m3421            C1702 -1          A18X+111535Y+118635X0120Y0150R270 S2      
327m3421            C1681 -1          A18X+111167Y+118635X0120Y0150R270 S2      
327m3421            C1689 -1          A18X+112283Y+117887X0120Y0150R270 S2      
327m3421            C1691 -1          A18X+111909Y+117887X0120Y0150R270 S2      
327m3421            C1677 -1          A18X+111535Y+117887X0120Y0150R270 S2      
327m3421            C1674 -1          A18X+118537Y+117057X0120Y0150R180 S2      
327m3421            C1676 -1          A18X+118537Y+116683X0120Y0150R180 S2      
327m3421            C1672 -1          A18X+118537Y+115935X0120Y0150R180 S2      
327m3421            C1695 -1          A18X+117707Y+117139X0120Y0150R270 S2      
327m3421            C1675 -1          A18X+117999Y+116683X0120Y0150     S2      
327m3421            C1673 -1          A18X+117707Y+115853X0120Y0150R090 S2      
327m3421            C1706 -1          A18X+117894Y+115105X0120Y0150R090 S2      
327m3421            C1699 -1          A18X+117520Y+115105X0120Y0150R090 S2      
327m3421            C1705 -1          A18X+117894Y+114357X0120Y0150R090 S2      
327m3421            C1682 -1          A18X+117520Y+114357X0120Y0150R090 S2      
327m3421            C1680 -1          A18X+117146Y+115105X0120Y0150R090 S2      
327m3421            C1734 -1          A18X+116772Y+115105X0120Y0150R090 S2      
327m3421            C1720 -1          A18X+116398Y+115105X0120Y0150R090 S2      
327m3421            C1727 -1          A18X+116024Y+115105X0120Y0150R090 S2      
327m3421            C1678 -1          A18X+117146Y+114357X0120Y0150R090 S2      
327m3421            C1738 -1          A18X+116772Y+114357X0120Y0150R090 S2      
327m3421            C1711 -1          A18X+116024Y+114357X0120Y0150R090 S2      
327m3421            C1748 -1          A18X+116398Y+114357X0120Y0150R090 S2      
327m3421            C1742 -1          A18X+115650Y+115105X0120Y0150R090 S2      
327m3421            C1725 -1          A18X+115276Y+115105X0120Y0150R090 S2      
327m3421            C1715 -1          A18X+114902Y+115105X0120Y0150R090 S2      
327m3421            C1671 -1          A18X+114528Y+115105X0120Y0150R090 S2      
327m3421            C1708 -1          A18X+114154Y+115105X0120Y0150R090 S2      
327m3421            C1707 -1          A18X+115276Y+114357X0120Y0150R090 S2      
327m3421            C1731 -1          A18X+115650Y+114357X0120Y0150R090 S2      
327m3421            C1739 -1          A18X+114902Y+114357X0120Y0150R090 S2      
327m3421            C1690 -1          A18X+114528Y+114357X0120Y0150R090 S2      
327m3421            C1750 -1          A18X+114154Y+114357X0120Y0150R090 S2      
327m3421            C1726 -1          A18X+113780Y+115105X0120Y0150R090 S2      
327m3421            C1732 -1          A18X+113405Y+115105X0120Y0150R090 S2      
327m3421            C1743 -1          A18X+113031Y+115105X0120Y0150R090 S2      
327m3421            C1744 -1          A18X+112657Y+115105X0120Y0150R090 S2      
327m3421            C1721 -1          A18X+113780Y+114357X0120Y0150R090 S2      
327m3421            C1741 -1          A18X+113405Y+114357X0120Y0150R090 S2      
327m3421            C1746 -1          A18X+113031Y+114357X0120Y0150R090 S2      
327m3421            C1730 -1          A18X+112657Y+114357X0120Y0150R090 S2      
327m3421            C1700 -1          A18X+112283Y+115105X0120Y0150R090 S2      
327m3421            C1697 -1          A18X+111909Y+115105X0120Y0150R090 S2      
327m3421            C1685 -1          A18X+111535Y+115105X0120Y0150R090 S2      
327m3421            C1698 -1          A18X+112283Y+114357X0120Y0150R090 S2      
327m3421            C1686 -1          A18X+111535Y+114357X0120Y0150R090 S2      
327m3421            C1688 -1          A18X+111909Y+114357X0120Y0150R090 S2      
317m3421            VIA   -    MD0080PA00X+112470Y+118553X0160Y         S0      
317m3421            VIA   -    MD0080PA00X+111722Y+118553X0160Y         S0      
317m3421            VIA   -    MD0080PA00X+111348Y+118553X0160Y         S0      
317m3421            VIA   -    MD0080PA00X+112096Y+118553X0160Y         S0      
317m3421            VIA   -    MD0080PA00X+112470Y+117805X0160Y         S0      
317m3421            VIA   -    MD0080PA00X+112096Y+117805X0160Y         S0      
317m3421            VIA   -    MD0080PA00X+111722Y+117805X0160Y         S0      
317m3421            VIA   -    MD0080PA00X+111348Y+117805X0160Y         S0      
317m3421            VIA   -    MD0080PA00X+112470Y+115187X0160Y         S0      
317m3421            VIA   -    MD0080PA00X+112096Y+115187X0160Y         S0      
317m3421            VIA   -    MD0080PA00X+111722Y+115187X0160Y         S0      
317m3421            VIA   -    MD0080PA00X+111348Y+115187X0160Y         S0      
317m3421            VIA   -    MD0080PA00X+112096Y+114439X0160Y         S0      
317m3421            VIA   -    MD0080PA00X+111722Y+114439X0160Y         S0      
317m3421            VIA   -    MD0080PA00X+111348Y+114439X0160Y         S0      
317m3421            VIA   -    MD0080PA00X+112470Y+114439X0160Y         S0      
317m3421            VIA   -    MD0080PA00X+113966Y+115187X0160Y         S0      
317m3421            VIA   -    MD0080PA00X+112844Y+115187X0160Y         S0      
317m3421            VIA   -    MD0080PA00X+113218Y+115187X0160Y         S0      
317m3421            VIA   -    MD0080PA00X+113592Y+115187X0160Y         S0      
317m3421            VIA   -    MD0080PA00X+113966Y+114439X0160Y         S0      
317m3421            VIA   -    MD0080PA00X+113218Y+114439X0160Y         S0      
317m3421            VIA   -    MD0080PA00X+113592Y+114439X0160Y         S0      
317m3421            VIA   -    MD0080PA00X+112844Y+114439X0160Y         S0      
317m3421            VIA   -    MD0080PA00X+113592Y+118553X0160Y         S0      
317m3421            VIA   -    MD0080PA00X+112844Y+118553X0160Y         S0      
317m3421            VIA   -    MD0080PA00X+113218Y+118553X0160Y         S0      
317m3421            VIA   -    MD0080PA00X+113966Y+118553X0160Y         S0      
317m3421            VIA   -    MD0080PA00X+112844Y+117805X0160Y         S0      
317m3421            VIA   -    MD0080PA00X+113218Y+117805X0160Y         S0      
317m3421            VIA   -    MD0080PA00X+113592Y+117805X0160Y         S0      
317m3421            VIA   -    MD0080PA00X+113966Y+117805X0160Y         S0      
317m3421            VIA   -    MD0080PA00X+115088Y+117805X0160Y         S0      
317m3421            VIA   -    MD0080PA00X+115462Y+117805X0160Y         S0      
317m3421            VIA   -    MD0080PA00X+115088Y+118553X0160Y         S0      
317m3421            VIA   -    MD0080PA00X+115462Y+118553X0160Y         S0      
317m3421            VIA   -    MD0080PA00X+114340Y+118553X0160Y         S0      
317m3421            VIA   -    MD0080PA00X+114340Y+117805X0160Y         S0      
317m3421            VIA   -    MD0080PA00X+114340Y+115187X0160Y         S0      
317m3421            VIA   -    MD0080PA00X+115088Y+114439X0160Y         S0      
317m3421            VIA   -    MD0080PA00X+115462Y+114439X0160Y         S0      
317m3421            VIA   -    MD0080PA00X+115462Y+115187X0160Y         S0      
317m3421            VIA   -    MD0080PA00X+115088Y+115187X0160Y         S0      
317m3421            VIA   -    MD0080PA00X+114340Y+114439X0160Y         S0      
317m3421            VIA   -    MD0080PA00X+116959Y+114439X0160Y         S0      
317m3421            VIA   -    MD0080PA00X+116211Y+114439X0160Y         S0      
317m3421            VIA   -    MD0080PA00X+115836Y+114439X0160Y         S0      
317m3421            VIA   -    MD0080PA00X+116585Y+114439X0160Y         S0      
317m3421            VIA   -    MD0080PA00X+117333Y+114439X0160Y         S0      
317m3421            VIA   -    MD0080PA00X+116585Y+115187X0160Y         S0      
317m3421            VIA   -    MD0080PA00X+116959Y+115187X0160Y         S0      
317m3421            VIA   -    MD0080PA00X+116211Y+115187X0160Y         S0      
317m3421            VIA   -    MD0080PA00X+115836Y+115187X0160Y         S0      
317m3421            VIA   -    MD0080PA00X+117333Y+115187X0160Y         S0      
317m3421            VIA   -    MD0080PA00X+117333Y+117805X0160Y         S0      
317m3421            VIA   -    MD0080PA00X+116959Y+117805X0160Y         S0      
317m3421            VIA   -    MD0080PA00X+116211Y+117805X0160Y         S0      
317m3421            VIA   -    MD0080PA00X+115836Y+117805X0160Y         S0      
317m3421            VIA   -    MD0080PA00X+116585Y+117805X0160Y         S0      
317m3421            VIA   -    MD0080PA00X+117333Y+118553X0160Y         S0      
317m3421            VIA   -    MD0080PA00X+116585Y+118553X0160Y         S0      
317m3421            VIA   -    MD0080PA00X+116959Y+118553X0160Y         S0      
317m3421            VIA   -    MD0080PA00X+116211Y+118553X0160Y         S0      
317m3421            VIA   -    MD0080PA00X+115836Y+118553X0160Y         S0      
317m3421            VIA   -    MD0080PA00X+118455Y+115935X0160Y         S0      
317m3421            VIA   -    MD0080PA00X+118081Y+115935X0160Y         S0      
317m3421            VIA   -    MD0080PA00X+117707Y+115935X0160Y         S0      
317m3421            VIA   -    MD0080PA00X+118081Y+116683X0160Y         S0      
317m3421            VIA   -    MD0080PA00X+118455Y+116683X0160Y         S0      
317m3421            VIA   -    MD0080PA00X+117707Y+117057X0160Y         S0      
317m3421            VIA   -    MD0080PA00X+118455Y+117057X0160Y         S0      
317m3421            VIA   -    MD0080PA00X+118081Y+117057X0160Y         S0      
317m3421            VIA   -    MD0080PA00X+118081Y+114439X0160Y         S0      
317m3421            VIA   -    MD0080PA00X+117707Y+114439X0160Y         S0      
317m3421            VIA   -    MD0080PA00X+117707Y+115187X0160Y         S0      
317m3421            VIA   -    MD0080PA00X+118081Y+115187X0160Y         S0      
317m3421            VIA   -    MD0080PA00X+118081Y+117805X0160Y         S0      
317m3421            VIA   -    MD0080PA00X+118081Y+118553X0160Y         S0      
317m3421            VIA   -    MD0080PA00X+117707Y+117805X0160Y         S0      
317m3421            VIA   -    MD0080PA00X+117707Y+118553X0160Y         S0      
327m3421            R5791 -2B  M      A01X+132869Y+126180X0100Y0200R090 S1      
327m3421            R5791 -2A  M      A01X+132869Y+126425X0590Y0790R090 S1      
327m3421            L63   -2   M      A01X+132869Y+126425X0460Y3860R090 S1      
327m3421            R5794 -2B  M      A01X+136274Y+123473X0100Y0200     S1      
327m3421            R5794 -2A  M      A01X+136519Y+123473X0590Y0790     S1      
327m3421            L62   -2   M      A01X+136470Y+123473X0460Y3860     S1      
327m3421            C1668 -1          A18X+137278Y+125840X0280Y0320R270 S2      
327m3421            C4322 -1          A18X+137292Y+124751X0120Y0150R180 S2      
327m3421            C4323 -1          A18X+137292Y+125070X0120Y0150R180 S2      
327m3421            C4309 -1          A18X+137292Y+125410X0120Y0150R180 S2      
327m3421            R6508 -1          A18X+137215Y+127066X0198Y0197R270 S2      
327m3421            C4308 -1          A18X+131079Y+127362X0120Y0150R270 S2      
327m3421            R6513 -1          A18X+136783Y+127069X0198Y0197R270 S2      
327m3421            R6514 -1          A18X+136231Y+127069X0198Y0197R270 S2      
327m3421            C1670 -1   M      A18X+136462Y+121791X0280Y0320R180 S2      
327m3421            R6507 -1          A18X+135686Y+127069X0198Y0197R270 S2      
327m3421            R6510 -1          A18X+135167Y+127069X0198Y0197R270 S2      
327m3421            R6509 -1          A18X+134636Y+127069X0198Y0197R270 S2      
327m3421            R6516 -1          A18X+134123Y+127069X0198Y0197R270 S2      
327m3421            R6506 -1          A18X+133594Y+127069X0198Y0197R270 S2      
327m3421            R6518 -1          A18X+133058Y+127069X0198Y0197R270 S2      
327m3421            R6515 -1          A18X+132548Y+127069X0198Y0197R270 S2      
327m3421            R6505 -1          A18X+132000Y+127069X0198Y0197R270 S2      
327m3421            R6517 -1          A18X+131460Y+127069X0198Y0197R270 S2      
327m3421            C1667 -1          A18X+137516Y+121791X0280Y0320R180 S2      
327m3421            C1669 -1          A18X+136994Y+121791X0280Y0320R180 S2      
327m3421            L64   -2   M      A18X+132869Y+126425X0460Y3860R270 S2      
327m3421            R5793 -2A  M      A18X+132869Y+126425X0590Y0790R270 S2      
327m3421            R5793 -2B  M      A18X+132869Y+126180X0100Y0200R270 S2      
327m3421            L61   -2   M      A18X+136470Y+123473X0460Y3860R180 S2      
327m3421            R5792 -2A  M      A18X+136519Y+123473X0590Y0790R180 S2      
327m3421            R5792 -2B  M      A18X+136274Y+123473X0100Y0200R180 S2      
317m3421            VIA   -    MD0100PA00X+133388Y+126016X0200Y         S0      
317m3421            VIA   -    MD0100PA00X+133388Y+125716X0200Y         S0      
317m3421            VIA   -    MD0100PA00X+133988Y+126016X0200Y         S0      
317m3421            VIA   -    MD0100PA00X+134288Y+126016X0200Y         S0      
317m3421            VIA   -    MD0100PA00X+133688Y+125716X0200Y         S0      
317m3421            VIA   -    MD0100PA00X+133688Y+126016X0200Y         S0      
317m3421            VIA   -    MD0100PA00X+135188Y+125716X0200Y         S0      
317m3421            VIA   -    M      A01X+135188Y+126016X0200Y         S2      
017m3421            VIA   -    M      A18X+135188Y+126016X0260Y         S2      
017m3421                  -    MD0100PA00X+135188Y+126016                       
317m3421            VIA   -    MD0100PA00X+134888Y+125716X0200Y         S0      
317m3421            VIA   -    MD0100PA00X+134888Y+126016X0200Y         S0      
317m3421            VIA   -    MD0100PA00X+134588Y+125716X0200Y         S0      
317m3421            VIA   -    MD0100PA00X+134588Y+126016X0200Y         S0      
317m3421            VIA   -    MD0100PA00X+134288Y+125716X0200Y         S0      
317m3421            VIA   -    MD0100PA00X+133988Y+125716X0200Y         S0      
317m3421            VIA   -    MD0100PA00X+136688Y+125716X0200Y         S0      
317m3421            VIA   -    MD0100PA00X+136688Y+126016X0200Y         S0      
317m3421            VIA   -    MD0100PA00X+135488Y+125716X0200Y         S0      
317m3421            VIA   -    MD0100PA00X+135788Y+125716X0200Y         S0      
317m3421            VIA   -    MD0100PA00X+136088Y+125716X0200Y         S0      
317m3421            VIA   -    M      A01X+136088Y+126016X0200Y         S2      
017m3421            VIA   -    M      A18X+136088Y+126016X0260Y         S2      
017m3421                  -    MD0100PA00X+136088Y+126016                       
317m3421            VIA   -    MD0100PA00X+135788Y+126016X0200Y         S0      
317m3421            VIA   -    MD0100PA00X+135488Y+126016X0200Y         S0      
317m3421            VIA   -    MD0100PA00X+136388Y+125716X0200Y         S0      
317m3421            VIA   -    MD0100PA00X+136388Y+126016X0200Y         S0      
327m3421            PEX2  -AB33       A01X+117894Y+117618X0180Y         S1      
327m3421            PEX2  -Y33        A01X+117894Y+118366X0180Y         S1      
327m3421            PEX2  -AB26M      A01X+115276Y+117618X0180Y         S1      
327m3421            PEX2  -AB25       A01X+114902Y+117618X0180Y         S1      
327m3421            PEX2  -AB30M      A01X+116772Y+117618X0180Y         S1      
327m3421            PEX2  -AB28M      A01X+116024Y+117618X0180Y         S1      
327m3421            PEX2  -AB29M      A01X+116398Y+117618X0180Y         S1      
327m3421            PEX2  -AB31M      A01X+117146Y+117618X0180Y         S1      
327m3421            PEX2  -AB32M      A01X+117520Y+117618X0180Y         S1      
327m3421            PEX2  -AB27M      A01X+115650Y+117618X0180Y         S1      
327m3421            PEX2  -Y26 M      A01X+115276Y+118366X0180Y         S1      
327m3421            PEX2  -Y25        A01X+114902Y+118366X0180Y         S1      
327m3421            PEX2  -Y29 M      A01X+116398Y+118366X0180Y         S1      
327m3421            PEX2  -Y30 M      A01X+116772Y+118366X0180Y         S1      
327m3421            PEX2  -Y28 M      A01X+116024Y+118366X0180Y         S1      
327m3421            PEX2  -Y31 M      A01X+117146Y+118366X0180Y         S1      
327m3421            PEX2  -Y32 M      A01X+117520Y+118366X0180Y         S1      
327m3421            PEX2  -Y27 M      A01X+115650Y+118366X0180Y         S1      
327m3421            PEX2  -Y22 M      A01X+113780Y+118366X0180Y         S1      
327m3421            PEX2  -Y19 M      A01X+112657Y+118366X0180Y         S1      
327m3421            PEX2  -Y20 M      A01X+113031Y+118366X0180Y         S1      
327m3421            PEX2  -Y21 M      A01X+113405Y+118366X0180Y         S1      
327m3421            PEX2  -Y24        A01X+114528Y+118366X0180Y         S1      
327m3421            PEX2  -Y23 M      A01X+114154Y+118366X0180Y         S1      
327m3421            PEX2  -Y18 M      A01X+112283Y+118366X0180Y         S1      
327m3421            PEX2  -Y16 M      A01X+111535Y+118366X0180Y         S1      
327m3421            PEX2  -Y17 M      A01X+111909Y+118366X0180Y         S1      
327m3421            PEX2  -AB22M      A01X+113780Y+117618X0180Y         S1      
327m3421            PEX2  -AB19M      A01X+112657Y+117618X0180Y         S1      
327m3421            PEX2  -AB20M      A01X+113031Y+117618X0180Y         S1      
327m3421            PEX2  -AB21M      A01X+113405Y+117618X0180Y         S1      
327m3421            PEX2  -AB24       A01X+114528Y+117618X0180Y         S1      
327m3421            PEX2  -AB23M      A01X+114154Y+117618X0180Y         S1      
327m3421            PEX2  -AB18M      A01X+112283Y+117618X0180Y         S1      
327m3421            PEX2  -AB17M      A01X+111909Y+117618X0180Y         S1      
327m3421            PEX2  -AB16M      A01X+111535Y+117618X0180Y         S1      
327m3421            PEX2  -AF34M      A01X+118268Y+116122X0180Y         S1      
327m3421            PEX2  -AF33M      A01X+117894Y+116122X0180Y         S1      
327m3421            PEX2  -AF32       A01X+117520Y+116122X0180Y         S1      
327m3421            PEX2  -AE33       A01X+117894Y+116496X0180Y         S1      
327m3421            PEX2  -AE34M      A01X+118268Y+116496X0180Y         S1      
327m3421            PEX2  -AD34M      A01X+118268Y+116870X0180Y         S1      
327m3421            PEX2  -AD32       A01X+117520Y+116870X0180Y         S1      
327m3421            PEX2  -AD33M      A01X+117894Y+116870X0180Y         S1      
327m3421            PEX2  -AH24       A01X+114528Y+115374X0180Y         S1      
327m3421            PEX2  -AK26M      A01X+115276Y+114626X0180Y         S1      
327m3421            PEX2  -AK25       A01X+114902Y+114626X0180Y         S1      
327m3421            PEX2  -AK29M      A01X+116398Y+114626X0180Y         S1      
327m3421            PEX2  -AK28M      A01X+116024Y+114626X0180Y         S1      
327m3421            PEX2  -AK30M      A01X+116772Y+114626X0180Y         S1      
327m3421            PEX2  -AK31M      A01X+117146Y+114626X0180Y         S1      
327m3421            PEX2  -AK33M      A01X+117894Y+114626X0180Y         S1      
327m3421            PEX2  -AK32M      A01X+117520Y+114626X0180Y         S1      
327m3421            PEX2  -AK27M      A01X+115650Y+114626X0180Y         S1      
327m3421            PEX2  -AH26M      A01X+115276Y+115374X0180Y         S1      
327m3421            PEX2  -AH25       A01X+114902Y+115374X0180Y         S1      
327m3421            PEX2  -AH29M      A01X+116398Y+115374X0180Y         S1      
327m3421            PEX2  -AH30M      A01X+116772Y+115374X0180Y         S1      
327m3421            PEX2  -AH31M      A01X+117146Y+115374X0180Y         S1      
327m3421            PEX2  -AH33M      A01X+117894Y+115374X0180Y         S1      
327m3421            PEX2  -AH32M      A01X+117520Y+115374X0180Y         S1      
327m3421            PEX2  -AH28M      A01X+116024Y+115374X0180Y         S1      
327m3421            PEX2  -AH27M      A01X+115650Y+115374X0180Y         S1      
327m3421            PEX2  -AH23       A01X+114154Y+115374X0180Y         S1      
327m3421            PEX2  -AH20       A01X+113031Y+115374X0180Y         S1      
327m3421            PEX2  -AH21       A01X+113405Y+115374X0180Y         S1      
327m3421            PEX2  -AH22       A01X+113780Y+115374X0180Y         S1      
327m3421            PEX2  -AH19       A01X+112657Y+115374X0180Y         S1      
327m3421            PEX2  -AH18       A01X+112283Y+115374X0180Y         S1      
327m3421            PEX2  -AH17       A01X+111909Y+115374X0180Y         S1      
327m3421            PEX2  -AH16       A01X+111535Y+115374X0180Y         S1      
327m3421            PEX2  -AK22M      A01X+113780Y+114626X0180Y         S1      
327m3421            PEX2  -AK21M      A01X+113405Y+114626X0180Y         S1      
327m3421            PEX2  -AK19M      A01X+112657Y+114626X0180Y         S1      
327m3421            PEX2  -AK20M      A01X+113031Y+114626X0180Y         S1      
327m3421            PEX2  -AK24       A01X+114528Y+114626X0180Y         S1      
327m3421            PEX2  -AK23M      A01X+114154Y+114626X0180Y         S1      
327m3421            PEX2  -AK18M      A01X+112283Y+114626X0180Y         S1      
327m3421            PEX2  -AK17M      A01X+111909Y+114626X0180Y         S1      
327m3421            PEX2  -AK16M      A01X+111535Y+114626X0180Y         S1      
327m3422            PC195 -1          A01X+142256Y+110570X0198Y0197R270 S1      
327m3422            PU15  -32         A01X+142453Y+111023X0090Y0240R180 S1      
327m3423            PU18  -10         A01X+094909Y+121996X0120Y0790R180 S1      
327m3423            PU18  -21         A01X+094909Y+120972X0120Y0790R180 S1      
327m3423            PC1009-1          A01X+094742Y+125029X0400Y0500     S1      
327m3423            PL21  -2          A01X+095509Y+125162X0280Y0320R180 S1      
327m3423            PC247 -1          A01X+095542Y+124479X0400Y0500R180 S1      
327m3423            PC245 -1          A01X+094742Y+124339X0400Y0500     S1      
327m3423            PC250 -1          A01X+095542Y+123099X0400Y0500R180 S1      
327m3423            PC246 -1          A01X+095542Y+123789X0400Y0500R180 S1      
327m3423            PC244 -1          A01X+094742Y+122959X0400Y0500     S1      
327m3423            PC249 -1          A01X+094742Y+123649X0400Y0500     S1      
327m3423            PC248 -1          A01X+094948Y+120212X0198Y0197     S1      
327m3424            PU18  -1          A01X+095322Y+120814X0120Y0360R270 S1      
327m3424            PC251 -1          A01X+095652Y+120125X0198Y0197     S1      
327P1V25_PEX2_EN    PU18  -8          A01X+095342Y+121956X0070Y0320R270 S1      
317P1V25_PEX2_EN    VIA   -    M      A01X+095651Y+122011X0200Y         S2      
017P1V25_PEX2_EN    VIA   -    M      A18X+095651Y+122011X0260Y         S2      
017P1V25_PEX2_EN          -    MD0100PA00X+095651Y+122011                       
327P1V25_PEX2_EN    R846  -1          A01X+095900Y+122271X0198Y0197     S1      
317m3425            VIA   -    M      A01X+097076Y+121661X0200Y         S2      
017m3425            VIA   -    M      A18X+097076Y+121661X0260Y         S2      
017m3425                  -    MD0100PA00X+097076Y+121661                       
327m3425            PR176 -1          A01X+096903Y+122272X0198Y0197R180 S1      
327m3425            PJ13  -1          A01X+097305Y+121484X0200Y0400R090 S1      
327m3425            PC980 -1   M      A01X+096905Y+121455X0198Y0197R270 S1      
327m3425            PC260 -2   M      A01X+096903Y+121872X0198Y0197     S1      
327m3426            PU18  -6          A01X+095342Y+121641X0070Y0320R270 S1      
317m3426            VIA   -    M      A01X+096286Y+121418X0200Y         S2      
017m3426            VIA   -    M      A18X+096286Y+121418X0260Y         S2      
017m3426                  -    MD0100PA00X+096286Y+121418                       
327m3426            PR178 -1   M      A01X+096072Y+121579X0198Y0197R090 S1      
327m3426            PC262 -2   M      A01X+096522Y+121481X0198Y0197R090 S1      
327m3426            PC980 -2   M      A01X+096905Y+121140X0198Y0197R270 S1      
327m3426            PJ14  -1          A01X+097305Y+121057X0200Y0400R090 S1      
327P1V25_PEX2_REF   PU18  -5          A01X+095342Y+121484X0070Y0320R270 S1      
317P1V25_PEX2_REF   VIA   -           A01X+096794Y+120782X0200Y         S2      
017P1V25_PEX2_REF   VIA   -           A18X+096794Y+120782X0260Y         S2      
017P1V25_PEX2_REF         -     D0100PA00X+096794Y+120782                       
327P1V25_PEX2_REF   PC262 -1   M      A01X+096522Y+121166X0198Y0197R090 S1      
327P1V25_PEX2_REF   PC261 -1   M      A01X+096537Y+120782X0198Y0197R270 S1      
327P1V25_PEX2_FB    PU18  -7          A01X+095342Y+121799X0070Y0320R270 S1      
317P1V25_PEX2_FB    VIA   -    M      A01X+096326Y+121947X0200Y         S2      
017P1V25_PEX2_FB    VIA   -    M      A18X+096326Y+121947X0260Y         S2      
017P1V25_PEX2_FB          -    MD0100PA00X+096326Y+121947                       
327P1V25_PEX2_FB    PR178 -2   M      A01X+096072Y+121894X0198Y0197R090 S1      
327P1V25_PEX2_FB    PR176 -2          A01X+096588Y+122272X0198Y0197R180 S1      
327P1V25_PEX2_FB    PC260 -1   M      A01X+096588Y+121872X0198Y0197     S1      
327P1V25_PEX2_CS    PU18  -3          A01X+095342Y+121169X0070Y0320R270 S1      
317P1V25_PEX2_CS    VIA   -    M      A01X+095869Y+121042X0200Y         S2      
017P1V25_PEX2_CS    VIA   -    M      A18X+095869Y+121042X0260Y         S2      
017P1V25_PEX2_CS          -    MD0100PA00X+095869Y+121042                       
327P1V25_PEX2_CS    PR177 -1          A01X+096140Y+120898X0198Y0197R270 S1      
327m3427            PU18  -9          A01X+095342Y+122153X0120Y0320R270 S1      
317m3427            VIA   -    M      A01X+096115Y+122526X0200Y         S2      
017m3427            VIA   -    M      A18X+096115Y+122526X0260Y         S2      
017m3427                  -    MD0100PA00X+096115Y+122526                       
327m3427            R4437 -2          A18X+097167Y+122848X0198Y0197R090 S2      
327m3427            R845  -2   M      A18X+097165Y+122421X0198Y0197R270 S2      
327P1V25_PEX2_VCC   PU18  -19         A01X+094240Y+120814X0120Y0320R090 S1      
327P1V25_PEX2_VCC   R845  -1          A18X+097165Y+122106X0198Y0197R270 S2      
327P1V25_PEX2_VCC   PC257 -1          A01X+093679Y+120763X0198Y0197R090 S1      
317P1V25_PEX2_VCC   VIA   -    M      A01X+093930Y+120765X0200Y         S2      
017P1V25_PEX2_VCC   VIA   -    M      A18X+093930Y+120765X0260Y         S2      
017P1V25_PEX2_VCC         -    MD0100PA00X+093930Y+120765                       
327m3428            PU18  -20         A01X+094673Y+120972X0120Y0790R180 S1      
327m3428            PC251 -2          A01X+095967Y+120125X0198Y0197     S1      
327m3428            PL22  -1          A01X+094912Y+118965X1160Y1460R270 S1      
327P1V8_VDDA_PEX3   VIA   -           A18X+153884Y+116864X0260Y         S2      
327P1V8_VDDA_PEX3   VIA   -           A18X+155374Y+119492X0260Y         S2      
327P1V8_VDDA_PEX3   C3536 -1          A18X+156473Y+119301X0120Y0150R180 S2      
327P1V8_VDDA_PEX3   C3517 -1   M      A18X+156145Y+119301X0120Y0150     S2      
327P1V8_VDDA_PEX3   C3510 -1          A18X+156243Y+118909X0280Y0320R090 S2      
327P1V8_VDDA_PEX3   C3532 -1          A18X+156391Y+113691X0120Y0150R180 S2      
327P1V8_VDDA_PEX3   C3531 -1          A18X+165449Y+118179X0120Y0150R180 S2      
327P1V8_VDDA_PEX3   C3511 -1          A18X+165121Y+118179X0120Y0150     S2      
327P1V8_VDDA_PEX3   C3530 -1          A18X+164245Y+118179X0120Y0150R180 S2      
327P1V8_VDDA_PEX3   C3529 -1          A18X+164537Y+119885X0120Y0150R090 S2      
327P1V8_VDDA_PEX3   C3518 -1          A18X+164537Y+120213X0120Y0150R270 S2      
327P1V8_VDDA_PEX3   C3519 -1          A18X+164373Y+113317X0120Y0150     S2      
327P1V8_VDDA_PEX3   C3520 -1          A18X+164373Y+112943X0120Y0150     S2      
327P1V8_VDDA_PEX3   C3534 -1          A18X+154731Y+118179X0120Y0150     S2      
327P1V8_VDDA_PEX3   C3535 -1          A18X+154731Y+117805X0120Y0150     S2      
327P1V8_VDDA_PEX3   C3533 -1          A18X+154731Y+117431X0120Y0150     S2      
317P1V8_VDDA_PEX3   VIA   -    MD0080PA00X+154813Y+118179X0160Y         S0      
317P1V8_VDDA_PEX3   VIA   -    MD0080PA00X+154813Y+117805X0160Y         S0      
317P1V8_VDDA_PEX3   VIA   -    MD0080PA00X+154813Y+117431X0160Y         S0      
317P1V8_VDDA_PEX3   VIA   -    MD0080PA00X+156309Y+113691X0160Y         S0      
317P1V8_VDDA_PEX3   VIA   -    MD0080PA00X+156309Y+119301X0160Y    R270 S0      
317P1V8_VDDA_PEX3   VIA   -    MD0080PA00X+164163Y+118179X0160Y         S0      
317P1V8_VDDA_PEX3   VIA   -    MD0080PA00X+164537Y+120049X0160Y    R180 S0      
317P1V8_VDDA_PEX3   VIA   -    MD0080PA00X+165285Y+118179X0160Y         S0      
317P1V8_VDDA_PEX3   VIA   -    MD0080PA00X+164537Y+112943X0160Y         S0      
327P1V8_VDDA_PEX3   C3592 -1          A01X+147393Y+102766X0280Y0320R090 S1      
327P1V8_VDDA_PEX3   L145  -2          A01X+147522Y+102178X0440Y0540R270 S1      
327P1V8_VDDA_PEX3   R4597 -1          A01X+147894Y+102693X0198Y0197     S1      
327P1V8_VDDA_PEX3   C3594 -1          A01X+147426Y+103299X0120Y0150R090 S1      
317P1V8_VDDA_PEX3   VIA   -    MD0100PA00X+147323Y+103067X0200Y    R090 S0      
317P1V8_VDDA_PEX3   VIA   -    MD0100PA00X+147623Y+103067X0200Y    R090 S0      
327P1V8_VDDA_PEX3   C3593 -1          A01X+147737Y+103300X0120Y0150R090 S1      
327P1V8_VDDA_PEX3   PEX3  -T35        A01X+164350Y+119862X0180Y         S1      
327P1V8_VDDA_PEX3   PEX3  -V14        A01X+156496Y+119114X0180Y         S1      
327P1V8_VDDA_PEX3   PEX3  -AA37       A01X+165098Y+117992X0180Y         S1      
327P1V8_VDDA_PEX3   PEX3  -AA34       A01X+163976Y+117992X0180Y         S1      
327P1V8_VDDA_PEX3   PEX3  -AA10M      A01X+155000Y+117992X0180Y         S1      
327P1V8_VDDA_PEX3   PEX3  -AB10M      A01X+155000Y+117618X0180Y         S1      
327P1V8_VDDA_PEX3   PEX3  -AC10       A01X+155000Y+117244X0180Y         S1      
327P1V8_VDDA_PEX3   VIA   -           A18X+165740Y+112810X0260Y         S2      
327P1V8_VDDA_PEX3   PEX3  -AP35       A01X+164350Y+113130X0180Y         S1      
327P1V8_VDDA_PEX3   PEX3  -AM14       A01X+156496Y+113878X0180Y         S1      
327m3429            C3482 -1          A18X+163789Y+112861X0120Y0150R090 S2      
327m3429            C3506 -1          A18X+163415Y+112861X0120Y0150R090 S2      
327m3429            C3507 -1          A18X+163041Y+112861X0120Y0150R090 S2      
327m3429            C3504 -1          A18X+162667Y+112861X0120Y0150R090 S2      
327m3429            C3505 -1          A18X+162293Y+112861X0120Y0150R090 S2      
327m3429            C3503 -1          A18X+161919Y+112861X0120Y0150R090 S2      
327m3429            C3481 -1          A18X+161545Y+112861X0120Y0150R090 S2      
327m3429            C3467 -1          A18X+160420Y+112961X0280Y0320R180 S2      
327m3429            C3478 -1          A18X+161171Y+112861X0120Y0150R090 S2      
327m3429            C3479 -1          A18X+160797Y+112861X0120Y0150R090 S2      
327m3429            C3473 -1          A18X+160049Y+112861X0120Y0150R090 S2      
327m3429            C3476 -1          A18X+159675Y+112861X0120Y0150R090 S2      
327m3429            C3474 -1          A18X+159301Y+112861X0120Y0150R090 S2      
327m3429            C3475 -1          A18X+158927Y+112861X0120Y0150R090 S2      
327m3429            C3501 -1          A18X+158553Y+112861X0120Y0150R090 S2      
327m3429            C3500 -1          A18X+158179Y+112861X0120Y0150R090 S2      
327m3429            C3491 -1          A18X+157805Y+112861X0120Y0150R090 S2      
327m3429            C3502 -1          A18X+157431Y+112861X0120Y0150R090 S2      
327m3429            C3472 -1          A18X+157057Y+112861X0120Y0150R090 S2      
327m3429            C3494 -1          A18X+163800Y+120131X0120Y0150R270 S2      
327m3429            C3484 -1          A18X+163426Y+120131X0120Y0150R270 S2      
327m3429            C3483 -1          A18X+163052Y+120131X0120Y0150R270 S2      
327m3429            C3477 -1          A18X+162678Y+120131X0120Y0150R270 S2      
327m3429            C3480 -1          A18X+162304Y+120131X0120Y0150R270 S2      
327m3429            C3485 -1          A18X+161930Y+120131X0120Y0150R270 S2      
327m3429            C3486 -1          A18X+161556Y+120131X0120Y0150R270 S2      
327m3429            C3466 -1          A18X+160418Y+120008X0280Y0320     S2      
327m3429            C3496 -1          A18X+161182Y+120131X0120Y0150R270 S2      
327m3429            C3495 -1          A18X+160808Y+120131X0120Y0150R270 S2      
327m3429            C3497 -1          A18X+160028Y+120131X0120Y0150R270 S2      
327m3429            C3487 -1          A18X+159654Y+120131X0120Y0150R270 S2      
327m3429            C3488 -1          A18X+159280Y+120131X0120Y0150R270 S2      
327m3429            C3498 -1          A18X+158906Y+120131X0120Y0150R270 S2      
327m3429            C3499 -1          A18X+158532Y+120131X0120Y0150R270 S2      
327m3429            C3489 -1          A18X+158158Y+120131X0120Y0150R270 S2      
327m3429            C3492 -1          A18X+157784Y+120131X0120Y0150R270 S2      
327m3429            C3490 -1          A18X+157410Y+120131X0120Y0150R270 S2      
327m3429            C3493 -1          A18X+157036Y+120131X0120Y0150R270 S2      
327m3429            C3469 -1          A18X+165741Y+117244X0120Y0150R180 S2      
327m3429            C3468 -1          A18X+165741Y+116870X0120Y0150R180 S2      
327m3429            C3508 -1          A18X+165741Y+116496X0120Y0150R180 S2      
327m3429            C3470 -1          A18X+165741Y+116122X0120Y0150R180 S2      
327m3429            C3471 -1          A18X+165741Y+115748X0120Y0150R180 S2      
317m3429            VIA   -    MD0080PA00X+157805Y+112943X0160Y         S0      
317m3429            VIA   -    MD0080PA00X+157057Y+112943X0160Y         S0      
317m3429            VIA   -    MD0080PA00X+157431Y+112943X0160Y         S0      
317m3429            VIA   -    MD0080PA00X+157431Y+120049X0160Y         S0      
317m3429            VIA   -    MD0080PA00X+157805Y+120049X0160Y         S0      
317m3429            VIA   -    MD0080PA00X+157057Y+120049X0160Y         S0      
317m3429            VIA   -    MD0080PA00X+159301Y+120049X0160Y         S0      
317m3429            VIA   -    MD0080PA00X+158179Y+120049X0160Y         S0      
317m3429            VIA   -    MD0080PA00X+158553Y+120049X0160Y         S0      
317m3429            VIA   -    MD0080PA00X+158927Y+120049X0160Y         S0      
317m3429            VIA   -    MD0080PA00X+159301Y+112943X0160Y         S0      
317m3429            VIA   -    MD0080PA00X+158179Y+112943X0160Y         S0      
317m3429            VIA   -    MD0080PA00X+158553Y+112943X0160Y         S0      
317m3429            VIA   -    MD0080PA00X+158927Y+112943X0160Y         S0      
317m3429            VIA   -    MD0080PA00X+160797Y+120049X0160Y         S0      
317m3429            VIA   -    MD0080PA00X+161171Y+120049X0160Y         S0      
317m3429            VIA   -    MD0080PA00X+159675Y+120049X0160Y         S0      
317m3429            VIA   -    MD0080PA00X+160049Y+120049X0160Y         S0      
317m3429            VIA   -    MD0080PA00X+159675Y+112943X0160Y         S0      
317m3429            VIA   -    MD0080PA00X+160049Y+112943X0160Y         S0      
317m3429            VIA   -    MD0080PA00X+160797Y+112943X0160Y         S0      
317m3429            VIA   -    MD0080PA00X+161171Y+112943X0160Y         S0      
317m3429            VIA   -    MD0080PA00X+161545Y+112943X0160Y         S0      
317m3429            VIA   -    MD0080PA00X+161919Y+112943X0160Y         S0      
317m3429            VIA   -    MD0080PA00X+162293Y+112943X0160Y         S0      
317m3429            VIA   -    MD0080PA00X+162667Y+112943X0160Y         S0      
317m3429            VIA   -    MD0080PA00X+162667Y+120049X0160Y         S0      
317m3429            VIA   -    MD0080PA00X+161545Y+120049X0160Y         S0      
317m3429            VIA   -    MD0080PA00X+161919Y+120049X0160Y         S0      
317m3429            VIA   -    MD0080PA00X+162293Y+120049X0160Y         S0      
317m3429            VIA   -    MD0080PA00X+163415Y+112943X0160Y         S0      
317m3429            VIA   -    MD0080PA00X+163789Y+112943X0160Y         S0      
317m3429            VIA   -    MD0080PA00X+163041Y+112943X0160Y         S0      
317m3429            VIA   -    MD0080PA00X+163415Y+120049X0160Y         S0      
317m3429            VIA   -    MD0080PA00X+163789Y+120049X0160Y         S0      
317m3429            VIA   -    MD0080PA00X+163041Y+120049X0160Y         S0      
317m3429            VIA   -    MD0080PA00X+165659Y+117431X0160Y         S0      
317m3429            VIA   -    MD0080PA00X+165659Y+115935X0160Y         S0      
317m3429            VIA   -    MD0080PA00X+165659Y+116683X0160Y         S0      
317m3429            VIA   -    MD0080PA00X+165659Y+117057X0160Y         S0      
317m3429            VIA   -    MD0080PA00X+165659Y+115561X0160Y         S0      
327m3429            L132  -2   M      A18X+180470Y+105086X0460Y3860R180 S2      
327m3429            R6139 -2A  M      A18X+180519Y+105117X0590Y0790R180 S2      
327m3429            R6139 -2B  M      A18X+180274Y+105117X0100Y0200R180 S2      
327m3429            L131  -2   M      A18X+177056Y+105117X0460Y3860     S2      
327m3429            R6138 -2A  M      A18X+177007Y+105117X0590Y0790     S2      
327m3429            R6138 -2B  M      A18X+177252Y+105117X0100Y0200     S2      
327m3429            C4407 -1          A01X+181678Y+104155X0120Y0150     S1      
327m3429            C4406 -1          A01X+181680Y+104676X0120Y0150     S1      
327m3429            C4393 -1          A01X+181686Y+105122X0120Y0150     S1      
327m3429            C4392 -1          A01X+181697Y+105678X0120Y0150     S1      
327m3429            R6559 -1          A01X+175630Y+101863X0198Y0197R270 S1      
327m3429            R6564 -1          A01X+181626Y+101863X0198Y0197R270 S1      
327m3429            R6556 -1          A01X+180832Y+101863X0198Y0197R270 S1      
327m3429            R6555 -1          A01X+180243Y+101863X0198Y0197R270 S1      
327m3429            R6563 -1          A01X+181226Y+101863X0198Y0197R270 S1      
327m3429            R6554 -1          A01X+179634Y+101863X0198Y0197R270 S1      
327m3429            R6553 -1          A01X+179004Y+101863X0198Y0197R270 S1      
327m3429            R6562 -1          A01X+177804Y+101863X0198Y0197R270 S1      
327m3429            R6552 -1          A01X+178414Y+101863X0198Y0197R270 S1      
327m3429            R6561 -1          A01X+177199Y+101863X0198Y0197R270 S1      
327m3429            R6551 -1          A01X+176513Y+101863X0198Y0197R270 S1      
327m3429            R6560 -1          A01X+176049Y+101863X0198Y0197R270 S1      
327m3429            PEX3  -T17        A01X+157618Y+119862X0180Y         S1      
327m3429            PEX3  -T18        A01X+157992Y+119862X0180Y         S1      
327m3429            PEX3  -T16        A01X+157244Y+119862X0180Y         S1      
327m3429            PEX3  -T22        A01X+159488Y+119862X0180Y         S1      
327m3429            PEX3  -T19        A01X+158366Y+119862X0180Y         S1      
327m3429            PEX3  -T20        A01X+158740Y+119862X0180Y         S1      
327m3429            PEX3  -T21        A01X+159114Y+119862X0180Y         S1      
327m3429            PEX3  -T25        A01X+160610Y+119862X0180Y         S1      
327m3429            PEX3  -T26        A01X+160984Y+119862X0180Y         S1      
327m3429            PEX3  -T23        A01X+159862Y+119862X0180Y         S1      
327m3429            PEX3  -T24        A01X+160236Y+119862X0180Y         S1      
327m3429            PEX3  -T30        A01X+162480Y+119862X0180Y         S1      
327m3429            PEX3  -T27        A01X+161358Y+119862X0180Y         S1      
327m3429            PEX3  -T28        A01X+161732Y+119862X0180Y         S1      
327m3429            PEX3  -T29        A01X+162106Y+119862X0180Y         S1      
327m3429            PEX3  -T32        A01X+163228Y+119862X0180Y         S1      
327m3429            PEX3  -T33        A01X+163602Y+119862X0180Y         S1      
327m3429            PEX3  -T31        A01X+162854Y+119862X0180Y         S1      
327m3429            PEX3  -AC38       A01X+165472Y+117244X0180Y         S1      
327m3429            PEX3  -AD38       A01X+165472Y+116870X0180Y         S1      
327m3429            PEX3  -AE38       A01X+165472Y+116496X0180Y         S1      
327m3429            PEX3  -AF38       A01X+165472Y+116122X0180Y         S1      
327m3429            PEX3  -AG38       A01X+165472Y+115748X0180Y         S1      
327m3429            L133  -2   M      A01X+180470Y+105086X0460Y3860     S1      
327m3429            R6141 -2A  M      A01X+180519Y+105117X0590Y0790     S1      
327m3429            R6141 -2B  M      A01X+180274Y+105117X0100Y0200     S1      
327m3429            L130  -2   M      A01X+177056Y+105117X0460Y3860R180 S1      
327m3429            R6140 -2A  M      A01X+177007Y+105117X0590Y0790R180 S1      
327m3429            R6140 -2B  M      A01X+177252Y+105117X0100Y0200R180 S1      
317m3429            VIA   -    MD0100PA00X+180784Y+102725X0200Y         S0      
317m3429            VIA   -    MD0100PA00X+180784Y+102369X0200Y         S0      
317m3429            VIA   -    MD0100PA00X+179284Y+102725X0200Y         S0      
317m3429            VIA   -    MD0100PA00X+179884Y+102725X0200Y         S0      
317m3429            VIA   -    MD0100PA00X+179584Y+102369X0200Y         S0      
317m3429            VIA   -    MD0100PA00X+180184Y+102369X0200Y         S0      
317m3429            VIA   -    MD0100PA00X+179347Y+101876X0200Y         S0      
317m3429            VIA   -    MD0100PA00X+179965Y+101900X0200Y         S0      
317m3429            VIA   -    MD0100PA00X+180519Y+101908X0200Y         S0      
317m3429            VIA   -    MD0100PA00X+180335Y+102747X0200Y         S0      
317m3429            VIA   -    MD0100PA00X+181147Y+102108X0200Y         S0      
317m3429            VIA   -    M      A01X+175957Y+102194X0200Y         S2      
017m3429            VIA   -    M      A18X+175957Y+102194X0260Y         S2      
017m3429                  -    MD0100PA00X+175957Y+102194                       
317m3429            VIA   -    MD0100PA00X+178984Y+102369X0200Y         S0      
317m3429            VIA   -    MD0100PA00X+177484Y+102725X0200Y         S0      
317m3429            VIA   -    MD0100PA00X+178084Y+102725X0200Y         S0      
317m3429            VIA   -    MD0100PA00X+178684Y+102725X0200Y         S0      
317m3429            VIA   -    MD0100PA00X+178384Y+102369X0200Y         S0      
317m3429            VIA   -    MD0100PA00X+177484Y+102369X0200Y         S0      
317m3429            VIA   -    MD0100PA00X+177486Y+101924X0200Y         S0      
317m3429            VIA   -    MD0100PA00X+178080Y+101947X0200Y         S0      
317m3429            VIA   -    MD0100PA00X+178674Y+101924X0200Y         S0      
317m3429            VIA   -    MD0100PA00X+181035Y+103126X0200Y         S0      
317m3429            VIA   -    M      A01X+177903Y+102343X0200Y         S2      
017m3429            VIA   -    M      A18X+177903Y+102343X0260Y         S2      
017m3429                  -    MD0100PA00X+177903Y+102343                       
317m3429            VIA   -    MD0100PA00X+177177Y+102883X0200Y         S0      
317m3429            VIA   -    MD0100PA00X+176884Y+102725X0200Y         S0      
317m3429            VIA   -    M      A01X+176884Y+102369X0200Y         S2      
017m3429            VIA   -    M      A18X+176884Y+102369X0260Y         S2      
017m3429                  -    MD0100PA00X+176884Y+102369                       
317m3429            VIA   -    MD0100PA00X+176900Y+101940X0200Y         S0      
317m3429            VIA   -    MD0100PA00X+181254Y+102686X0200Y         S0      
327m3429            PEX3  -AP18       A01X+157992Y+113130X0180Y         S1      
327m3429            PEX3  -AP16       A01X+157244Y+113130X0180Y         S1      
327m3429            PEX3  -AP17       A01X+157618Y+113130X0180Y         S1      
327m3429            PEX3  -AP22       A01X+159488Y+113130X0180Y         S1      
327m3429            PEX3  -AP19       A01X+158366Y+113130X0180Y         S1      
327m3429            PEX3  -AP20       A01X+158740Y+113130X0180Y         S1      
327m3429            PEX3  -AP21       A01X+159114Y+113130X0180Y         S1      
327m3429            PEX3  -AP23       A01X+159862Y+113130X0180Y         S1      
327m3429            PEX3  -AP24       A01X+160236Y+113130X0180Y         S1      
327m3429            PEX3  -AP25       A01X+160610Y+113130X0180Y         S1      
327m3429            PEX3  -AP26       A01X+160984Y+113130X0180Y         S1      
327m3429            PEX3  -AP27       A01X+161358Y+113130X0180Y         S1      
327m3429            PEX3  -AP28       A01X+161732Y+113130X0180Y         S1      
327m3429            PEX3  -AP29       A01X+162106Y+113130X0180Y         S1      
327m3429            PEX3  -AP30       A01X+162480Y+113130X0180Y         S1      
327m3429            PEX3  -AP32       A01X+163228Y+113130X0180Y         S1      
327m3429            PEX3  -AP33       A01X+163602Y+113130X0180Y         S1      
327m3429            PEX3  -AP31       A01X+162854Y+113130X0180Y         S1      
327P1V25_PEX3       C3441 -1          A18X+163602Y+113609X0120Y0150R090 S2      
327P1V25_PEX3       C3445 -1          A18X+163228Y+113609X0120Y0150R090 S2      
327P1V25_PEX3       C3444 -1          A18X+162854Y+113609X0120Y0150R090 S2      
327P1V25_PEX3       C3443 -1          A18X+162480Y+113609X0120Y0150R090 S2      
327P1V25_PEX3       C3442 -1          A18X+162106Y+113609X0120Y0150R090 S2      
327P1V25_PEX3       C3446 -1          A18X+161732Y+113609X0120Y0150R090 S2      
327P1V25_PEX3       C3447 -1          A18X+161358Y+113609X0120Y0150R090 S2      
327P1V25_PEX3       C3448 -1          A18X+160984Y+113609X0120Y0150R090 S2      
327P1V25_PEX3       C3453 -1          A18X+160610Y+113609X0120Y0150R090 S2      
327P1V25_PEX3       C3457 -1          A18X+160236Y+113609X0120Y0150R090 S2      
327P1V25_PEX3       C3458 -1          A18X+159862Y+113609X0120Y0150R090 S2      
327P1V25_PEX3       C3463 -1          A18X+159488Y+113609X0120Y0150R090 S2      
327P1V25_PEX3       C3454 -1          A18X+159114Y+113609X0120Y0150R090 S2      
327P1V25_PEX3       C3461 -1          A18X+158740Y+113609X0120Y0150R090 S2      
327P1V25_PEX3       C3451 -1          A18X+158366Y+113609X0120Y0150R090 S2      
327P1V25_PEX3       C3449 -1          A18X+157992Y+113609X0120Y0150R090 S2      
327P1V25_PEX3       C3450 -1          A18X+157618Y+113609X0120Y0150R090 S2      
327P1V25_PEX3       C3456 -1          A18X+157244Y+113609X0120Y0150R090 S2      
327P1V25_PEX3       C3455 -1          A18X+163602Y+119383X0120Y0150R270 S2      
327P1V25_PEX3       C3425 -1          A18X+163228Y+119383X0120Y0150R270 S2      
327P1V25_PEX3       C3426 -1          A18X+162854Y+119383X0120Y0150R270 S2      
327P1V25_PEX3       C3460 -1          A18X+162480Y+119383X0120Y0150R270 S2      
327P1V25_PEX3       C3439 -1          A18X+162106Y+119383X0120Y0150R270 S2      
327P1V25_PEX3       C3429 -1          A18X+161732Y+119383X0120Y0150R270 S2      
327P1V25_PEX3       C3427 -1          A18X+161358Y+119383X0120Y0150R270 S2      
327P1V25_PEX3       C3434 -1          A18X+160984Y+119383X0120Y0150R270 S2      
327P1V25_PEX3       C3428 -1          A18X+160610Y+119383X0120Y0150R270 S2      
327P1V25_PEX3       C3462 -1          A18X+160236Y+119383X0120Y0150R270 S2      
327P1V25_PEX3       C3430 -1          A18X+159862Y+119383X0120Y0150R270 S2      
327P1V25_PEX3       C3435 -1          A18X+159488Y+119383X0120Y0150R270 S2      
327P1V25_PEX3       C3431 -1          A18X+159114Y+119383X0120Y0150R270 S2      
327P1V25_PEX3       C3432 -1          A18X+158740Y+119383X0120Y0150R270 S2      
327P1V25_PEX3       C3436 -1          A18X+158366Y+119383X0120Y0150R270 S2      
327P1V25_PEX3       C3437 -1          A18X+157992Y+119383X0120Y0150R270 S2      
327P1V25_PEX3       C3433 -1          A18X+157618Y+119383X0120Y0150R270 S2      
327P1V25_PEX3       C3438 -1          A18X+157244Y+119383X0120Y0150R270 S2      
327P1V25_PEX3       C3452 -1          A18X+164993Y+115561X0120Y0150R180 S2      
327P1V25_PEX3       C3440 -1          A18X+164993Y+117057X0120Y0150R180 S2      
327P1V25_PEX3       C3459 -1          A18X+164993Y+116683X0120Y0150R180 S2      
327P1V25_PEX3       C3464 -1          A18X+164993Y+115935X0120Y0150R180 S2      
327P1V25_PEX3       C3465 -1          A18X+164993Y+117431X0120Y0150R180 S2      
327P1V25_PEX3       C3424 -1          A18X+167742Y+116308X0280Y0320R270 S2      
327P1V25_PEX3       C3423 -1          A18X+167226Y+116309X0280Y0320R090 S2      
317P1V25_PEX3       VIA   -     D0080PA00X+168278Y+122293X0160Y         S0      
317P1V25_PEX3       VIA   -    MD0080PA00X+157057Y+113691X0160Y         S0      
317P1V25_PEX3       VIA   -    MD0080PA00X+157431Y+113691X0160Y         S0      
317P1V25_PEX3       VIA   -    MD0080PA00X+157805Y+113691X0160Y         S0      
317P1V25_PEX3       VIA   -    MD0080PA00X+157805Y+119301X0160Y         S0      
317P1V25_PEX3       VIA   -    MD0080PA00X+157431Y+119301X0160Y         S0      
317P1V25_PEX3       VIA   -    MD0080PA00X+157057Y+119301X0160Y         S0      
317P1V25_PEX3       VIA   -    MD0080PA00X+158179Y+119301X0160Y         S0      
317P1V25_PEX3       VIA   -    MD0080PA00X+159301Y+119301X0160Y         S0      
317P1V25_PEX3       VIA   -    MD0080PA00X+158927Y+119301X0160Y         S0      
317P1V25_PEX3       VIA   -    MD0080PA00X+158553Y+119301X0160Y         S0      
317P1V25_PEX3       VIA   -    MD0080PA00X+158179Y+113691X0160Y         S0      
317P1V25_PEX3       VIA   -    MD0080PA00X+158553Y+113691X0160Y         S0      
317P1V25_PEX3       VIA   -    MD0080PA00X+158927Y+113691X0160Y         S0      
317P1V25_PEX3       VIA   -    MD0080PA00X+159301Y+113691X0160Y         S0      
317P1V25_PEX3       VIA   -    MD0080PA00X+159675Y+119301X0160Y         S0      
317P1V25_PEX3       VIA   -    MD0080PA00X+160049Y+119301X0160Y         S0      
317P1V25_PEX3       VIA   -    MD0080PA00X+161171Y+119301X0160Y         S0      
317P1V25_PEX3       VIA   -    MD0080PA00X+160797Y+119301X0160Y         S0      
317P1V25_PEX3       VIA   -    MD0080PA00X+160797Y+113691X0160Y         S0      
317P1V25_PEX3       VIA   -    MD0080PA00X+161171Y+113691X0160Y         S0      
317P1V25_PEX3       VIA   -    MD0080PA00X+159675Y+113691X0160Y         S0      
317P1V25_PEX3       VIA   -    MD0080PA00X+160049Y+113691X0160Y         S0      
317P1V25_PEX3       VIA   -    MD0080PA00X+161919Y+113691X0160Y         S0      
317P1V25_PEX3       VIA   -    MD0080PA00X+161545Y+113691X0160Y         S0      
317P1V25_PEX3       VIA   -    MD0080PA00X+162293Y+113691X0160Y         S0      
317P1V25_PEX3       VIA   -    MD0080PA00X+162667Y+113691X0160Y         S0      
317P1V25_PEX3       VIA   -    MD0080PA00X+161919Y+119301X0160Y         S0      
317P1V25_PEX3       VIA   -    MD0080PA00X+161545Y+119301X0160Y         S0      
317P1V25_PEX3       VIA   -    MD0080PA00X+162667Y+119301X0160Y         S0      
317P1V25_PEX3       VIA   -    MD0080PA00X+162293Y+119301X0160Y         S0      
317P1V25_PEX3       VIA   -    MD0080PA00X+163415Y+113691X0160Y         S0      
317P1V25_PEX3       VIA   -    MD0080PA00X+163789Y+113691X0160Y         S0      
317P1V25_PEX3       VIA   -    MD0080PA00X+163041Y+113691X0160Y         S0      
317P1V25_PEX3       VIA   -    MD0080PA00X+163041Y+119301X0160Y         S0      
317P1V25_PEX3       VIA   -    MD0080PA00X+163789Y+119301X0160Y         S0      
317P1V25_PEX3       VIA   -    MD0080PA00X+163415Y+119301X0160Y         S0      
317P1V25_PEX3       VIA   -    MD0080PA00X+164911Y+117431X0160Y         S0      
317P1V25_PEX3       VIA   -    MD0080PA00X+164911Y+116683X0160Y         S0      
317P1V25_PEX3       VIA   -    MD0080PA00X+164911Y+117057X0160Y         S0      
317P1V25_PEX3       VIA   -    MD0080PA00X+164911Y+115935X0160Y         S0      
317P1V25_PEX3       VIA   -    MD0080PA00X+164911Y+115561X0160Y         S0      
317P1V25_PEX3       VIA   -    MD0080PA00X+167530Y+115935X0160Y    R090 S0      
317P1V25_PEX3       VIA   -    MD0080PA00X+167530Y+116683X0160Y    R180 S0      
317P1V25_PEX3       VIA   -    MD0080PA00X+167904Y+116683X0160Y    R180 S0      
327P1V25_PEX3       C4405 -1          A18X+177196Y+109084X0120Y0150     S2      
327P1V25_PEX3       C4403 -1          A18X+180238Y+107448X0280Y0320R270 S2      
327P1V25_PEX3       C4390 -1          A18X+178949Y+109125X0120Y0150R180 S2      
327P1V25_PEX3       C4391 -1          A18X+177204Y+107361X0120Y0150     S2      
327P1V25_PEX3       C4404 -1          A18X+177196Y+107672X0120Y0150     S2      
327P1V25_PEX3       C4386 -1          A18X+177399Y+108087X0280Y0320R090 S2      
327P1V25_PEX3       C4387 -1          A18X+177392Y+108611X0280Y0320R090 S2      
327P1V25_PEX3       C4402 -1          A18X+177402Y+109580X0280Y0320R090 S2      
327P1V25_PEX3       C4401 -1          A18X+178354Y+110108X0280Y0320R270 S2      
327P1V25_PEX3       C4400 -1          A18X+178879Y+109563X0280Y0320R270 S2      
327P1V25_PEX3       C4388 -1          A18X+177392Y+110116X0280Y0320R090 S2      
327P1V25_PEX3       C4389 -1          A01X+180296Y+107569X0280Y0320R270 S1      
327P1V25_PEX3       PEX3  -V21 M      A01X+159114Y+119114X0180Y         S1      
327P1V25_PEX3       PEX3  -V20 M      A01X+158740Y+119114X0180Y         S1      
327P1V25_PEX3       PEX3  -V19 M      A01X+158366Y+119114X0180Y         S1      
327P1V25_PEX3       PEX3  -V18 M      A01X+157992Y+119114X0180Y         S1      
327P1V25_PEX3       PEX3  -V22 M      A01X+159488Y+119114X0180Y         S1      
327P1V25_PEX3       PEX3  -V23 M      A01X+159862Y+119114X0180Y         S1      
327P1V25_PEX3       PEX3  -V24        A01X+160236Y+119114X0180Y         S1      
327P1V25_PEX3       PEX3  -V17 M      A01X+157618Y+119114X0180Y         S1      
327P1V25_PEX3       PEX3  -V16 M      A01X+157244Y+119114X0180Y         S1      
327P1V25_PEX3       PEX3  -V26 M      A01X+160984Y+119114X0180Y         S1      
327P1V25_PEX3       PEX3  -V25        A01X+160610Y+119114X0180Y         S1      
327P1V25_PEX3       PEX3  -V28        A01X+161732Y+119114X0180Y         S1      
327P1V25_PEX3       PEX3  -V27        A01X+161358Y+119114X0180Y         S1      
327P1V25_PEX3       PEX3  -V30        A01X+162480Y+119114X0180Y         S1      
327P1V25_PEX3       PEX3  -V29        A01X+162106Y+119114X0180Y         S1      
327P1V25_PEX3       PEX3  -V31        A01X+162854Y+119114X0180Y         S1      
327P1V25_PEX3       PEX3  -V33        A01X+163602Y+119114X0180Y         S1      
327P1V25_PEX3       PEX3  -V32        A01X+163228Y+119114X0180Y         S1      
327P1V25_PEX3       PEX3  -AM25       A01X+160610Y+113878X0180Y         S1      
327P1V25_PEX3       PEX3  -AM27M      A01X+161358Y+113878X0180Y         S1      
327P1V25_PEX3       PEX3  -AM28M      A01X+161732Y+113878X0180Y         S1      
327P1V25_PEX3       PEX3  -AM29M      A01X+162106Y+113878X0180Y         S1      
327P1V25_PEX3       PEX3  -AM30M      A01X+162480Y+113878X0180Y         S1      
327P1V25_PEX3       PEX3  -AM31M      A01X+162854Y+113878X0180Y         S1      
327P1V25_PEX3       PEX3  -AM32M      A01X+163228Y+113878X0180Y         S1      
327P1V25_PEX3       PEX3  -AM33M      A01X+163602Y+113878X0180Y         S1      
327P1V25_PEX3       PEX3  -AM26M      A01X+160984Y+113878X0180Y         S1      
327P1V25_PEX3       PEX3  -AM17M      A01X+157618Y+113878X0180Y         S1      
327P1V25_PEX3       PEX3  -AM18M      A01X+157992Y+113878X0180Y         S1      
327P1V25_PEX3       PEX3  -AM20M      A01X+158740Y+113878X0180Y         S1      
327P1V25_PEX3       PEX3  -AM21M      A01X+159114Y+113878X0180Y         S1      
327P1V25_PEX3       PEX3  -AM23M      A01X+159862Y+113878X0180Y         S1      
327P1V25_PEX3       PEX3  -AM24       A01X+160236Y+113878X0180Y         S1      
327P1V25_PEX3       PEX3  -AM22M      A01X+159488Y+113878X0180Y         S1      
327P1V25_PEX3       PEX3  -AM19M      A01X+158366Y+113878X0180Y         S1      
327P1V25_PEX3       PEX3  -AM16M      A01X+157244Y+113878X0180Y         S1      
317P1V25_PEX3       VIA   -    MD0100PA00X+179074Y+107459X0200Y    R090 S0      
317P1V25_PEX3       VIA   -    MD0100PA00X+179074Y+107209X0200Y    R090 S0      
317P1V25_PEX3       VIA   -    MD0100PA00X+178120Y+107221X0200Y    R090 S0      
317P1V25_PEX3       VIA   -    MD0100PA00X+177860Y+107221X0200Y    R090 S0      
317P1V25_PEX3       VIA   -    MD0100PA00X+178380Y+107221X0200Y    R090 S0      
317P1V25_PEX3       VIA   -    MD0100PA00X+178380Y+107471X0200Y    R090 S0      
317P1V25_PEX3       VIA   -    MD0100PA00X+177860Y+107471X0200Y    R090 S0      
317P1V25_PEX3       VIA   -    MD0100PA00X+178120Y+107471X0200Y    R090 S0      
317P1V25_PEX3       VIA   -    MD0100PA00X+177600Y+107221X0200Y    R090 S0      
317P1V25_PEX3       VIA   -    MD0100PA00X+177600Y+107471X0200Y    R090 S0      
317P1V25_PEX3       VIA   -    MD0100PA00X+179594Y+107459X0200Y    R090 S0      
317P1V25_PEX3       VIA   -    MD0100PA00X+179334Y+107459X0200Y    R090 S0      
317P1V25_PEX3       VIA   -    MD0100PA00X+179854Y+107459X0200Y    R090 S0      
317P1V25_PEX3       VIA   -    MD0100PA00X+179854Y+107209X0200Y    R090 S0      
317P1V25_PEX3       VIA   -    MD0100PA00X+179334Y+107209X0200Y    R090 S0      
317P1V25_PEX3       VIA   -    MD0100PA00X+179594Y+107209X0200Y    R090 S0      
317P1V25_PEX3       VIA   -    MD0100PA00X+179057Y+108515X0200Y         S0      
317P1V25_PEX3       VIA   -    MD0100PA00X+179064Y+108258X0200Y         S0      
317P1V25_PEX3       VIA   -    MD0100PA00X+177513Y+109235X0200Y    R090 S0      
317P1V25_PEX3       VIA   -    MD0100PA00X+177513Y+108985X0200Y    R090 S0      
317P1V25_PEX3       VIA   -    MD0100PA00X+178033Y+109235X0200Y    R090 S0      
317P1V25_PEX3       VIA   -    MD0100PA00X+177773Y+109235X0200Y    R090 S0      
317P1V25_PEX3       VIA   -    MD0100PA00X+178293Y+109235X0200Y    R090 S0      
317P1V25_PEX3       VIA   -    MD0100PA00X+178293Y+108985X0200Y    R090 S0      
317P1V25_PEX3       VIA   -    MD0100PA00X+177773Y+108985X0200Y    R090 S0      
317P1V25_PEX3       VIA   -    MD0100PA00X+178033Y+108985X0200Y    R090 S0      
327P1V25_PEX3       PEX3  -AG36       A01X+164724Y+115748X0180Y         S1      
327P1V25_PEX3       PJ15  -2          A01X+182018Y+121532X0180Y0200R180 S1      
317P1V25_PEX3       VIA   -    MD0100PA00X+182259Y+121532X0200Y         S0      
327P1V25_PEX3       PEX3  -AC36M      A01X+164724Y+117244X0180Y         S1      
327P1V25_PEX3       PEX3  -AD36M      A01X+164724Y+116870X0180Y         S1      
327P1V25_PEX3       PEX3  -AE36       A01X+164724Y+116496X0180Y         S1      
327P1V25_PEX3       PEX3  -AF36       A01X+164724Y+116122X0180Y         S1      
327P1V25_PEX3       R6138 -1B  M      A18X+178101Y+105117X0100Y0200     S2      
327P1V25_PEX3       R6138 -1A  M      A18X+178346Y+105117X0590Y0790     S2      
327P1V25_PEX3       L131  -1   M      A18X+178296Y+105117X0460Y3860     S2      
327P1V25_PEX3       R6139 -1B  M      A18X+179425Y+105117X0100Y0200R180 S2      
327P1V25_PEX3       R6139 -1A  M      A18X+179180Y+105117X0590Y0790R180 S2      
327P1V25_PEX3       L132  -1   M      A18X+179230Y+105086X0460Y3860R180 S2      
327P1V25_PEX3       VIA   -           A18X+178156Y+108208X0260Y         S2      
327P1V25_PEX3       VIA   -           A18X+179261Y+107939X0260Y         S2      
327P1V25_PEX3       R6140 -1B  M      A01X+178101Y+105117X0100Y0200R180 S1      
327P1V25_PEX3       R6140 -1A  M      A01X+178346Y+105117X0590Y0790R180 S1      
327P1V25_PEX3       L130  -1   M      A01X+178296Y+105117X0460Y3860R180 S1      
327P1V25_PEX3       R6141 -1B  M      A01X+179425Y+105117X0100Y0200     S1      
327P1V25_PEX3       R6141 -1A  M      A01X+179180Y+105117X0590Y0790     S1      
327P1V25_PEX3       L133  -1   M      A01X+179230Y+105086X0460Y3860     S1      
327P1V25_PEX3       R804  -1          A01X+177944Y+108245X1150Y1380R090 S1      
327P1V25_PEX3       R811  -1          A01X+178980Y+108786X0198Y0197     S1      
327P1V25_PEX3       VIA   -           A18X+164873Y+116311X0260Y         S2      
327P3V3_BIC_SPI     R457  -1          A18X+090707Y+083286X0280Y0320R270 S2      
327P3V3_BIC_SPI     C2027 -1          A18X+090688Y+083688X0164Y0164R180 S2      
327P3V3_BIC_SPI     VIA   -           A18X+091510Y+083870X0260Y         S2      
317P3V3_BIC_SPI     VIA   -    MD0100PA00X+090656Y+083899X0180Y    R180 S0      
327P3V3_BIC_SPI     U5    -B8         A01X+090499Y+084057X0160Y    R180 S1      
327P1V2_BIC_PLL     C2023 -1          A18X+093427Y+085317X0164Y0164R270 S2      
327P1V2_BIC_PLL     C2022 -1          A18X+093077Y+085317X0164Y0164R270 S2      
327P1V2_BIC_PLL     L1    -1          A18X+093613Y+084937X0280Y0320R270 S2      
327P1V2_BIC_PLL     VIA   -           A18X+093088Y+084897X0260Y         S2      
327P1V2_BIC_PLL     U5    -G3         A01X+092074Y+085632X0160Y    R180 S1      
317P1V2_BIC_PLL     VIA   -    MD0100PA00X+092231Y+085474X0180Y    R270 S0      
327P1V2_BIC_PLL     C2021 -1          A18X+092389Y+085317X0164Y0164R270 S2      
327P1V2_BIC_PLL     C2024 -1          A18X+092744Y+085317X0164Y0164R270 S2      
327P1V25_PEX1_REF   PU17  -5          A01X+088944Y+121484X0070Y0320R270 S1      
317P1V25_PEX1_REF   VIA   -           A01X+090396Y+120782X0200Y    R180 S2      
017P1V25_PEX1_REF   VIA   -           A18X+090396Y+120782X0260Y    R180 S2      
017P1V25_PEX1_REF         -     D0100PA00X+090396Y+120782                       
327P1V25_PEX1_REF   PC242 -1   M      A01X+090124Y+121166X0198Y0197R090 S1      
327P1V25_PEX1_REF   PC241 -1   M      A01X+090139Y+120782X0198Y0197R270 S1      
327m3430            PU17  -1          A01X+088925Y+120814X0120Y0360R270 S1      
327m3430            PC231 -1          A01X+089254Y+120125X0198Y0197     S1      
327m3431            PU17  -9          A01X+088944Y+122153X0120Y0320R270 S1      
327m3431            R4436 -2          A01X+091273Y+122808X0198Y0197R090 S1      
327m3431            R843  -2   M      A01X+090885Y+122808X0198Y0197R090 S1      
317m3431            VIA   -    MD0100PA00X+090631Y+122665X0200Y         S0      
317m3431            VIA   -    M      A01X+089717Y+122526X0200Y         S2      
017m3431            VIA   -    M      A18X+089717Y+122526X0260Y         S2      
017m3431                  -    MD0100PA00X+089717Y+122526                       
317m3432            VIA   -    M      A01X+090678Y+121661X0200Y         S2      
017m3432            VIA   -    M      A18X+090678Y+121661X0260Y         S2      
017m3432                  -    MD0100PA00X+090678Y+121661                       
327m3432            PR171 -1          A01X+090505Y+122272X0198Y0197R180 S1      
327m3432            PJ11  -1          A01X+090907Y+121484X0200Y0400R090 S1      
327m3432            PC979 -1   M      A01X+090507Y+121455X0198Y0197R270 S1      
327m3432            PC240 -2   M      A01X+090505Y+121872X0198Y0197     S1      
327m3433            PU17  -20         A01X+088275Y+120972X0120Y0790R180 S1      
327m3433            PC231 -2          A01X+089569Y+120125X0198Y0197     S1      
327m3433            PL20  -1          A01X+088514Y+118965X1160Y1460R270 S1      
327P1V25_PEX1_VCC   PU17  -19         A01X+087842Y+120814X0120Y0320R090 S1      
317P1V25_PEX1_VCC   VIA   -    MD0100PA00X+091063Y+122280X0200Y         S0      
327P1V25_PEX1_VCC   R843  -1          A01X+090885Y+122493X0198Y0197R090 S1      
327P1V25_PEX1_VCC   PC237 -1          A01X+087282Y+120763X0198Y0197R090 S1      
317P1V25_PEX1_VCC   VIA   -    M      A01X+087532Y+120765X0200Y         S2      
017P1V25_PEX1_VCC   VIA   -    M      A18X+087532Y+120765X0260Y         S2      
017P1V25_PEX1_VCC         -    MD0100PA00X+087532Y+120765                       
327P1V25_PEX1       C3112 -1          A18X+072185Y+119383X0120Y0150R270 S2      
327P1V25_PEX1       C3085 -1          A18X+070315Y+119383X0120Y0150R270 S2      
327P1V25_PEX1       C3086 -1          A18X+071811Y+119383X0120Y0150R270 S2      
327P1V25_PEX1       C3083 -1          A18X+071437Y+119383X0120Y0150R270 S2      
327P1V25_PEX1       C3104 -1          A18X+071063Y+119383X0120Y0150R270 S2      
327P1V25_PEX1       C3092 -1          A18X+070689Y+119383X0120Y0150R270 S2      
327P1V25_PEX1       C3076 -1          A18X+069941Y+119383X0120Y0150R270 S2      
327P1V25_PEX1       C3084 -1          A18X+069193Y+119383X0120Y0150R270 S2      
327P1V25_PEX1       C3089 -1          A18X+069567Y+119383X0120Y0150R270 S2      
327P1V25_PEX1       C3117 -1          A18X+068819Y+119383X0120Y0150R270 S2      
327P1V25_PEX1       C3078 -1          A18X+067323Y+119383X0120Y0150R270 S2      
327P1V25_PEX1       C3081 -1          A18X+067697Y+119383X0120Y0150R270 S2      
327P1V25_PEX1       C3090 -1          A18X+068071Y+119383X0120Y0150R270 S2      
327P1V25_PEX1       C3091 -1          A18X+068445Y+119383X0120Y0150R270 S2      
327P1V25_PEX1       C3077 -1          A18X+066201Y+119383X0120Y0150R270 S2      
327P1V25_PEX1       C3079 -1          A18X+065827Y+119383X0120Y0150R270 S2      
327P1V25_PEX1       C3087 -1          A18X+066575Y+119383X0120Y0150R270 S2      
327P1V25_PEX1       C3088 -1          A18X+066949Y+119383X0120Y0150R270 S2      
317P1V25_PEX1       VIA   -    MD0080PA00X+066762Y+113691X0160Y         S0      
317P1V25_PEX1       VIA   -    MD0080PA00X+065640Y+113691X0160Y         S0      
317P1V25_PEX1       VIA   -    MD0080PA00X+066014Y+113691X0160Y         S0      
317P1V25_PEX1       VIA   -    MD0080PA00X+066388Y+113691X0160Y         S0      
317P1V25_PEX1       VIA   -    MD0080PA00X+066762Y+119301X0160Y         S0      
317P1V25_PEX1       VIA   -    MD0080PA00X+065640Y+119301X0160Y         S0      
317P1V25_PEX1       VIA   -    MD0080PA00X+066014Y+119301X0160Y         S0      
317P1V25_PEX1       VIA   -    MD0080PA00X+066388Y+119301X0160Y         S0      
317P1V25_PEX1       VIA   -    MD0080PA00X+068632Y+113691X0160Y         S0      
317P1V25_PEX1       VIA   -    MD0080PA00X+067136Y+113691X0160Y         S0      
317P1V25_PEX1       VIA   -    MD0080PA00X+067510Y+113691X0160Y         S0      
317P1V25_PEX1       VIA   -    MD0080PA00X+067884Y+113691X0160Y         S0      
317P1V25_PEX1       VIA   -    MD0080PA00X+068258Y+113691X0160Y         S0      
317P1V25_PEX1       VIA   -    MD0080PA00X+068632Y+119301X0160Y         S0      
317P1V25_PEX1       VIA   -    MD0080PA00X+067136Y+119301X0160Y         S0      
317P1V25_PEX1       VIA   -    MD0080PA00X+067510Y+119301X0160Y         S0      
317P1V25_PEX1       VIA   -    MD0080PA00X+067884Y+119301X0160Y         S0      
317P1V25_PEX1       VIA   -    MD0080PA00X+068258Y+119301X0160Y         S0      
317P1V25_PEX1       VIA   -    MD0080PA00X+069380Y+119301X0160Y         S0      
317P1V25_PEX1       VIA   -    MD0080PA00X+069754Y+119301X0160Y         S0      
317P1V25_PEX1       VIA   -    MD0080PA00X+070128Y+119301X0160Y         S0      
317P1V25_PEX1       VIA   -    MD0080PA00X+070128Y+113691X0160Y         S0      
317P1V25_PEX1       VIA   -    MD0080PA00X+069380Y+113691X0160Y         S0      
317P1V25_PEX1       VIA   -    MD0080PA00X+069754Y+113691X0160Y         S0      
317P1V25_PEX1       VIA   -    MD0080PA00X+071624Y+119301X0160Y         S0      
317P1V25_PEX1       VIA   -    MD0080PA00X+070502Y+119301X0160Y         S0      
317P1V25_PEX1       VIA   -    MD0080PA00X+071250Y+119301X0160Y         S0      
317P1V25_PEX1       VIA   -    MD0080PA00X+070876Y+119301X0160Y         S0      
317P1V25_PEX1       VIA   -    MD0080PA00X+071250Y+113691X0160Y         S0      
317P1V25_PEX1       VIA   -    MD0080PA00X+070876Y+113691X0160Y         S0      
317P1V25_PEX1       VIA   -    MD0080PA00X+070502Y+113691X0160Y         S0      
317P1V25_PEX1       VIA   -    MD0080PA00X+071624Y+113691X0160Y         S0      
317P1V25_PEX1       VIA   -    MD0080PA00X+073494Y+117057X0160Y         S0      
317P1V25_PEX1       VIA   -    MD0080PA00X+073494Y+116683X0160Y         S0      
317P1V25_PEX1       VIA   -    MD0080PA00X+073494Y+115935X0160Y         S0      
317P1V25_PEX1       VIA   -    MD0080PA00X+073494Y+115561X0160Y         S0      
317P1V25_PEX1       VIA   -    MD0080PA00X+072372Y+113691X0160Y         S0      
317P1V25_PEX1       VIA   -    MD0080PA00X+071998Y+113691X0160Y         S0      
317P1V25_PEX1       VIA   -    MD0080PA00X+072372Y+119301X0160Y         S0      
317P1V25_PEX1       VIA   -    MD0080PA00X+071998Y+119301X0160Y         S0      
317P1V25_PEX1       VIA   -    MD0080PA00X+073494Y+117431X0160Y         S0      
317P1V25_PEX1       VIA   -    MD0080PA00X+076112Y+115935X0160Y         S0      
317P1V25_PEX1       VIA   -    MD0080PA00X+076112Y+116683X0160Y         S0      
317P1V25_PEX1       VIA   -    MD0080PA00X+076486Y+116683X0160Y         S0      
327P1V25_PEX1       R789  -1          A01X+088184Y+108738X0198Y0197     S1      
327P1V25_PEX1       R781  -1          A01X+087125Y+108180X1150Y1380R090 S1      
327P1V25_PEX1       R6132 -1B  M      A01X+088630Y+105068X0100Y0200     S1      
327P1V25_PEX1       R6132 -1A  M      A01X+088385Y+105068X0590Y0790     S1      
327P1V25_PEX1       L100  -1   M      A01X+088434Y+105037X0460Y3860     S1      
327P1V25_PEX1       R6131 -1B  M      A01X+087305Y+105068X0100Y0200R180 S1      
327P1V25_PEX1       R6131 -1A  M      A01X+087550Y+105068X0590Y0790R180 S1      
327P1V25_PEX1       L99   -1   M      A01X+087501Y+105068X0460Y3860R180 S1      
327P1V25_PEX1       C4274 -1          A18X+089386Y+107451X0280Y0320R270 S2      
327P1V25_PEX1       C4293 -1          A18X+087000Y+110091X0120Y0150R270 S2      
327P1V25_PEX1       C4292 -1          A18X+087688Y+110096X0120Y0150R270 S2      
327P1V25_PEX1       C4279 -1          A18X+087326Y+110096X0120Y0150R270 S2      
327P1V25_PEX1       C4288 -1          A18X+086001Y+107330X0280Y0320R090 S2      
327P1V25_PEX1       C4278 -1          A18X+088116Y+110070X0120Y0150R180 S2      
327P1V25_PEX1       C4276 -1          A18X+085985Y+108392X0280Y0320R090 S2      
327P1V25_PEX1       C4289 -1          A18X+088165Y+109344X0280Y0320R270 S2      
327P1V25_PEX1       C4277 -1          A18X+085999Y+107851X0280Y0320R090 S2      
327P1V25_PEX1       C4275 -1          A18X+085985Y+108926X0280Y0320R090 S2      
327P1V25_PEX1       C4291 -1          A18X+085983Y+109472X0280Y0320R090 S2      
327P1V25_PEX1       C4290 -1          A18X+085978Y+110073X0280Y0320R090 S2      
327P1V25_PEX1       PEX1  -AM20M      A01X+067323Y+113878X0180Y         S1      
327P1V25_PEX1       PEX1  -AM21M      A01X+067697Y+113878X0180Y         S1      
327P1V25_PEX1       PEX1  -AM24       A01X+068819Y+113878X0180Y         S1      
327P1V25_PEX1       PEX1  -AM23M      A01X+068445Y+113878X0180Y         S1      
327P1V25_PEX1       PEX1  -AM22M      A01X+068071Y+113878X0180Y         S1      
327P1V25_PEX1       PEX1  -AM19M      A01X+066949Y+113878X0180Y         S1      
327P1V25_PEX1       PEX1  -AM16M      A01X+065827Y+113878X0180Y         S1      
327P1V25_PEX1       PEX1  -AM17M      A01X+066201Y+113878X0180Y         S1      
327P1V25_PEX1       PEX1  -AM18M      A01X+066575Y+113878X0180Y         S1      
327P1V25_PEX1       C3097 -1          A18X+066949Y+113609X0120Y0150R090 S2      
327P1V25_PEX1       C3098 -1          A18X+066201Y+113609X0120Y0150R090 S2      
327P1V25_PEX1       C3115 -1          A18X+066575Y+113609X0120Y0150R090 S2      
327P1V25_PEX1       C3094 -1          A18X+065827Y+113609X0120Y0150R090 S2      
327P1V25_PEX1       C3101 -1          A18X+067697Y+113609X0120Y0150R090 S2      
327P1V25_PEX1       C3116 -1          A18X+068071Y+113609X0120Y0150R090 S2      
327P1V25_PEX1       C3093 -1          A18X+068445Y+113609X0120Y0150R090 S2      
327P1V25_PEX1       C3100 -1          A18X+067323Y+113609X0120Y0150R090 S2      
327P1V25_PEX1       PEX1  -AM27M      A01X+069941Y+113878X0180Y         S1      
327P1V25_PEX1       PEX1  -AM26M      A01X+069567Y+113878X0180Y         S1      
327P1V25_PEX1       PEX1  -AM32M      A01X+071811Y+113878X0180Y         S1      
327P1V25_PEX1       PEX1  -AM33M      A01X+072185Y+113878X0180Y         S1      
327P1V25_PEX1       PEX1  -AM31M      A01X+071437Y+113878X0180Y         S1      
327P1V25_PEX1       PEX1  -AM30M      A01X+071063Y+113878X0180Y         S1      
327P1V25_PEX1       PEX1  -AM28M      A01X+070315Y+113878X0180Y         S1      
327P1V25_PEX1       PEX1  -AM29M      A01X+070689Y+113878X0180Y         S1      
327P1V25_PEX1       PEX1  -AM25       A01X+069193Y+113878X0180Y         S1      
327P1V25_PEX1       C3096 -1          A18X+068819Y+113609X0120Y0150R090 S2      
327P1V25_PEX1       C3099 -1          A18X+069193Y+113609X0120Y0150R090 S2      
327P1V25_PEX1       C3105 -1          A18X+069941Y+113609X0120Y0150R090 S2      
327P1V25_PEX1       C3107 -1          A18X+069567Y+113609X0120Y0150R090 S2      
327P1V25_PEX1       C3109 -1          A18X+070689Y+113609X0120Y0150R090 S2      
327P1V25_PEX1       C3108 -1          A18X+071437Y+113609X0120Y0150R090 S2      
327P1V25_PEX1       C3095 -1          A18X+071063Y+113609X0120Y0150R090 S2      
327P1V25_PEX1       C3106 -1          A18X+071811Y+113609X0120Y0150R090 S2      
327P1V25_PEX1       C3111 -1          A18X+070315Y+113609X0120Y0150R090 S2      
327P1V25_PEX1       C3103 -1          A18X+072185Y+113609X0120Y0150R090 S2      
327P1V25_PEX1       PEX1  -V32        A01X+071811Y+119114X0180Y         S1      
327P1V25_PEX1       PEX1  -V33        A01X+072185Y+119114X0180Y         S1      
327P1V25_PEX1       PEX1  -V29        A01X+070689Y+119114X0180Y         S1      
327P1V25_PEX1       PEX1  -V30        A01X+071063Y+119114X0180Y         S1      
327P1V25_PEX1       PEX1  -V28        A01X+070315Y+119114X0180Y         S1      
327P1V25_PEX1       PEX1  -V31        A01X+071437Y+119114X0180Y         S1      
327P1V25_PEX1       PEX1  -V27        A01X+069941Y+119114X0180Y         S1      
327P1V25_PEX1       PEX1  -V25        A01X+069193Y+119114X0180Y         S1      
327P1V25_PEX1       PEX1  -V26 M      A01X+069567Y+119114X0180Y         S1      
327P1V25_PEX1       PEX1  -V19 M      A01X+066949Y+119114X0180Y         S1      
327P1V25_PEX1       PEX1  -V22 M      A01X+068071Y+119114X0180Y         S1      
327P1V25_PEX1       PEX1  -V23 M      A01X+068445Y+119114X0180Y         S1      
327P1V25_PEX1       PEX1  -V24        A01X+068819Y+119114X0180Y         S1      
327P1V25_PEX1       PEX1  -V21 M      A01X+067697Y+119114X0180Y         S1      
327P1V25_PEX1       PEX1  -V20 M      A01X+067323Y+119114X0180Y         S1      
327P1V25_PEX1       PEX1  -V18 M      A01X+066575Y+119114X0180Y         S1      
327P1V25_PEX1       PEX1  -V17 M      A01X+066201Y+119114X0180Y         S1      
327P1V25_PEX1       PEX1  -V16 M      A01X+065827Y+119114X0180Y         S1      
327P1V25_PEX1       C3075 -1          A18X+075808Y+116309X0280Y0320R090 S2      
327P1V25_PEX1       C3082 -1          A18X+076325Y+116308X0280Y0320R270 S2      
327P1V25_PEX1       C3113 -1          A18X+073576Y+117431X0120Y0150R180 S2      
327P1V25_PEX1       C3114 -1          A18X+073576Y+115935X0120Y0150R180 S2      
327P1V25_PEX1       C3080 -1          A18X+073576Y+117057X0120Y0150R180 S2      
327P1V25_PEX1       C3102 -1          A18X+073576Y+116683X0120Y0150R180 S2      
327P1V25_PEX1       PEX1  -AF36       A01X+073307Y+116122X0180Y         S1      
327P1V25_PEX1       VIA   -           A18X+087560Y+109620X0260Y         S2      
327P1V25_PEX1       C3110 -1          A18X+073576Y+115561X0120Y0150R180 S2      
327P1V25_PEX1       PEX1  -AG36       A01X+073307Y+115748X0180Y         S1      
327P1V25_PEX1       PEX1  -AC36M      A01X+073307Y+117244X0180Y         S1      
327P1V25_PEX1       PEX1  -AE36       A01X+073307Y+116496X0180Y         S1      
327P1V25_PEX1       PEX1  -AD36M      A01X+073307Y+116870X0180Y         S1      
317P1V25_PEX1       VIA   -    MD0100PA00X+091464Y+121484X0200Y         S0      
327P1V25_PEX1       PJ11  -2          A01X+091222Y+121484X0180Y0200R180 S1      
327P1V25_PEX1       VIA   -           A18X+086990Y+107908X0260Y         S2      
327P1V25_PEX1       L98   -1   M      A18X+088434Y+105037X0460Y3860R180 S2      
327P1V25_PEX1       R6130 -1A  M      A18X+088385Y+105068X0590Y0790R180 S2      
327P1V25_PEX1       R6130 -1B  M      A18X+088630Y+105068X0100Y0200R180 S2      
327P1V25_PEX1       L101  -1   M      A18X+087501Y+105068X0460Y3860     S2      
327P1V25_PEX1       R6133 -1A  M      A18X+087550Y+105068X0590Y0790     S2      
327P1V25_PEX1       R6133 -1B  M      A18X+087305Y+105068X0100Y0200     S2      
317P1V25_PEX1       VIA   -    MD0100PA00X+088262Y+108467X0200Y         S0      
317P1V25_PEX1       VIA   -    MD0100PA00X+087266Y+109160X0200Y    R090 S0      
317P1V25_PEX1       VIA   -    MD0100PA00X+086746Y+108910X0200Y    R090 S0      
317P1V25_PEX1       VIA   -    MD0100PA00X+086746Y+109160X0200Y    R090 S0      
317P1V25_PEX1       VIA   -    MD0100PA00X+088012Y+108467X0200Y         S0      
317P1V25_PEX1       VIA   -    MD0100PA00X+087266Y+108910X0200Y    R090 S0      
317P1V25_PEX1       VIA   -    MD0100PA00X+087006Y+108910X0200Y    R090 S0      
317P1V25_PEX1       VIA   -    MD0100PA00X+087526Y+108910X0200Y    R090 S0      
317P1V25_PEX1       VIA   -    MD0100PA00X+087526Y+109160X0200Y    R090 S0      
317P1V25_PEX1       VIA   -    MD0100PA00X+087006Y+109160X0200Y    R090 S0      
317P1V25_PEX1       VIA   -    MD0100PA00X+088798Y+107160X0200Y    R090 S0      
317P1V25_PEX1       VIA   -    MD0100PA00X+088538Y+107160X0200Y    R090 S0      
317P1V25_PEX1       VIA   -    MD0100PA00X+089058Y+107160X0200Y    R090 S0      
317P1V25_PEX1       VIA   -    MD0100PA00X+089058Y+107410X0200Y    R090 S0      
317P1V25_PEX1       VIA   -    MD0100PA00X+088538Y+107410X0200Y    R090 S0      
317P1V25_PEX1       VIA   -    MD0100PA00X+088798Y+107410X0200Y    R090 S0      
317P1V25_PEX1       VIA   -    MD0100PA00X+088278Y+107160X0200Y    R090 S0      
317P1V25_PEX1       VIA   -    MD0100PA00X+088278Y+107410X0200Y    R090 S0      
317P1V25_PEX1       VIA   -    MD0100PA00X+086862Y+107410X0200Y    R090 S0      
317P1V25_PEX1       VIA   -    MD0100PA00X+086862Y+107160X0200Y    R090 S0      
317P1V25_PEX1       VIA   -    MD0100PA00X+087382Y+107410X0200Y    R090 S0      
317P1V25_PEX1       VIA   -    MD0100PA00X+087122Y+107410X0200Y    R090 S0      
317P1V25_PEX1       VIA   -    MD0100PA00X+087642Y+107410X0200Y    R090 S0      
317P1V25_PEX1       VIA   -    MD0100PA00X+087642Y+107160X0200Y    R090 S0      
317P1V25_PEX1       VIA   -    MD0100PA00X+087122Y+107160X0200Y    R090 S0      
317P1V25_PEX1       VIA   -    MD0100PA00X+087382Y+107160X0200Y    R090 S0      
327m3434            PU17  -10         A01X+088511Y+121996X0120Y0790R180 S1      
327m3434            PU17  -21         A01X+088511Y+120972X0120Y0790R180 S1      
327m3434            PC1008-1          A01X+088344Y+125029X0400Y0500     S1      
327m3434            PL19  -2          A01X+089112Y+125162X0280Y0320R180 S1      
327m3434            PC227 -1          A01X+089144Y+124479X0400Y0500R180 S1      
327m3434            PC226 -1          A01X+088344Y+124339X0400Y0500     S1      
327m3434            PC224 -1          A01X+089144Y+123099X0400Y0500R180 S1      
327m3434            PC225 -1          A01X+089144Y+123789X0400Y0500R180 S1      
327m3434            PC228 -1          A01X+088344Y+123649X0400Y0500     S1      
327m3434            PC229 -1          A01X+088344Y+122959X0400Y0500     S1      
327m3434            PC230 -1          A01X+088550Y+120227X0198Y0197     S1      
327m3435            C1420 -1          A18X+071998Y+115853X0120Y0150R090 S2      
327m3435            C1421 -1          A18X+072828Y+117057X0120Y0150R180 S2      
327m3435            C1448 -1          A18X+072290Y+116683X0120Y0150     S2      
327m3435            C1447 -1          A18X+071998Y+117139X0120Y0150R270 S2      
327m3435            C1419 -1          A18X+072828Y+116683X0120Y0150R180 S2      
327m3435            C1418 -1          A18X+072835Y+116280X0120Y0150R180 S2      
327m3435            C1417 -1          A18X+072828Y+115935X0120Y0150R180 S2      
327m3435            C1439 -1          A18X+072185Y+115105X0120Y0150R090 S2      
327m3435            C1437 -1          A18X+072185Y+114357X0120Y0150R090 S2      
327m3435            C1422 -1          A18X+071437Y+115105X0120Y0150R090 S2      
327m3435            C1495 -1          A18X+070689Y+115105X0120Y0150R090 S2      
327m3435            C1493 -1          A18X+071063Y+115105X0120Y0150R090 S2      
327m3435            C1441 -1          A18X+071811Y+115105X0120Y0150R090 S2      
327m3435            C1427 -1          A18X+071437Y+114357X0120Y0150R090 S2      
327m3435            C1438 -1          A18X+071811Y+114357X0120Y0150R090 S2      
327m3435            C1465 -1          A18X+071063Y+114357X0120Y0150R090 S2      
327m3435            C1458 -1          A18X+070689Y+114357X0120Y0150R090 S2      
327m3435            C1461 -1          A18X+070315Y+115105X0120Y0150R090 S2      
327m3435            C1491 -1          A18X+070315Y+114357X0120Y0150R090 S2      
327m3435            C1480 -1          A18X+069941Y+114357X0120Y0150R090 S2      
327m3435            C1483 -1          A18X+069193Y+114357X0120Y0150R090 S2      
327m3435            C1489 -1          A18X+069567Y+114357X0120Y0150R090 S2      
327m3435            C1433 -1          A18X+068819Y+114357X0120Y0150R090 S2      
327m3435            C1478 -1          A18X+069567Y+115105X0120Y0150R090 S2      
327m3435            C1487 -1          A18X+069193Y+115105X0120Y0150R090 S2      
327m3435            C1416 -1          A18X+068819Y+115105X0120Y0150R090 S2      
327m3435            C1464 -1          A18X+069941Y+115105X0120Y0150R090 S2      
327m3435            C1471 -1          A18X+067697Y+115105X0120Y0150R090 S2      
327m3435            C1479 -1          A18X+068071Y+115105X0120Y0150R090 S2      
327m3435            C1488 -1          A18X+068445Y+115105X0120Y0150R090 S2      
327m3435            C1456 -1          A18X+067323Y+115105X0120Y0150R090 S2      
327m3435            C1452 -1          A18X+067697Y+114357X0120Y0150R090 S2      
327m3435            C1453 -1          A18X+067323Y+114357X0120Y0150R090 S2      
327m3435            C1467 -1          A18X+068445Y+114357X0120Y0150R090 S2      
327m3435            C1485 -1          A18X+068071Y+114357X0120Y0150R090 S2      
327m3435            C1490 -1          A18X+066949Y+115105X0120Y0150R090 S2      
327m3435            C1434 -1          A18X+066201Y+115105X0120Y0150R090 S2      
327m3435            C1435 -1          A18X+066575Y+115105X0120Y0150R090 S2      
327m3435            C1442 -1          A18X+065827Y+115105X0120Y0150R090 S2      
327m3435            C1486 -1          A18X+066949Y+114357X0120Y0150R090 S2      
327m3435            C1425 -1          A18X+066201Y+114357X0120Y0150R090 S2      
327m3435            C1428 -1          A18X+065827Y+114357X0120Y0150R090 S2      
327m3435            C1431 -1          A18X+066575Y+114357X0120Y0150R090 S2      
317m3435            VIA   -    MD0080PA00X+065640Y+115187X0160Y         S0      
317m3435            VIA   -    MD0080PA00X+066014Y+115187X0160Y         S0      
317m3435            VIA   -    MD0080PA00X+066388Y+115187X0160Y         S0      
317m3435            VIA   -    MD0080PA00X+066762Y+115187X0160Y         S0      
317m3435            VIA   -    MD0080PA00X+065640Y+114439X0160Y         S0      
317m3435            VIA   -    MD0080PA00X+066014Y+114439X0160Y         S0      
317m3435            VIA   -    MD0080PA00X+066388Y+114439X0160Y         S0      
317m3435            VIA   -    MD0080PA00X+066762Y+114439X0160Y         S0      
317m3435            VIA   -    MD0080PA00X+065640Y+117805X0160Y         S0      
317m3435            VIA   -    MD0080PA00X+066014Y+117805X0160Y         S0      
317m3435            VIA   -    MD0080PA00X+066388Y+117805X0160Y         S0      
317m3435            VIA   -    MD0080PA00X+066762Y+117805X0160Y         S0      
317m3435            VIA   -    MD0080PA00X+066388Y+118553X0160Y         S0      
317m3435            VIA   -    MD0080PA00X+065640Y+118553X0160Y         S0      
317m3435            VIA   -    MD0080PA00X+066014Y+118553X0160Y         S0      
317m3435            VIA   -    MD0080PA00X+066762Y+118553X0160Y         S0      
317m3435            VIA   -    MD0080PA00X+068632Y+115187X0160Y         S0      
317m3435            VIA   -    MD0080PA00X+068632Y+114439X0160Y         S0      
317m3435            VIA   -    MD0080PA00X+067510Y+114439X0160Y         S0      
317m3435            VIA   -    MD0080PA00X+067884Y+114439X0160Y         S0      
317m3435            VIA   -    MD0080PA00X+067136Y+114439X0160Y         S0      
317m3435            VIA   -    MD0080PA00X+068258Y+114439X0160Y         S0      
317m3435            VIA   -    MD0080PA00X+067136Y+117805X0160Y         S0      
317m3435            VIA   -    MD0080PA00X+067510Y+117805X0160Y         S0      
317m3435            VIA   -    MD0080PA00X+067884Y+117805X0160Y         S0      
317m3435            VIA   -    MD0080PA00X+068258Y+117805X0160Y         S0      
317m3435            VIA   -    MD0080PA00X+068632Y+117805X0160Y         S0      
317m3435            VIA   -    MD0080PA00X+067884Y+118553X0160Y         S0      
317m3435            VIA   -    MD0080PA00X+067136Y+118553X0160Y         S0      
317m3435            VIA   -    MD0080PA00X+067510Y+118553X0160Y         S0      
317m3435            VIA   -    MD0080PA00X+068258Y+118553X0160Y         S0      
317m3435            VIA   -    MD0080PA00X+068632Y+118553X0160Y         S0      
317m3435            VIA   -    MD0080PA00X+068258Y+115187X0160Y         S0      
317m3435            VIA   -    MD0080PA00X+067136Y+115187X0160Y         S0      
317m3435            VIA   -    MD0080PA00X+067510Y+115187X0160Y         S0      
317m3435            VIA   -    MD0080PA00X+067884Y+115187X0160Y         S0      
317m3435            VIA   -    MD0080PA00X+069380Y+117805X0160Y         S0      
317m3435            VIA   -    MD0080PA00X+069754Y+117805X0160Y         S0      
317m3435            VIA   -    MD0080PA00X+070128Y+117805X0160Y         S0      
317m3435            VIA   -    MD0080PA00X+069380Y+118553X0160Y         S0      
317m3435            VIA   -    MD0080PA00X+069754Y+118553X0160Y         S0      
317m3435            VIA   -    MD0080PA00X+070128Y+118553X0160Y         S0      
317m3435            VIA   -    MD0080PA00X+069380Y+114439X0160Y         S0      
317m3435            VIA   -    MD0080PA00X+069754Y+114439X0160Y         S0      
317m3435            VIA   -    MD0080PA00X+070128Y+114439X0160Y         S0      
317m3435            VIA   -    MD0080PA00X+069380Y+115187X0160Y         S0      
317m3435            VIA   -    MD0080PA00X+069754Y+115187X0160Y         S0      
317m3435            VIA   -    MD0080PA00X+070128Y+115187X0160Y         S0      
317m3435            VIA   -    MD0080PA00X+070876Y+117805X0160Y         S0      
317m3435            VIA   -    MD0080PA00X+070502Y+117805X0160Y         S0      
317m3435            VIA   -    MD0080PA00X+071250Y+117805X0160Y         S0      
317m3435            VIA   -    MD0080PA00X+071624Y+117805X0160Y         S0      
317m3435            VIA   -    MD0080PA00X+070502Y+118553X0160Y         S0      
317m3435            VIA   -    MD0080PA00X+071250Y+118553X0160Y         S0      
317m3435            VIA   -    MD0080PA00X+070876Y+118553X0160Y         S0      
317m3435            VIA   -    MD0080PA00X+071624Y+118553X0160Y         S0      
317m3435            VIA   -    MD0080PA00X+071624Y+114439X0160Y         S0      
317m3435            VIA   -    MD0080PA00X+070876Y+114439X0160Y         S0      
317m3435            VIA   -    MD0080PA00X+070502Y+114439X0160Y         S0      
317m3435            VIA   -    MD0080PA00X+071250Y+114439X0160Y         S0      
317m3435            VIA   -    MD0080PA00X+070502Y+115187X0160Y         S0      
317m3435            VIA   -    MD0080PA00X+071250Y+115187X0160Y         S0      
317m3435            VIA   -    MD0080PA00X+070876Y+115187X0160Y         S0      
317m3435            VIA   -    MD0080PA00X+071624Y+115187X0160Y         S0      
317m3435            VIA   -    MD0080PA00X+072372Y+117057X0160Y         S0      
317m3435            VIA   -    MD0080PA00X+072746Y+117057X0160Y         S0      
317m3435            VIA   -    MD0080PA00X+071998Y+117057X0160Y         S0      
317m3435            VIA   -    MD0080PA00X+072746Y+116683X0160Y         S0      
317m3435            VIA   -    MD0080PA00X+072372Y+116683X0160Y         S0      
317m3435            VIA   -    MD0080PA00X+072372Y+115935X0160Y         S0      
317m3435            VIA   -    MD0080PA00X+072746Y+115935X0160Y         S0      
317m3435            VIA   -    MD0080PA00X+071998Y+115935X0160Y         S0      
317m3435            VIA   -    MD0080PA00X+071998Y+114439X0160Y         S0      
317m3435            VIA   -    MD0080PA00X+072372Y+114439X0160Y         S0      
317m3435            VIA   -    MD0080PA00X+072372Y+115187X0160Y         S0      
317m3435            VIA   -    MD0080PA00X+071998Y+115187X0160Y         S0      
317m3435            VIA   -    MD0080PA00X+072372Y+118553X0160Y         S0      
317m3435            VIA   -    MD0080PA00X+072372Y+117805X0160Y         S0      
317m3435            VIA   -    MD0080PA00X+071998Y+117805X0160Y         S0      
317m3435            VIA   -    MD0080PA00X+071998Y+118553X0160Y         S0      
327m3435            VIA   -           A18X+046977Y+122472X0260Y         S2      
327m3435            VIA   -           A18X+046751Y+123097X0260Y         S2      
327m3435            VIA   -           A18X+046905Y+123809X0260Y         S2      
327m3435            C4266 -1          A18X+046742Y+124411X0120Y0150     S2      
327m3435            C4267 -1          A18X+046742Y+125081X0120Y0150     S2      
327m3435            C4253 -1          A18X+046742Y+125410X0120Y0150     S2      
327m3435            C4252 -1          A18X+046742Y+124751X0120Y0150     S2      
327m3435            C1414 -1          A18X+046624Y+121778X0280Y0320R180 S2      
327m3435            C1413 -1          A18X+047135Y+121778X0280Y0320R180 S2      
327m3435            C1412 -1   M      A18X+047658Y+121778X0280Y0320R180 S2      
327m3435            C1415 -1          A18X+048289Y+121778X0280Y0320R180 S2      
327m3435            R6479 -1   M      A18X+053045Y+126556X0198Y0197R270 S2      
327m3435            R6480 -1   M      A18X+052672Y+126553X0198Y0197R270 S2      
327m3435            R6487 -1   M      A18X+052294Y+126549X0198Y0197R270 S2      
327m3435            R6488 -1   M      A18X+051913Y+126549X0198Y0197R270 S2      
327m3435            R6475 -1   M      A18X+049490Y+126541X0198Y0197R270 S2      
327m3435            R6477 -1   M      A18X+050030Y+126541X0198Y0197R270 S2      
327m3435            R6476 -1   M      A18X+050573Y+126541X0198Y0197R270 S2      
327m3435            R6485 -1          A18X+047810Y+126373X0198Y0197R270 S2      
327m3435            R6486 -1          A18X+048350Y+126373X0198Y0197R270 S2      
327m3435            R6478 -1          A18X+048912Y+126373X0198Y0197R270 S2      
327m3435            R6483 -1          A18X+046698Y+126376X0198Y0197R270 S2      
327m3435            R6484 -1          A18X+047259Y+126373X0198Y0197R270 S2      
327m3435            L29   -2   M      A01X+051283Y+126425X0460Y3860R090 S1      
327m3435            R5790 -2A  M      A01X+051283Y+126425X0590Y0790R090 S1      
327m3435            R5790 -2B  M      A01X+051283Y+126180X0100Y0200R090 S1      
327m3435            L28   -2   M      A01X+047683Y+123473X0460Y3860R180 S1      
327m3435            R5789 -2A  M      A01X+047634Y+123473X0590Y0790R180 S1      
327m3435            R5789 -2B  M      A01X+047879Y+123473X0100Y0200R180 S1      
327m3435            L30   -2   M      A18X+051283Y+126425X0460Y3860R270 S2      
327m3435            R5787 -2A  M      A18X+051243Y+126425X0590Y0790R270 S2      
327m3435            R5787 -2B  M      A18X+051243Y+126180X0100Y0200R270 S2      
327m3435            L27   -2   M      A18X+047683Y+123473X0460Y3860     S2      
327m3435            R5788 -2A  M      A18X+047634Y+123473X0590Y0790     S2      
327m3435            R5788 -2B  M      A18X+047879Y+123473X0100Y0200     S2      
327m3435            C1424 -1          A18X+072185Y+117887X0120Y0150R270 S2      
327m3435            C1450 -1          A18X+072185Y+118635X0120Y0150R270 S2      
327m3435            C1482 -1          A18X+070689Y+118635X0120Y0150R270 S2      
327m3435            C1423 -1          A18X+071811Y+117887X0120Y0150R270 S2      
327m3435            C1446 -1          A18X+071811Y+118635X0120Y0150R270 S2      
327m3435            C1440 -1          A18X+071437Y+117887X0120Y0150R270 S2      
327m3435            C1451 -1          A18X+071437Y+118635X0120Y0150R270 S2      
327m3435            C1460 -1          A18X+071063Y+117887X0120Y0150R270 S2      
327m3435            C1468 -1          A18X+070689Y+117887X0120Y0150R270 S2      
327m3435            C1475 -1          A18X+071063Y+118635X0120Y0150R270 S2      
327m3435            C1481 -1          A18X+070315Y+117887X0120Y0150R270 S2      
327m3435            C1473 -1          A18X+070315Y+118635X0120Y0150R270 S2      
327m3435            C1474 -1          A18X+069941Y+117887X0120Y0150R270 S2      
327m3435            C1472 -1          A18X+069193Y+117887X0120Y0150R270 S2      
327m3435            C1470 -1          A18X+069193Y+118635X0120Y0150R270 S2      
327m3435            C1454 -1          A18X+069567Y+118635X0120Y0150R270 S2      
327m3435            C1449 -1          A18X+068819Y+117887X0120Y0150R270 S2      
327m3435            C1430 -1          A18X+068819Y+118635X0120Y0150R270 S2      
327m3435            C1494 -1          A18X+069941Y+118635X0120Y0150R270 S2      
327m3435            C1492 -1          A18X+069567Y+117887X0120Y0150R270 S2      
327m3435            C1484 -1          A18X+067697Y+118635X0120Y0150R270 S2      
327m3435            C1476 -1          A18X+067323Y+117887X0120Y0150R270 S2      
327m3435            C1469 -1          A18X+068071Y+118635X0120Y0150R270 S2      
327m3435            C1466 -1          A18X+067323Y+118635X0120Y0150R270 S2      
327m3435            C1463 -1          A18X+068445Y+117887X0120Y0150R270 S2      
327m3435            C1459 -1          A18X+068445Y+118635X0120Y0150R270 S2      
327m3435            C1457 -1          A18X+067697Y+117887X0120Y0150R270 S2      
327m3435            C1455 -1          A18X+068071Y+117887X0120Y0150R270 S2      
327m3435            C1443 -1          A18X+065827Y+118635X0120Y0150R270 S2      
327m3435            C1436 -1          A18X+066575Y+117887X0120Y0150R270 S2      
327m3435            C1432 -1          A18X+066201Y+117887X0120Y0150R270 S2      
327m3435            C1429 -1          A18X+066201Y+118635X0120Y0150R270 S2      
327m3435            C1426 -1          A18X+065827Y+117887X0120Y0150R270 S2      
327m3435            C1477 -1          A18X+066949Y+118635X0120Y0150R270 S2      
327m3435            C1462 -1          A18X+066949Y+117887X0120Y0150R270 S2      
327m3435            C1445 -1          A18X+066575Y+118635X0120Y0150R270 S2      
327m3435            C1444 -1          A18X+065459Y+118635X0120Y0150R270 S2      
317m3435            VIA   -    MD0100PA00X+050465Y+126016X0200Y         S0      
317m3435            VIA   -    MD0100PA00X+050735Y+126016X0200Y         S0      
317m3435            VIA   -    MD0100PA00X+049865Y+126016X0200Y         S0      
317m3435            VIA   -    MD0100PA00X+049865Y+125716X0200Y         S0      
317m3435            VIA   -    MD0100PA00X+049565Y+125716X0200Y         S0      
317m3435            VIA   -    MD0100PA00X+049265Y+125716X0200Y         S0      
317m3435            VIA   -    MD0100PA00X+049265Y+126016X0200Y         S0      
317m3435            VIA   -    MD0100PA00X+049565Y+126016X0200Y         S0      
317m3435            VIA   -    MD0100PA00X+050165Y+126016X0200Y         S0      
317m3435            VIA   -    MD0100PA00X+050165Y+125716X0200Y         S0      
317m3435            VIA   -    MD0100PA00X+050735Y+125716X0200Y         S0      
317m3435            VIA   -    MD0100PA00X+050465Y+125716X0200Y         S0      
317m3435            VIA   -    MD0100PA00X+048365Y+126016X0200Y         S0      
317m3435            VIA   -    MD0100PA00X+048365Y+125716X0200Y         S0      
317m3435            VIA   -    MD0100PA00X+048065Y+126016X0200Y         S0      
317m3435            VIA   -    MD0100PA00X+047765Y+126016X0200Y         S0      
317m3435            VIA   -    MD0100PA00X+047765Y+125716X0200Y         S0      
317m3435            VIA   -    MD0100PA00X+048065Y+125716X0200Y         S0      
317m3435            VIA   -    MD0100PA00X+048665Y+126016X0200Y         S0      
317m3435            VIA   -    MD0100PA00X+048665Y+125716X0200Y         S0      
317m3435            VIA   -    MD0100PA00X+048965Y+125716X0200Y         S0      
317m3435            VIA   -    MD0100PA00X+048965Y+126016X0200Y         S0      
317m3435            VIA   -    MD0100PA00X+047165Y+126016X0200Y         S0      
317m3435            VIA   -    MD0100PA00X+047165Y+125716X0200Y         S0      
317m3435            VIA   -    MD0100PA00X+047465Y+125716X0200Y         S0      
317m3435            VIA   -    MD0100PA00X+047465Y+126016X0200Y         S0      
327m3435            PEX1  -AB33       A01X+072185Y+117618X0180Y         S1      
327m3435            PEX1  -Y33        A01X+072185Y+118366X0180Y         S1      
327m3435            PEX1  -Y25        A01X+069193Y+118366X0180Y         S1      
327m3435            PEX1  -Y29 M      A01X+070689Y+118366X0180Y         S1      
327m3435            PEX1  -Y30 M      A01X+071063Y+118366X0180Y         S1      
327m3435            PEX1  -Y32 M      A01X+071811Y+118366X0180Y         S1      
327m3435            PEX1  -Y31 M      A01X+071437Y+118366X0180Y         S1      
327m3435            PEX1  -Y28 M      A01X+070315Y+118366X0180Y         S1      
327m3435            PEX1  -Y27 M      A01X+069941Y+118366X0180Y         S1      
327m3435            PEX1  -Y26 M      A01X+069567Y+118366X0180Y         S1      
327m3435            PEX1  -AB25       A01X+069193Y+117618X0180Y         S1      
327m3435            PEX1  -AB26M      A01X+069567Y+117618X0180Y         S1      
327m3435            PEX1  -AB30M      A01X+071063Y+117618X0180Y         S1      
327m3435            PEX1  -AB32M      A01X+071811Y+117618X0180Y         S1      
327m3435            PEX1  -AB31M      A01X+071437Y+117618X0180Y         S1      
327m3435            PEX1  -AB28M      A01X+070315Y+117618X0180Y         S1      
327m3435            PEX1  -AB29M      A01X+070689Y+117618X0180Y         S1      
327m3435            PEX1  -AB27M      A01X+069941Y+117618X0180Y         S1      
327m3435            PEX1  -Y18 M      A01X+066575Y+118366X0180Y         S1      
327m3435            PEX1  -Y21 M      A01X+067697Y+118366X0180Y         S1      
327m3435            PEX1  -Y20 M      A01X+067323Y+118366X0180Y         S1      
327m3435            PEX1  -Y23 M      A01X+068445Y+118366X0180Y         S1      
327m3435            PEX1  -Y24        A01X+068819Y+118366X0180Y         S1      
327m3435            PEX1  -Y22 M      A01X+068071Y+118366X0180Y         S1      
327m3435            PEX1  -Y19 M      A01X+066949Y+118366X0180Y         S1      
327m3435            PEX1  -Y16 M      A01X+065827Y+118366X0180Y         S1      
327m3435            PEX1  -Y17 M      A01X+066201Y+118366X0180Y         S1      
327m3435            PEX1  -AB18M      A01X+066575Y+117618X0180Y         S1      
327m3435            PEX1  -AB19M      A01X+066949Y+117618X0180Y         S1      
327m3435            PEX1  -AB21M      A01X+067697Y+117618X0180Y         S1      
327m3435            PEX1  -AB23M      A01X+068445Y+117618X0180Y         S1      
327m3435            PEX1  -AB24       A01X+068819Y+117618X0180Y         S1      
327m3435            PEX1  -AB22M      A01X+068071Y+117618X0180Y         S1      
327m3435            PEX1  -AB20M      A01X+067323Y+117618X0180Y         S1      
327m3435            PEX1  -AB17M      A01X+066201Y+117618X0180Y         S1      
327m3435            PEX1  -AB16M      A01X+065827Y+117618X0180Y         S1      
327m3435            PEX1  -AF32       A01X+071811Y+116122X0180Y         S1      
327m3435            PEX1  -AF34M      A01X+072559Y+116122X0180Y         S1      
327m3435            PEX1  -AF33M      A01X+072185Y+116122X0180Y         S1      
327m3435            PEX1  -AE33       A01X+072185Y+116496X0180Y         S1      
327m3435            PEX1  -AE34M      A01X+072559Y+116496X0180Y         S1      
327m3435            PEX1  -AD32       A01X+071811Y+116870X0180Y         S1      
327m3435            PEX1  -AD34M      A01X+072559Y+116870X0180Y         S1      
327m3435            PEX1  -AD33M      A01X+072185Y+116870X0180Y         S1      
327m3435            PEX1  -AH25       A01X+069193Y+115374X0180Y         S1      
327m3435            PEX1  -AH31M      A01X+071437Y+115374X0180Y         S1      
327m3435            PEX1  -AH33M      A01X+072185Y+115374X0180Y         S1      
327m3435            PEX1  -AH32M      A01X+071811Y+115374X0180Y         S1      
327m3435            PEX1  -AH29M      A01X+070689Y+115374X0180Y         S1      
327m3435            PEX1  -AH30M      A01X+071063Y+115374X0180Y         S1      
327m3435            PEX1  -AH28M      A01X+070315Y+115374X0180Y         S1      
327m3435            PEX1  -AH27M      A01X+069941Y+115374X0180Y         S1      
327m3435            PEX1  -AH26M      A01X+069567Y+115374X0180Y         S1      
327m3435            PEX1  -AK25       A01X+069193Y+114626X0180Y         S1      
327m3435            PEX1  -AK29M      A01X+070689Y+114626X0180Y         S1      
327m3435            PEX1  -AK28M      A01X+070315Y+114626X0180Y         S1      
327m3435            PEX1  -AK31M      A01X+071437Y+114626X0180Y         S1      
327m3435            PEX1  -AK30M      A01X+071063Y+114626X0180Y         S1      
327m3435            PEX1  -AK33M      A01X+072185Y+114626X0180Y         S1      
327m3435            PEX1  -AK32M      A01X+071811Y+114626X0180Y         S1      
327m3435            PEX1  -AK27M      A01X+069941Y+114626X0180Y         S1      
327m3435            PEX1  -AK26M      A01X+069567Y+114626X0180Y         S1      
327m3435            PEX1  -AH22       A01X+068071Y+115374X0180Y         S1      
327m3435            PEX1  -AH21       A01X+067697Y+115374X0180Y         S1      
327m3435            PEX1  -AH20       A01X+067323Y+115374X0180Y         S1      
327m3435            PEX1  -AH23       A01X+068445Y+115374X0180Y         S1      
327m3435            PEX1  -AH24       A01X+068819Y+115374X0180Y         S1      
327m3435            PEX1  -AH19       A01X+066949Y+115374X0180Y         S1      
327m3435            PEX1  -AH18       A01X+066575Y+115374X0180Y         S1      
327m3435            PEX1  -AH17       A01X+066201Y+115374X0180Y         S1      
327m3435            PEX1  -AH16       A01X+065827Y+115374X0180Y         S1      
327m3435            PEX1  -AK18M      A01X+066575Y+114626X0180Y         S1      
327m3435            PEX1  -AK19M      A01X+066949Y+114626X0180Y         S1      
327m3435            PEX1  -AK20M      A01X+067323Y+114626X0180Y         S1      
327m3435            PEX1  -AK21M      A01X+067697Y+114626X0180Y         S1      
327m3435            PEX1  -AK23M      A01X+068445Y+114626X0180Y         S1      
327m3435            PEX1  -AK24       A01X+068819Y+114626X0180Y         S1      
327m3435            PEX1  -AK22M      A01X+068071Y+114626X0180Y         S1      
327m3435            PEX1  -AK17M      A01X+066201Y+114626X0180Y         S1      
327m3435            PEX1  -AK16M      A01X+065827Y+114626X0180Y         S1      
327P1V8_VDDA_PEX1   VIA   -           A18X+062607Y+117009X0260Y         S2      
327P1V8_VDDA_PEX1   VIA   -           A18X+074320Y+112810X0260Y         S2      
327P1V8_VDDA_PEX1   C3171 -1          A18X+072956Y+112943X0120Y0150     S2      
327P1V8_VDDA_PEX1   C3170 -1          A18X+072956Y+113317X0120Y0150     S2      
327P1V8_VDDA_PEX1   VIA   -           A18X+063956Y+119492X0260Y         S2      
327P1V8_VDDA_PEX1   C3184 -1          A18X+065056Y+119301X0120Y0150R180 S2      
327P1V8_VDDA_PEX1   C3169 -1   M      A18X+064728Y+119301X0120Y0150     S2      
327P1V8_VDDA_PEX1   C3163 -1          A18X+064826Y+118909X0280Y0320R090 S2      
327P1V8_VDDA_PEX1   C3185 -1          A18X+064974Y+113691X0120Y0150R180 S2      
327P1V8_VDDA_PEX1   C3188 -1          A18X+072828Y+118179X0120Y0150R180 S2      
327P1V8_VDDA_PEX1   C3186 -1          A18X+073120Y+119885X0120Y0150R090 S2      
327P1V8_VDDA_PEX1   C3172 -1          A18X+073120Y+120213X0120Y0150R270 S2      
327P1V8_VDDA_PEX1   C3164 -1          A18X+074032Y+118179X0120Y0150R180 S2      
327P1V8_VDDA_PEX1   C3187 -1          A18X+073704Y+118179X0120Y0150     S2      
327P1V8_VDDA_PEX1   PEX1  -T35        A01X+072933Y+119862X0180Y         S1      
317P1V8_VDDA_PEX1   VIA   -    MD0080PA00X+073120Y+120049X0160Y    R180 S0      
327P1V8_VDDA_PEX1   PEX1  -V14        A01X+065079Y+119114X0180Y         S1      
317P1V8_VDDA_PEX1   VIA   -    MD0080PA00X+064892Y+119301X0160Y    R270 S0      
327P1V8_VDDA_PEX1   PEX1  -AA37       A01X+073681Y+117992X0180Y         S1      
317P1V8_VDDA_PEX1   VIA   -    MD0080PA00X+073868Y+118179X0160Y         S0      
327P1V8_VDDA_PEX1   PEX1  -AA34       A01X+072559Y+117992X0180Y         S1      
317P1V8_VDDA_PEX1   VIA   -    MD0080PA00X+072746Y+118179X0160Y         S0      
317P1V8_VDDA_PEX1   VIA   -    MD0080PA00X+063396Y+118179X0160Y         S0      
317P1V8_VDDA_PEX1   VIA   -    MD0080PA00X+063396Y+117805X0160Y         S0      
317P1V8_VDDA_PEX1   VIA   -    MD0080PA00X+063396Y+117431X0160Y         S0      
327P1V8_VDDA_PEX1   C3183 -1          A18X+063314Y+117992X0120Y0150     S2      
327P1V8_VDDA_PEX1   C3182 -1          A18X+063314Y+117618X0120Y0150     S2      
327P1V8_VDDA_PEX1   C3181 -1   M      A18X+063314Y+117250X0120Y0150     S2      
327P1V8_VDDA_PEX1   PEX1  -AA10M      A01X+063583Y+117992X0180Y         S1      
327P1V8_VDDA_PEX1   PEX1  -AB10M      A01X+063583Y+117618X0180Y         S1      
327P1V8_VDDA_PEX1   PEX1  -AC10       A01X+063583Y+117244X0180Y         S1      
327P1V8_VDDA_PEX1   PEX1  -AP35       A01X+072933Y+113130X0180Y         S1      
317P1V8_VDDA_PEX1   VIA   -    MD0080PA00X+073120Y+112943X0160Y         S0      
327P1V8_VDDA_PEX1   PEX1  -AM14       A01X+065079Y+113878X0180Y         S1      
327P1V8_VDDA_PEX1   C3245 -1          A01X+055540Y+103299X0120Y0150R090 S1      
317P1V8_VDDA_PEX1   VIA   -    MD0100PA00X+056206Y+103056X0200Y    R090 S0      
317P1V8_VDDA_PEX1   VIA   -    MD0100PA00X+055906Y+103056X0200Y    R090 S0      
327P1V8_VDDA_PEX1   C3246 -1          A01X+056009Y+103299X0120Y0150R090 S1      
327P1V8_VDDA_PEX1   R4577 -1          A01X+056477Y+102693X0198Y0197     S1      
327P1V8_VDDA_PEX1   L113  -2          A01X+056104Y+102178X0440Y0540R270 S1      
327P1V8_VDDA_PEX1   C3244 -1          A01X+055976Y+102766X0280Y0320R090 S1      
317P1V8_VDDA_PEX1   VIA   -    MD0080PA00X+064892Y+113691X0160Y         S0      
327P1V25_PEX1_EN    PU17  -8          A01X+088944Y+121956X0070Y0320R270 S1      
317P1V25_PEX1_EN    VIA   -    M      A01X+089253Y+122011X0200Y         S2      
017P1V25_PEX1_EN    VIA   -    M      A18X+089253Y+122011X0260Y         S2      
017P1V25_PEX1_EN          -    MD0100PA00X+089253Y+122011                       
327P1V25_PEX1_EN    R844  -1          A01X+089503Y+122271X0198Y0197     S1      
327P1V25_PEX1_FB    PU17  -7          A01X+088944Y+121799X0070Y0320R270 S1      
317P1V25_PEX1_FB    VIA   -    M      A01X+089929Y+121947X0200Y         S2      
017P1V25_PEX1_FB    VIA   -    M      A18X+089929Y+121947X0260Y         S2      
017P1V25_PEX1_FB          -    MD0100PA00X+089929Y+121947                       
327P1V25_PEX1_FB    PR171 -2          A01X+090190Y+122272X0198Y0197R180 S1      
327P1V25_PEX1_FB    PC240 -1   M      A01X+090190Y+121872X0198Y0197     S1      
327P1V25_PEX1_FB    PR173 -2   M      A01X+089675Y+121894X0198Y0197R090 S1      
327m3436            PU17  -6          A01X+088944Y+121641X0070Y0320R270 S1      
317m3436            VIA   -    M      A01X+089888Y+121418X0200Y         S2      
017m3436            VIA   -    M      A18X+089888Y+121418X0260Y         S2      
017m3436                  -    MD0100PA00X+089888Y+121418                       
327m3436            PR173 -1   M      A01X+089675Y+121579X0198Y0197R090 S1      
327m3436            PC242 -2   M      A01X+090124Y+121481X0198Y0197R090 S1      
327m3436            PC979 -2   M      A01X+090507Y+121140X0198Y0197R270 S1      
327m3436            PJ12  -1          A01X+090907Y+121057X0200Y0400R090 S1      
317m3437            VIA   -    MD0080PA00X+066388Y+112943X0160Y         S0      
317m3437            VIA   -    MD0080PA00X+065640Y+112943X0160Y         S0      
317m3437            VIA   -    MD0080PA00X+066014Y+112943X0160Y         S0      
317m3437            VIA   -    MD0080PA00X+066762Y+112943X0160Y         S0      
317m3437            VIA   -    MD0080PA00X+066014Y+120049X0160Y         S0      
317m3437            VIA   -    MD0080PA00X+066388Y+120049X0160Y         S0      
317m3437            VIA   -    MD0080PA00X+065640Y+120049X0160Y         S0      
317m3437            VIA   -    MD0080PA00X+066762Y+120049X0160Y         S0      
317m3437            VIA   -    MD0080PA00X+068258Y+112943X0160Y         S0      
317m3437            VIA   -    MD0080PA00X+067884Y+112943X0160Y         S0      
317m3437            VIA   -    MD0080PA00X+067136Y+112943X0160Y         S0      
317m3437            VIA   -    MD0080PA00X+067510Y+112943X0160Y         S0      
317m3437            VIA   -    MD0080PA00X+068632Y+112943X0160Y         S0      
317m3437            VIA   -    MD0080PA00X+068258Y+120049X0160Y         S0      
317m3437            VIA   -    MD0080PA00X+067884Y+120049X0160Y         S0      
317m3437            VIA   -    MD0080PA00X+067136Y+120049X0160Y         S0      
317m3437            VIA   -    MD0080PA00X+067510Y+120049X0160Y         S0      
317m3437            VIA   -    MD0080PA00X+068632Y+120049X0160Y         S0      
317m3437            VIA   -    MD0080PA00X+069380Y+120049X0160Y         S0      
317m3437            VIA   -    MD0080PA00X+069754Y+120049X0160Y         S0      
317m3437            VIA   -    MD0080PA00X+070128Y+120049X0160Y         S0      
317m3437            VIA   -    MD0080PA00X+069380Y+112943X0160Y         S0      
317m3437            VIA   -    MD0080PA00X+069754Y+112943X0160Y         S0      
317m3437            VIA   -    MD0080PA00X+070128Y+112943X0160Y         S0      
317m3437            VIA   -    MD0080PA00X+071624Y+120049X0160Y         S0      
317m3437            VIA   -    MD0080PA00X+070876Y+120049X0160Y         S0      
317m3437            VIA   -    MD0080PA00X+070502Y+120049X0160Y         S0      
317m3437            VIA   -    MD0080PA00X+071250Y+120049X0160Y         S0      
317m3437            VIA   -    MD0080PA00X+071624Y+112943X0160Y         S0      
317m3437            VIA   -    MD0080PA00X+071250Y+112943X0160Y         S0      
317m3437            VIA   -    MD0080PA00X+070876Y+112943X0160Y         S0      
317m3437            VIA   -    MD0080PA00X+070502Y+112943X0160Y         S0      
317m3437            VIA   -    MD0080PA00X+072372Y+112943X0160Y         S0      
317m3437            VIA   -    MD0080PA00X+071998Y+112943X0160Y         S0      
317m3437            VIA   -    MD0080PA00X+072372Y+120049X0160Y         S0      
317m3437            VIA   -    MD0080PA00X+071998Y+120049X0160Y         S0      
317m3437            VIA   -    MD0080PA00X+074242Y+117431X0160Y         S0      
317m3437            VIA   -    MD0080PA00X+074242Y+117057X0160Y         S0      
317m3437            VIA   -    MD0080PA00X+074242Y+116683X0160Y         S0      
317m3437            VIA   -    MD0080PA00X+074242Y+115935X0160Y         S0      
317m3437            VIA   -    MD0080PA00X+074242Y+115561X0160Y         S0      
327m3437            R6130 -2B  M      A18X+089478Y+105068X0100Y0200R180 S2      
327m3437            R6130 -2A  M      A18X+089723Y+105068X0590Y0790R180 S2      
327m3437            L98   -2   M      A18X+089674Y+105037X0460Y3860R180 S2      
327m3437            L101  -2   M      A18X+086261Y+105068X0460Y3860     S2      
327m3437            R6133 -2A  M      A18X+086211Y+105068X0590Y0790     S2      
327m3437            R6133 -2B  M      A18X+086456Y+105068X0100Y0200     S2      
327m3437            C4280 -1          A01X+089637Y+107398X0120Y0150R090 S1      
327m3437            C4281 -1          A01X+089958Y+107401X0120Y0150R090 S1      
327m3437            C4295 -1          A01X+090299Y+107398X0120Y0150R090 S1      
327m3437            C4294 -1          A01X+090612Y+107400X0120Y0150R090 S1      
327m3437            R6495 -1          A01X+090626Y+101886X0198Y0197R270 S1      
327m3437            R6503 -1          A01X+085788Y+101723X0198Y0197R270 S1      
327m3437            R6492 -1          A01X+087595Y+101723X0198Y0197R270 S1      
327m3437            R6504 -1          A01X+086401Y+101723X0198Y0197R270 S1      
327m3437            R6493 -1          A01X+088145Y+101723X0198Y0197R270 S1      
327m3437            R6494 -1          A01X+088521Y+101723X0198Y0197R270 S1      
327m3437            R6491 -1          A01X+087040Y+101723X0198Y0197R270 S1      
327m3437            R6500 -1          A01X+089361Y+101737X0198Y0197R270 S1      
327m3437            R6501 -1          A01X+089805Y+101732X0198Y0197R270 S1      
327m3437            R6502 -1          A01X+090222Y+101880X0198Y0197R270 S1      
327m3437            R6499 -1          A01X+088909Y+101723X0198Y0197R270 S1      
327m3437            R6496 -1          A01X+085249Y+101723X0198Y0197R270 S1      
327m3437            C3137 -1          A18X+071998Y+120131X0120Y0150R270 S2      
327m3437            C3160 -1          A18X+072372Y+120131X0120Y0150R270 S2      
327m3437            PEX1  -T32        A01X+071811Y+119862X0180Y         S1      
327m3437            PEX1  -T33        A01X+072185Y+119862X0180Y         S1      
327m3437            C3127 -1          A18X+070876Y+120131X0120Y0150R270 S2      
327m3437            C3128 -1          A18X+071250Y+120131X0120Y0150R270 S2      
327m3437            C3139 -1          A18X+070502Y+120131X0120Y0150R270 S2      
327m3437            C3129 -1          A18X+071624Y+120131X0120Y0150R270 S2      
327m3437            C3140 -1          A18X+070128Y+120131X0120Y0150R270 S2      
327m3437            PEX1  -T30        A01X+071063Y+119862X0180Y         S1      
327m3437            PEX1  -T28        A01X+070315Y+119862X0180Y         S1      
327m3437            PEX1  -T29        A01X+070689Y+119862X0180Y         S1      
327m3437            PEX1  -T31        A01X+071437Y+119862X0180Y         S1      
327m3437            C3152 -1          A18X+069390Y+120131X0120Y0150R270 S2      
327m3437            C3143 -1          A18X+069754Y+120131X0120Y0150R270 S2      
327m3437            C3119 -1          A18X+069000Y+120008X0280Y0320     S2      
327m3437            PEX1  -T27        A01X+069941Y+119862X0180Y         S1      
327m3437            PEX1  -T26        A01X+069567Y+119862X0180Y         S1      
327m3437            PEX1  -T25        A01X+069193Y+119862X0180Y         S1      
327m3437            C3136 -1          A18X+067510Y+120131X0120Y0150R270 S2      
327m3437            C3154 -1          A18X+068610Y+120131X0120Y0150R270 S2      
327m3437            C3147 -1          A18X+068258Y+120131X0120Y0150R270 S2      
327m3437            C3145 -1          A18X+067884Y+120131X0120Y0150R270 S2      
327m3437            PEX1  -T24        A01X+068819Y+119862X0180Y         S1      
327m3437            PEX1  -T21        A01X+067697Y+119862X0180Y         S1      
327m3437            PEX1  -T20        A01X+067323Y+119862X0180Y         S1      
327m3437            PEX1  -T22        A01X+068071Y+119862X0180Y         S1      
327m3437            PEX1  -T23        A01X+068445Y+119862X0180Y         S1      
327m3437            C3155 -1          A18X+066388Y+120131X0120Y0150R270 S2      
327m3437            C3151 -1          A18X+066762Y+120131X0120Y0150R270 S2      
327m3437            C3157 -1          A18X+066014Y+120131X0120Y0150R270 S2      
327m3437            C3156 -1          A18X+067136Y+120131X0120Y0150R270 S2      
327m3437            C3141 -1          A18X+065640Y+120131X0120Y0150R270 S2      
327m3437            PEX1  -T19        A01X+066949Y+119862X0180Y         S1      
327m3437            PEX1  -T16        A01X+065827Y+119862X0180Y         S1      
327m3437            PEX1  -T18        A01X+066575Y+119862X0180Y         S1      
327m3437            PEX1  -T17        A01X+066201Y+119862X0180Y         S1      
327m3437            PEX1  -AC38       A01X+074055Y+117244X0180Y         S1      
327m3437            C3149 -1          A18X+074324Y+116496X0120Y0150R180 S2      
327m3437            C3121 -1          A18X+074324Y+116122X0120Y0150R180 S2      
327m3437            C3122 -1          A18X+074324Y+116870X0120Y0150R180 S2      
327m3437            C3123 -1          A18X+074324Y+117244X0120Y0150R180 S2      
327m3437            C3124 -1          A18X+074324Y+115748X0120Y0150R180 S2      
327m3437            PEX1  -AF38       A01X+074055Y+116122X0180Y         S1      
327m3437            PEX1  -AE38       A01X+074055Y+116496X0180Y         S1      
327m3437            PEX1  -AD38       A01X+074055Y+116870X0180Y         S1      
327m3437            PEX1  -AG38       A01X+074055Y+115748X0180Y         S1      
327m3437            L100  -2   M      A01X+089674Y+105037X0460Y3860     S1      
327m3437            R6132 -2A  M      A01X+089723Y+105068X0590Y0790     S1      
327m3437            R6132 -2B  M      A01X+089478Y+105068X0100Y0200     S1      
327m3437            R6131 -2B  M      A01X+086456Y+105068X0100Y0200R180 S1      
327m3437            R6131 -2A  M      A01X+086211Y+105068X0590Y0790R180 S1      
327m3437            L99   -2   M      A01X+086261Y+105068X0460Y3860R180 S1      
317m3437            VIA   -    MD0100PA00X+089989Y+102676X0200Y         S0      
317m3437            VIA   -    MD0100PA00X+089989Y+102321X0200Y         S0      
317m3437            VIA   -    MD0100PA00X+088489Y+102676X0200Y         S0      
317m3437            VIA   -    MD0100PA00X+089089Y+102676X0200Y         S0      
317m3437            VIA   -    MD0100PA00X+088789Y+102321X0200Y         S0      
317m3437            VIA   -    MD0100PA00X+089389Y+102321X0200Y         S0      
317m3437            VIA   -    MD0100PA00X+086369Y+102497X0200Y         S0      
317m3437            VIA   -    MD0100PA00X+089315Y+102002X0200Y         S0      
317m3437            VIA   -    MD0100PA00X+089772Y+101992X0200Y         S0      
317m3437            VIA   -    MD0100PA00X+089539Y+102698X0200Y         S0      
317m3437            VIA   -    MD0100PA00X+088874Y+101993X0200Y         S0      
317m3437            VIA   -    M      A01X+086974Y+102590X0200Y         S2      
017m3437            VIA   -    M      A18X+086974Y+102590X0260Y         S2      
017m3437                  -    MD0100PA00X+086974Y+102590                       
317m3437            VIA   -    MD0100PA00X+088189Y+102321X0200Y         S0      
317m3437            VIA   -    MD0100PA00X+086689Y+102676X0200Y         S0      
317m3437            VIA   -    MD0100PA00X+087289Y+102676X0200Y         S0      
317m3437            VIA   -    MD0100PA00X+087889Y+102676X0200Y         S0      
317m3437            VIA   -    MD0100PA00X+087589Y+102321X0200Y         S0      
317m3437            VIA   -    MD0100PA00X+086689Y+102321X0200Y         S0      
317m3437            VIA   -    MD0100PA00X+086691Y+101875X0200Y         S0      
317m3437            VIA   -    MD0100PA00X+087284Y+101899X0200Y         S0      
317m3437            VIA   -    MD0100PA00X+087878Y+101875X0200Y         S0      
317m3437            VIA   -    MD0100PA00X+087893Y+102239X0200Y         S0      
317m3437            VIA   -    M      A01X+088510Y+102168X0200Y         S2      
017m3437            VIA   -    M      A18X+088510Y+102168X0260Y         S2      
017m3437                  -    MD0100PA00X+088510Y+102168                       
317m3437            VIA   -    MD0100PA00X+086396Y+102076X0200Y         S0      
317m3437            VIA   -    MD0100PA00X+086089Y+102676X0200Y         S0      
317m3437            VIA   -    M      A01X+086089Y+102321X0200Y         S2      
017m3437            VIA   -    M      A18X+086089Y+102321X0260Y         S2      
017m3437                  -    MD0100PA00X+086089Y+102321                       
317m3437            VIA   -    MD0100PA00X+086105Y+101891X0200Y         S0      
317m3437            VIA   -    MD0100PA00X+087107Y+102311X0200Y         S0      
327m3437            C3126 -1          A18X+072372Y+112861X0120Y0150R090 S2      
327m3437            C3158 -1          A18X+071998Y+112861X0120Y0150R090 S2      
327m3437            PEX1  -AP32       A01X+071811Y+113130X0180Y         S1      
327m3437            PEX1  -AP33       A01X+072185Y+113130X0180Y         S1      
327m3437            C3132 -1          A18X+070128Y+112861X0120Y0150R090 S2      
327m3437            C3138 -1          A18X+070502Y+112861X0120Y0150R090 S2      
327m3437            C3142 -1          A18X+071250Y+112861X0120Y0150R090 S2      
327m3437            C3159 -1          A18X+070876Y+112861X0120Y0150R090 S2      
327m3437            C3148 -1          A18X+071624Y+112861X0120Y0150R090 S2      
327m3437            PEX1  -AP28       A01X+070315Y+113130X0180Y         S1      
327m3437            PEX1  -AP29       A01X+070689Y+113130X0180Y         S1      
327m3437            PEX1  -AP30       A01X+071063Y+113130X0180Y         S1      
327m3437            PEX1  -AP31       A01X+071437Y+113130X0180Y         S1      
327m3437            C3118 -1          A18X+069003Y+112961X0280Y0320R180 S2      
327m3437            C3131 -1          A18X+069754Y+112861X0120Y0150R090 S2      
327m3437            C3130 -1          A18X+069393Y+112861X0120Y0150R090 S2      
327m3437            PEX1  -AP27       A01X+069941Y+113130X0180Y         S1      
327m3437            PEX1  -AP26       A01X+069567Y+113130X0180Y         S1      
327m3437            PEX1  -AP25       A01X+069193Y+113130X0180Y         S1      
327m3437            C3135 -1          A18X+068613Y+112861X0120Y0150R090 S2      
327m3437            C3134 -1          A18X+067884Y+112861X0120Y0150R090 S2      
327m3437            C3133 -1          A18X+067510Y+112861X0120Y0150R090 S2      
327m3437            C3125 -1          A18X+068258Y+112861X0120Y0150R090 S2      
327m3437            PEX1  -AP24       A01X+068819Y+113130X0180Y         S1      
327m3437            PEX1  -AP21       A01X+067697Y+113130X0180Y         S1      
327m3437            PEX1  -AP20       A01X+067323Y+113130X0180Y         S1      
327m3437            PEX1  -AP22       A01X+068071Y+113130X0180Y         S1      
327m3437            PEX1  -AP23       A01X+068445Y+113130X0180Y         S1      
327m3437            C3153 -1          A18X+067136Y+112861X0120Y0150R090 S2      
327m3437            C3150 -1          A18X+066762Y+112861X0120Y0150R090 S2      
327m3437            C3146 -1          A18X+066388Y+112861X0120Y0150R090 S2      
327m3437            C3144 -1          A18X+066014Y+112861X0120Y0150R090 S2      
327m3437            C3120 -1          A18X+065640Y+112861X0120Y0150R090 S2      
327m3437            PEX1  -AP19       A01X+066949Y+113130X0180Y         S1      
327m3437            PEX1  -AP17       A01X+066201Y+113130X0180Y         S1      
327m3437            PEX1  -AP16       A01X+065827Y+113130X0180Y         S1      
327m3437            PEX1  -AP18       A01X+066575Y+113130X0180Y         S1      
327P1V25_PEX1_CS    PU17  -3          A01X+088944Y+121169X0070Y0320R270 S1      
317P1V25_PEX1_CS    VIA   -    M      A01X+089471Y+121042X0200Y         S2      
017P1V25_PEX1_CS    VIA   -    M      A18X+089471Y+121042X0260Y         S2      
017P1V25_PEX1_CS          -    MD0100PA00X+089471Y+121042                       
327P1V25_PEX1_CS    PR172 -1          A01X+089743Y+120898X0198Y0197R270 S1      
327P0V8_PEX1_PWM2   PU6   -2          A01X+046998Y+100785X0070Y0240     S1      
317P0V8_PEX1_PWM2   VIA   -    M      A01X+047502Y+099257X0200Y    R090 S2      
017P0V8_PEX1_PWM2   VIA   -    M      A18X+047502Y+099257X0260Y    R090 S2      
017P0V8_PEX1_PWM2         -    MD0100PA00X+047502Y+099257                       
327P0V8_PEX1_PWM2   PU10  -34         A01X+051390Y+111023X0090Y0240R180 S1      
317P0V8_PEX1_PWM2   VIA   -    MD0100PA00X+051470Y+110479X0200Y         S0      
327m3438            R836  -2          A01X+140626Y+099534X0198Y0197R090 S1      
327m3438            VIA   -    M      A01X+140518Y+100050X0300Y         S1      
327m3438            PU11  -10         A01X+139676Y+100785X0070Y0240     S1      
327m3439            VIA   -    M      A18X+145278Y+128910X0260Y         S2      
327m3439            PJ25  -1          A18X+144446Y+128880X0200Y0400R270 S2      
327m3439            PEX3  -W39        A01X+165846Y+118740X0180Y         S1      
317m3439            VIA   -    MD0080PA00X+165659Y+118927X0160Y         S0      
327m3440            PR7135-1          A18X+047891Y+102720X0198Y0197R090 S2      
317m3440            VIA   -    MD0100PA00X+047156Y+102948X0200Y         S0      
327m3440            VIA   -    M      A18X+047395Y+102720X0260Y         S2      
327m3440            PU6   -28         A01X+047156Y+102675X0070Y0240     S1      
327m3441            PR133 -1   M      A01X+136284Y+103027X0198Y0197R180 S1      
317m3441            VIA   -    M      A01X+136505Y+102842X0200Y         S2      
017m3441            VIA   -    M      A18X+136505Y+102842X0260Y         S2      
017m3441                  -    MD0100PA00X+136505Y+102842                       
327m3441            PR131 -1          A01X+136284Y+103427X0198Y0197R180 S1      
327m3441            PU11  -33         A01X+138022Y+102124X0070Y0240R090 S1      
327m3442            PR146 -2          A18X+136476Y+101034X0198Y0197R270 S2      
327m3442            PC136 -1          A01X+137103Y+101232X0198Y0197R180 S1      
327m3442            PU11  -38         A01X+138022Y+101337X0070Y0240R090 S1      
317m3442            VIA   -    M      A01X+137353Y+101232X0200Y         S2      
017m3442            VIA   -    M      A18X+137353Y+101232X0260Y         S2      
017m3442                  -    MD0100PA00X+137353Y+101232                       
327m3442            PR147 -1   M      A18X+136876Y+101034X0198Y0197R090 S2      
327m3443            PC66  -1          A01X+041067Y+110570X0198Y0197R270 S1      
327m3443            PU7   -32         A01X+041264Y+111023X0090Y0240R180 S1      
327m3444            PR102 -1          A01X+042253Y+110192X0198Y0197R270 S1      
317m3444            VIA   -    M      A01X+042334Y+110434X0200Y         S2      
017m3444            VIA   -    M      A18X+042334Y+110434X0260Y         S2      
017m3444                  -    MD0100PA00X+042334Y+110434                       
327m3444            PU7   -37         A01X+042150Y+111023X0090Y0240R180 S1      
327m3445            PR100 -2          A01X+041446Y+110256X0198Y0197R270 S1      
327m3445            PC66  -2          A01X+041067Y+110256X0198Y0197R270 S1      
327m3446            PU8   -10_1       A01X+044934Y+113307X0240Y1700R270 S1      
327m3446            PL7   -1          A01X+044689Y+114354X1220Y1320R180 S1      
327m3447            PC82  -1          A01X+044280Y+110570X0198Y0197R270 S1      
327m3447            PU8   -32         A01X+044477Y+111023X0090Y0240R180 S1      
327m3448            PR109 -1          A18X+049637Y+111197X0198Y0197R090 S2      
327m3448            PU9   -1          A01X+049225Y+111269X0090Y0240R270 S1      
317m3448            VIA   -    MD0100PA00X+049340Y+111009X0200Y         S0      
327m3449            PR113 -1          A18X+052850Y+111197X0198Y0197R090 S2      
327m3449            PU10  -1          A01X+052438Y+111269X0090Y0240R270 S1      
317m3449            VIA   -    MD0100PA00X+052552Y+111009X0200Y         S0      
327m3450            PC99  -1          A01X+047626Y+110570X0198Y0197R270 S1      
327m3450            PU9   -32         A01X+047823Y+111023X0090Y0240R180 S1      
327m3451            PU9   -10_1       A01X+048280Y+113307X0240Y1700R270 S1      
327m3451            PL9   -1          A01X+048465Y+114354X1220Y1320R180 S1      
327P0V8_PEX1_VCC2   PR111 -2   M      A18X+052650Y+111582X0198Y0197R090 S2      
317P0V8_PEX1_VCC2   VIA   -    MD0100PA00X+052919Y+111590X0200Y         S0      
327P0V8_PEX1_VCC2   PU10  -3          A01X+052438Y+111624X0090Y0240R270 S1      
327P0V8_PEX1_VCC2   PC113 -1   M      A01X+052900Y+111347X0198Y0197R270 S1      
327P0V8_PEX1_VCC2   R6765 -1   M      A18X+052320Y+111249X0198Y0197R090 S2      
327P0V8_PEX1_VCC2   PR7169-2          A18X+051938Y+111127X0198Y0197R180 S2      
327m3452            PC6613-1          A18X+050519Y+108589X0400Y0500     S2      
327m3452            PC6612-1          A18X+050533Y+109309X0400Y0500     S2      
327m3452            PC6611-1          A18X+047078Y+109307X0400Y0500R180 S2      
327m3452            PC6614-1          A01X+050519Y+108589X0400Y0500R180 S1      
327m3452            PC97  -1          A01X+047125Y+108033X0630Y1380R180 S1      
327m3452            PL8   -1          A01X+049910Y+107868X0420Y0990R270 S1      
327m3452            PC114 -1          A18X+051095Y+111775X0400Y0500R090 S2      
327m3452            PC112 -1          A18X+050881Y+110990X0400Y0500R270 S2      
327m3452            PC110 -1          A18X+050295Y+111775X0400Y0500R090 S2      
327m3452            PC94  -1          A18X+047882Y+111775X0400Y0500R090 S2      
327m3452            PC95  -1          A18X+047668Y+110990X0400Y0500R270 S2      
327m3452            PC93  -1          A18X+047082Y+111775X0400Y0500R090 S2      
327m3452            PU10  -30         A01X+050682Y+111023X0090Y0240R180 S1      
327m3452            PC109 -1          A01X+050087Y+111982X0198Y0197R090 S1      
317m3452            VIA   -    MD0100PA00X+050251Y+110940X0200Y         S0      
317m3452            VIA   -    MD0100PA00X+050041Y+111090X0200Y         S0      
317m3452            VIA   -    MD0100PA00X+050261Y+111240X0200Y         S0      
317m3452            VIA   -    MD0100PA00X+050041Y+111380X0200Y         S0      
317m3452            VIA   -    MD0100PA00X+050471Y+111060X0200Y         S0      
317m3452            VIA   -    MD0100PA00X+050695Y+111880X0200Y         S0      
317m3452            VIA   -    MD0100PA00X+050695Y+111610X0200Y         S0      
317m3452            VIA   -    MD0100PA00X+050550Y+111365X0200Y         S0      
317m3452            VIA   -    MD0100PA00X+051230Y+111365X0200Y         S0      
317m3452            VIA   -    MD0100PA00X+050980Y+111365X0200Y         S0      
327m3452            PU10  -25_2M      A01X+050882Y+111661X0810Y0910R090 S1      
327m3452            PU9   -30         A01X+047469Y+111023X0090Y0240R180 S1      
327m3452            PC92  -1          A01X+046875Y+111982X0198Y0197R090 S1      
317m3452            VIA   -    MD0100PA00X+047038Y+110940X0200Y         S0      
317m3452            VIA   -    MD0100PA00X+046828Y+111380X0200Y         S0      
317m3452            VIA   -    MD0100PA00X+046828Y+111090X0200Y         S0      
317m3452            VIA   -    MD0100PA00X+047048Y+111240X0200Y         S0      
317m3452            VIA   -    MD0100PA00X+047258Y+111060X0200Y         S0      
317m3452            VIA   -    MD0100PA00X+047482Y+111880X0200Y         S0      
317m3452            VIA   -    MD0100PA00X+047482Y+111610X0200Y         S0      
317m3452            VIA   -    MD0100PA00X+047337Y+111365X0200Y         S0      
317m3452            VIA   -    MD0100PA00X+047767Y+111365X0200Y         S0      
317m3452            VIA   -    MD0100PA00X+048017Y+111365X0200Y         S0      
327m3452            PU9   -25_2M      A01X+047670Y+111661X0810Y0910R090 S1      
327m3452            PC108 -1          A01X+050683Y+109883X0198Y0197     S1      
317m3452            VIA   -    MD0100PA00X+050041Y+110800X0200Y         S0      
317m3452            VIA   -    MD0100PA00X+050183Y+109309X0200Y         S0      
317m3452            VIA   -    MD0100PA00X+050461Y+110800X0200Y         S0      
327m3452            PC91  -1          A01X+047470Y+109883X0198Y0197     S1      
317m3452            VIA   -    MD0100PA00X+046828Y+110800X0200Y         S0      
317m3452            VIA   -    MD0100PA00X+047248Y+110800X0200Y         S0      
317m3452            VIA   -    MD0100PA00X+047428Y+109305X0200Y         S0      
327m3452            PC96  -1          A01X+050533Y+109309X0400Y0500R180 S1      
317m3452            VIA   -    MD0100PA00X+050183Y+109029X0200Y         S0      
317m3452            VIA   -    MD0100PA00X+049400Y+108430X0200Y         S0      
317m3452            VIA   -    MD0100PA00X+049650Y+108430X0200Y         S0      
317m3452            VIA   -    MD0100PA00X+049900Y+108430X0200Y         S0      
317m3452            VIA   -    MD0100PA00X+050150Y+108430X0200Y         S0      
317m3452            VIA   -    MD0100PA00X+050150Y+108680X0200Y         S0      
317m3452            VIA   -    MD0100PA00X+049900Y+108680X0200Y         S0      
317m3452            VIA   -    MD0100PA00X+049650Y+108680X0200Y         S0      
317m3452            VIA   -    MD0100PA00X+049400Y+108680X0200Y         S0      
317m3452            VIA   -    MD0100PA00X+047602Y+108672X0200Y         S0      
317m3452            VIA   -    MD0100PA00X+047602Y+108422X0200Y         S0      
317m3452            VIA   -    MD0100PA00X+047602Y+108172X0200Y         S0      
317m3452            VIA   -    MD0100PA00X+047852Y+108172X0200Y         S0      
317m3452            VIA   -    MD0100PA00X+047852Y+108422X0200Y         S0      
317m3452            VIA   -    MD0100PA00X+047852Y+108672X0200Y         S0      
317m3452            VIA   -    MD0100PA00X+049150Y+108430X0200Y         S0      
317m3452            VIA   -    MD0100PA00X+049150Y+108680X0200Y         S0      
317m3452            VIA   -    MD0100PA00X+047435Y+109017X0200Y         S0      
317m3452            VIA   -    MD0100PA00X+047761Y+108994X0200Y         S0      
327m3452            PC111 -1          A01X+047078Y+109307X0400Y0500     S1      
317m3452            VIA   -    M      A01X+047776Y+109343X0200Y         S2      
017m3452            VIA   -    M      A18X+047776Y+109343X0260Y         S2      
017m3452                  -    MD0100PA00X+047776Y+109343                       
327m3453            PU10  -10_1       A01X+051493Y+113307X0240Y1700R270 S1      
327m3453            PL10  -1          A01X+051248Y+114354X1220Y1320R180 S1      
327m3454            PR108 -1          A01X+048004Y+110570X0198Y0197R270 S1      
327m3454            PU9   -33         A01X+048000Y+111023X0090Y0240R180 S1      
327m3455            PR114 -1          A01X+052025Y+110192X0198Y0197R270 S1      
317m3455            VIA   -    M      A01X+052106Y+110434X0200Y         S2      
017m3455            VIA   -    M      A18X+052106Y+110434X0260Y         S2      
017m3455                  -    MD0100PA00X+052106Y+110434                       
327m3455            PU10  -37         A01X+051922Y+111023X0090Y0240R180 S1      
327m3456            PR108 -2          A01X+048004Y+110256X0198Y0197R270 S1      
327m3456            PC99  -2          A01X+047626Y+110256X0198Y0197R270 S1      
327P0V8_PEX1_VCC1   PR7168-2          A18X+048713Y+111118X0198Y0197R180 S2      
327P0V8_PEX1_VCC1   R6764 -1   M      A18X+049107Y+111248X0198Y0197R090 S2      
317P0V8_PEX1_VCC1   VIA   -    MD0100PA00X+049706Y+111590X0200Y         S0      
327P0V8_PEX1_VCC1   PR107 -2   M      A18X+049437Y+111582X0198Y0197R090 S2      
327P0V8_PEX1_VCC1   PU9   -3          A01X+049225Y+111624X0090Y0240R270 S1      
327P0V8_PEX1_VCC1   PC98  -1   M      A01X+049687Y+111347X0198Y0197R270 S1      
327m3457            PC115 -1          A01X+050838Y+110570X0198Y0197R270 S1      
327m3457            PU10  -32         A01X+051036Y+111023X0090Y0240R180 S1      
327m3458            PR112 -2          A01X+051217Y+110256X0198Y0197R270 S1      
327m3458            PC115 -2          A01X+050838Y+110256X0198Y0197R270 S1      
327m3459            PR112 -1          A01X+051217Y+110570X0198Y0197R270 S1      
327m3459            PU10  -33         A01X+051213Y+111023X0090Y0240R180 S1      
327m3460            PR110 -1          A01X+048812Y+110192X0198Y0197R270 S1      
317m3460            VIA   -    M      A01X+048893Y+110434X0200Y         S2      
017m3460            VIA   -    M      A18X+048893Y+110434X0260Y         S2      
017m3460                  -    MD0100PA00X+048893Y+110434                       
327m3460            PU9   -37         A01X+048709Y+111023X0090Y0240R180 S1      
327m3461            PR77  -2   M      A01X+049121Y+103218X0198Y0197R180 S1      
327m3461            VIA   -           A01X+049121Y+102745X0300Y         S1      
327m3461            PU6   -21         A01X+048258Y+102675X0070Y0240     S1      
327m3461            PC49  -1   M      A01X+048536Y+103168X0198Y0197R180 S1      
327m3462            VIA   -    M      A18X+054362Y+129273X0260Y         S2      
327m3462            PJ20  -1          A18X+053029Y+129300X0200Y0400R270 S2      
317m3462            VIA   -    MD0080PA00X+074616Y+118927X0160Y         S0      
327m3462            PEX1  -V39        A01X+074429Y+119114X0180Y         S1      
327m3463            R827  -2          A01X+050902Y+100477X0198Y0197R180 S1      
327m3463            VIA   -    M      A01X+049165Y+101196X0300Y         S1      
327m3463            PU6   -13         A01X+048494Y+101337X0070Y0240R090 S1      
327m3463            C200  -2   M      A01X+050102Y+100477X0198Y0197R180 S1      
327m3464            R829  -2          A01X+048809Y+099534X0198Y0197R090 S1      
327m3464            VIA   -    M      A01X+048450Y+100147X0300Y         S1      
327m3464            PU6   -9          A01X+048101Y+100785X0070Y0240     S1      
327m3465            PU1   -11         A01X+080145Y+146140X0090Y0150     S1      
317m3465            VIA   -    M      A01X+079708Y+146788X0200Y    R270 S2      
017m3465            VIA   -    M      A18X+079708Y+146788X0260Y    R270 S2      
017m3465                  -    MD0100PA00X+079708Y+146788                       
317m3465            VIA   -    MD0100PA00X+089111Y+131430X0200Y         S0      
317m3465            VIA   -    MD0100PA00X+084094Y+101150X0200Y         S0      
327m3465            R6245 -2          A01X+051380Y+097388X0198Y0197     S1      
317m3465            VIA   -    MD0100PA00X+076891Y+143774X0200Y         S0      
327m3465            PJ1   -3          A01X+073670Y+143166X0400Y1090R270 S1      
327m3466            VIA   -    M      A18X+045559Y+101582X0260Y         S2      
327m3466            PR94  -1          A01X+045686Y+101632X0198Y0197R180 S1      
327m3466            PU6   -37         A01X+046605Y+101494X0070Y0240R090 S1      
317m3466            VIA   -    MD0100PA00X+045986Y+101582X0200Y         S0      
327m3466            PC54  -1   M      A18X+045059Y+101419X0198Y0197R270 S2      
327m3466            PR93  -2          A18X+044359Y+101419X0198Y0197R090 S2      
327m3466            PR96  -2   M      A18X+044709Y+101419X0198Y0197R090 S2      
327P0V8_PEX0_TSEN   PR95  -2          A18X+045638Y+102677X0198Y0197R270 S2      
317P0V8_PEX0_TSEN   VIA   -    MD0100PA00X+042078Y+110555X0200Y         S0      
317P0V8_PEX0_TSEN   VIA   -    MD0100PA00X+045291Y+110555X0200Y         S0      
317P0V8_PEX0_TSEN   VIA   -    M      A01X+045209Y+103988X0200Y         S2      
017P0V8_PEX0_TSEN   VIA   -    M      A18X+045209Y+103988X0260Y         S2      
017P0V8_PEX0_TSEN         -    MD0100PA00X+045209Y+103988                       
327P0V8_PEX0_TSEN   PU8   -36         A01X+045186Y+111023X0090Y0240R180 S1      
327P0V8_PEX0_TSEN   PU7   -36         A01X+041973Y+111023X0090Y0240R180 S1      
327m3467            R826  -2          A01X+050902Y+099677X0198Y0197R180 S1      
327m3467            VIA   -    M      A01X+049557Y+100418X0300Y         S1      
327m3467            PU6   -12         A01X+048494Y+101179X0070Y0240R090 S1      
327m3467            C199  -1   M      A01X+050102Y+100077X0198Y0197     S1      
327m3467            R825  -2          A01X+050902Y+100077X0198Y0197R180 S1      
327m3468            PR84  -1   M      A01X+044867Y+103027X0198Y0197R180 S1      
317m3468            VIA   -    M      A01X+045088Y+102842X0200Y         S2      
017m3468            VIA   -    M      A18X+045088Y+102842X0260Y         S2      
017m3468                  -    MD0100PA00X+045088Y+102842                       
327m3468            PU6   -33         A01X+046605Y+102124X0070Y0240R090 S1      
327m3468            PR82  -1          A01X+044867Y+103427X0198Y0197R180 S1      
327m3469            PR97  -2          A18X+045059Y+101034X0198Y0197R270 S2      
327m3469            PC56  -1          A01X+045686Y+101232X0198Y0197R180 S1      
327m3469            PU6   -38         A01X+046605Y+101337X0070Y0240R090 S1      
317m3469            VIA   -    M      A01X+045936Y+101232X0200Y         S2      
017m3469            VIA   -    M      A18X+045936Y+101232X0260Y         S2      
017m3469                  -    MD0100PA00X+045936Y+101232                       
327m3469            PR98  -1   M      A18X+045459Y+101034X0198Y0197R090 S2      
327m3470            PR80  -1          A01X+045402Y+102477X0198Y0197     S1      
327m3470            PJ6   -2          A01X+045609Y+102982X0280Y0320R180 S1      
327P5V_AUX          U430  -10         A01X+005645Y+082968X0110Y0360R090 S1      
327P5V_AUX          U431  -10         A01X+057350Y+094377X0110Y0360R090 S1      
327P5V_AUX          PR96  -1          A18X+044709Y+101734X0198Y0197R090 S2      
317P5V_AUX          VIA   -    MD0100PA00X+044709Y+101977X0200Y         S0      
317P5V_AUX          VIA   -    MD0100PA00X+043265Y+101938X0200Y         S0      
317P5V_AUX          VIA   -    MD0100PA00X+042985Y+101938X0200Y         S0      
317P5V_AUX          VIA   -    MD0100PA00X+042705Y+101938X0200Y         S0      
317P5V_AUX          VIA   -    MD0100PA00X+042708Y+101619X0200Y         S0      
317P5V_AUX          VIA   -    MD0100PA00X+042988Y+101619X0200Y         S0      
317P5V_AUX          VIA   -    MD0100PA00X+043268Y+101619X0200Y         S0      
317P5V_AUX          VIA   -    MD0100PA00X+003736Y+069908X0200Y         S0      
317P5V_AUX          VIA   -    MD0100PA00X+004016Y+069908X0200Y         S0      
317P5V_AUX          VIA   -    MD0100PA00X+003456Y+069908X0200Y         S0      
317P5V_AUX          VIA   -    MD0100PA00X+003529Y+066295X0200Y         S0      
317P5V_AUX          VIA   -    MD0100PA00X+003785Y+066291X0200Y         S0      
317P5V_AUX          VIA   -    MD0100PA00X+003525Y+067151X0200Y         S0      
317P5V_AUX          VIA   -    MD0100PA00X+003780Y+067151X0200Y         S0      
317P5V_AUX          VIA   -    MD0100PA00X+003691Y+068211X0200Y         S0      
317P5V_AUX          VIA   -    MD0100PA00X+008431Y+068611X0200Y         S0      
317P5V_AUX          VIA   -    MD0100PA00X+003955Y+068211X0200Y         S0      
327P5V_AUX          R501  -1          A01X+008189Y+068611X0198Y0197R180 S1      
327P5V_AUX          PC20  -1          A01X+003642Y+066729X0400Y0500     S1      
327P5V_AUX          PL2   -2          A01X+004501Y+067178X0730Y1380R180 S1      
327P5V_AUX          PC21  -1          A01X+003642Y+067576X0400Y0500     S1      
327P5V_AUX          PJ2   -2          A01X+009184Y+068258X0180Y0200R270 S1      
327P5V_AUX          PC22  -1   M      A01X+004945Y+068847X0198Y0197     S1      
317P5V_AUX          VIA   -    MD0100PA00X+047188Y+093724X0200Y         S0      
317P5V_AUX          VIA   -    MD0100PA00X+057310Y+094131X0200Y    R270 S0      
327P5V_AUX          C4419 -1          A01X+057320Y+093847X0198Y0197R270 S1      
317P5V_AUX          VIA   -    MD0100PA00X+005605Y+082722X0200Y    R270 S0      
327P5V_AUX          C4414 -1          A01X+005615Y+082438X0198Y0197R270 S1      
317P5V_AUX          VIA   -    MD0100PA00X+016619Y+106655X0200Y         S0      
317P5V_AUX          VIA   -    MD0100PA00X+007101Y+122868X0200Y         S0      
327P5V_AUX          R6753 -1          A01X+002238Y+155175X0198Y0197R270 S1      
317P5V_AUX          VIA   -    MD0100PA00X+002238Y+155415X0200Y         S0      
327P5V_AUX          PR7175-2          A18X+043182Y+112591X0198Y0197R270 S2      
317P5V_AUX          VIA   -    MD0100PA00X+043284Y+112882X0200Y         S0      
327P5V_AUX          PR7178-2          A18X+049353Y+112599X0198Y0197R270 S2      
317P5V_AUX          VIA   -    MD0100PA00X+049524Y+112909X0200Y         S0      
327P5V_AUX          PC349 -1   M      A01X+140281Y+053673X0198Y0197R180 S1      
317P5V_AUX          VIA   -    MD0100PA00X+140144Y+053421X0200Y    R180 S0      
327P5V_AUX          PU27  -10         A01X+140958Y+053846X0110Y0240R090 S1      
327P5V_AUX          PC325 -1   M      A01X+048864Y+053673X0198Y0197R180 S1      
317P5V_AUX          VIA   -    MD0100PA00X+048284Y+053425X0200Y    R180 S0      
327P5V_AUX          PU26  -10         A01X+049541Y+053846X0110Y0240R090 S1      
327P5V_AUX          PC360 -1   M      A01X+003155Y+053673X0198Y0197R180 S1      
317P5V_AUX          VIA   -    MD0100PA00X+003018Y+053421X0200Y         S0      
327P5V_AUX          PU22  -10         A01X+003832Y+053846X0110Y0240R090 S1      
317P5V_AUX          VIA   -    MD0100PA00X+101392Y+085131X0200Y         S0      
327P5V_AUX          C4424 -1          A01X+101482Y+093549X0198Y0197R270 S1      
317P5V_AUX          VIA   -    MD0100PA00X+101472Y+093832X0200Y    R270 S0      
327P5V_AUX          U432  -10         A01X+101512Y+094078X0110Y0360R090 S1      
327P5V_AUX          PC312 -1   M      A01X+094572Y+053673X0198Y0197R180 S1      
317P5V_AUX          VIA   -    MD0100PA00X+094435Y+053421X0200Y    R180 S0      
317P5V_AUX          VIA   -    MD0100PA00X+093665Y+052684X0200Y    R180 S0      
317P5V_AUX          VIA   -    MD0100PA00X+094543Y+063432X0200Y    R180 S0      
317P5V_AUX          VIA   -    MD0100PA00X+094318Y+063254X0200Y         S0      
317P5V_AUX          VIA   -    MD0100PA00X+094613Y+066652X0200Y         S0      
317P5V_AUX          VIA   -    MD0100PA00X+094914Y+066666X0200Y    R180 S0      
317P5V_AUX          VIA   -    MD0100PA00X+095476Y+082673X0200Y         S0      
327P5V_AUX          R473  -1          A01X+095034Y+082328X0198Y0197R090 S1      
317P5V_AUX          VIA   -    MD0100PA00X+095738Y+082659X0200Y         S0      
317P5V_AUX          VIA   -    MD0100PA00X+134066Y+102612X0200Y         S0      
317P5V_AUX          VIA   -    MD0100PA00X+134346Y+102612X0200Y         S0      
317P5V_AUX          VIA   -    MD0100PA00X+134066Y+102892X0200Y         S0      
317P5V_AUX          VIA   -    MD0100PA00X+134346Y+102892X0200Y         S0      
317P5V_AUX          VIA   -    MD0100PA00X+119021Y+090091X0200Y         S0      
317P5V_AUX          VIA   -    MD0100PA00X+119237Y+090378X0200Y         S0      
317P5V_AUX          VIA   -    MD0100PA00X+131705Y+098811X0200Y         S0      
317P5V_AUX          VIA   -    MD0100PA00X+131725Y+099078X0200Y         S0      
327P5V_AUX          PR145 -1          A18X+136126Y+101734X0198Y0197R090 S2      
317P5V_AUX          VIA   -    MD0100PA00X+136126Y+101977X0200Y         S0      
317P5V_AUX          VIA   -    MD0100PA00X+131794Y+052306X0200Y         S0      
317P5V_AUX          VIA   -    MD0100PA00X+131816Y+052005X0200Y         S0      
317P5V_AUX          VIA   -    MD0100PA00X+132116Y+052313X0200Y         S0      
317P5V_AUX          VIA   -    MD0100PA00X+132145Y+052027X0200Y         S0      
317P5V_AUX          VIA   -    MD0100PA00X+123870Y+062731X0200Y         S0      
317P5V_AUX          VIA   -    MD0100PA00X+123803Y+062996X0200Y    R090 S0      
317P5V_AUX          VIA   -    MD0100PA00X+123750Y+063240X0200Y    R090 S0      
327P5V_AUX          U342  -10         A01X+100744Y+084620X0110Y0360R270 S1      
327P5V_AUX          C2848 -1   M      A01X+101563Y+084868X0198Y0197     S1      
327P5V_AUX          PR7180-2          A18X+134222Y+112586X0198Y0197R270 S2      
317P5V_AUX          VIA   -    MD0100PA00X+134372Y+112874X0200Y         S0      
327P5V_AUX          PR7182-2          A18X+141183Y+112601X0198Y0197R270 S2      
317P5V_AUX          VIA   -    MD0100PA00X+141318Y+112889X0200Y         S0      
327P5V_AUX          PU23  -10         A01X+095250Y+053846X0110Y0240R090 S1      
327P5V_AUX          PC302 -1   M      A01X+046283Y+050767X0198Y0197     S1      
317P5V_AUX          VIA   -    MD0100PA00X+046420Y+051018X0200Y         S0      
327P5V_AUX          PU21  -10         A01X+045461Y+049962X0110Y0240R270 S1      
327P5V_AUX          U433  -10         A01X+178976Y+097162X0110Y0360R090 S1      
327P5V_AUX          PC492 -1   M      A01X+175935Y+048238X0198Y0197     S1      
317P5V_AUX          VIA   -    MD0100PA00X+175840Y+048488X0200Y         S0      
317P5V_AUX          VIA   -    MD0100PA00X+178936Y+096916X0200Y    R270 S0      
327P5V_AUX          C4429 -1          A01X+178946Y+096632X0198Y0197R270 S1      
327P5V_AUX          PU53  -10         A01X+175225Y+047851X0110Y0240R270 S1      
327P5V_AUX          PC480 -1   M      A01X+141264Y+048398X0198Y0197R180 S1      
317P5V_AUX          VIA   -    MD0100PA00X+141127Y+048147X0200Y    R180 S0      
327P5V_AUX          PU51  -10         A01X+141941Y+049171X0110Y0240R090 S1      
327P5V_AUX          PC493 -1   M      A01X+095555Y+048398X0198Y0197R180 S1      
317P5V_AUX          VIA   -    MD0100PA00X+095418Y+048147X0200Y    R180 S0      
327P5V_AUX          PU47  -10         A01X+096233Y+049171X0110Y0240R090 S1      
327P5V_AUX          R5961 -1          A01X+088903Y+048630X0198Y0197R180 S1      
317P5V_AUX          VIA   -    MD0100PA00X+089145Y+048630X0200Y    R090 S0      
327P5V_AUX          PC457 -1   M      A01X+049847Y+048398X0198Y0197R180 S1      
317P5V_AUX          VIA   -    MD0100PA00X+049710Y+048147X0200Y    R180 S0      
327P5V_AUX          PU50  -10         A01X+050524Y+049171X0110Y0240R090 S1      
327P5V_AUX          PC348 -1   M      A01X+038809Y+048238X0198Y0197     S1      
317P5V_AUX          VIA   -    MD0100PA00X+038714Y+048488X0200Y         S0      
327P5V_AUX          PU48  -10         A01X+038099Y+047851X0110Y0240R270 S1      
327P5V_AUX          PC481 -1   M      A01X+004138Y+048398X0198Y0197R180 S1      
317P5V_AUX          VIA   -    MD0100PA00X+004001Y+048147X0200Y    R180 S0      
327P5V_AUX          PU46  -10         A01X+004815Y+049171X0110Y0240R090 S1      
327P5V_AUX          R6049 -1          A01X+179614Y+047456X0198Y0197R180 S1      
317P5V_AUX          VIA   -    MD0100PA00X+179614Y+047133X0200Y    R090 S0      
327P5V_AUX          PC468 -1   M      A01X+130227Y+048238X0198Y0197     S1      
327P5V_AUX          R6037 -1          A01X+133905Y+047456X0198Y0197R180 S1      
317P5V_AUX          VIA   -    MD0100PA00X+133905Y+047133X0200Y    R090 S0      
317P5V_AUX          VIA   -    MD0100PA00X+130131Y+048488X0200Y         S0      
327P5V_AUX          PU49  -10         A01X+129516Y+047851X0110Y0240R270 S1      
327P5V_AUX          R5861 -1          A01X+042488Y+047456X0198Y0197R180 S1      
317P5V_AUX          VIA   -    MD0100PA00X+042488Y+047133X0200Y    R090 S0      
327P5V_AUX          R6036 -1          A01X+096282Y+044534X0198Y0197R090 S1      
317P5V_AUX          VIA   -    MD0100PA00X+096282Y+044292X0200Y         S0      
317P5V_AUX          VIA   -    MD0100PA00X+004864Y+044292X0200Y         S0      
327P5V_AUX          R5860 -1          A01X+004864Y+044534X0198Y0197R090 S1      
327P5V_AUX          R6048 -1          A01X+141790Y+044234X0198Y0197R090 S1      
317P5V_AUX          VIA   -    MD0100PA00X+141790Y+043992X0200Y         S0      
327P5V_AUX          R5960 -1          A01X+050373Y+044234X0198Y0197R090 S1      
317P5V_AUX          VIA   -    MD0100PA00X+050373Y+043992X0200Y         S0      
327P5V_AUX          PC336 -1   M      A01X+176050Y+037663X0198Y0197R270 S1      
317P5V_AUX          VIA   -    MD0100PA00X+176300Y+037758X0200Y    R270 S0      
327P5V_AUX          PU29  -10         A01X+175663Y+038373X0110Y0240R180 S1      
327P5V_AUX          PC324 -1   M      A01X+130341Y+037663X0198Y0197R270 S1      
317P5V_AUX          VIA   -    MD0100PA00X+130591Y+037758X0200Y    R270 S0      
327P5V_AUX          PU25  -10         A01X+129954Y+038373X0110Y0240R180 S1      
327P5V_AUX          R5872 -1          A01X+003351Y+027060X0198Y0197R180 S1      
317P5V_AUX          VIA   -    MD0100PA00X+003168Y+026687X0200Y         S0      
327P5V_AUX          R6121 -1          A01X+167394Y+014977X0198Y0197R180 S1      
317P5V_AUX          VIA   -    MD0100PA00X+167394Y+015256X0200Y         S0      
327P5V_AUX          R6120 -1          A01X+157158Y+014977X0198Y0197R180 S1      
317P5V_AUX          VIA   -    MD0100PA00X+157158Y+015256X0200Y         S0      
327P5V_AUX          R6109 -1          A01X+146922Y+014977X0198Y0197R180 S1      
317P5V_AUX          VIA   -    MD0100PA00X+146922Y+015256X0200Y         S0      
327P5V_AUX          R6108 -1          A01X+136686Y+014977X0198Y0197R180 S1      
317P5V_AUX          VIA   -    MD0100PA00X+136686Y+015256X0200Y         S0      
327P5V_AUX          R6097 -1          A01X+121686Y+014977X0198Y0197R180 S1      
317P5V_AUX          VIA   -    MD0100PA00X+121686Y+015256X0200Y         S0      
327P5V_AUX          R6096 -1          A01X+111450Y+014977X0198Y0197R180 S1      
317P5V_AUX          VIA   -    MD0100PA00X+111450Y+015256X0200Y         S0      
327P5V_AUX          R6085 -1          A01X+101213Y+014977X0198Y0197R180 S1      
317P5V_AUX          VIA   -    MD0100PA00X+101213Y+015256X0200Y         S0      
327P5V_AUX          R6084 -1          A01X+090977Y+014977X0198Y0197R180 S1      
317P5V_AUX          VIA   -    MD0100PA00X+090977Y+015256X0200Y         S0      
327P5V_AUX          R6073 -1          A01X+075977Y+014977X0198Y0197R180 S1      
317P5V_AUX          VIA   -    MD0100PA00X+075977Y+015256X0200Y         S0      
327P5V_AUX          R6072 -1          A01X+065741Y+014977X0198Y0197R180 S1      
317P5V_AUX          VIA   -    MD0100PA00X+065741Y+015256X0200Y         S0      
327P5V_AUX          R6061 -1          A01X+055505Y+014977X0198Y0197R180 S1      
317P5V_AUX          VIA   -    MD0100PA00X+055505Y+015256X0200Y         S0      
327P5V_AUX          R6060 -1          A01X+045269Y+014977X0198Y0197R180 S1      
317P5V_AUX          VIA   -    MD0100PA00X+045269Y+015256X0200Y         S0      
327P5V_AUX          R5885 -1          A01X+030268Y+014977X0198Y0197R180 S1      
317P5V_AUX          VIA   -    MD0100PA00X+030268Y+015256X0200Y         S0      
327P5V_AUX          R5884 -1          A01X+020032Y+014977X0198Y0197R180 S1      
317P5V_AUX          VIA   -    MD0100PA00X+020032Y+015256X0200Y         S0      
327P5V_AUX          R5873 -1          A01X+009796Y+014977X0198Y0197R180 S1      
317P5V_AUX          VIA   -    MD0100PA00X+009796Y+015256X0200Y         S0      
327P5V_AUX          PU24  -10         A01X+038537Y+038373X0110Y0240R180 S1      
327P5V_AUX          PU28  -10         A01X+088069Y+039707X0110Y0240R180 S1      
327P5V_AUX          PU30  -10         A01X+009507Y+021513X0110Y0240R270 S1      
327P5V_AUX          PU32  -10         A01X+019743Y+021513X0110Y0240R270 S1      
327P5V_AUX          PU34  -10         A01X+029979Y+021513X0110Y0240R270 S1      
327P5V_AUX          PU36  -10         A01X+040215Y+021513X0110Y0240R270 S1      
327P5V_AUX          PU31  -10         A01X+055216Y+021513X0110Y0240R270 S1      
327P5V_AUX          PU33  -10         A01X+065452Y+021513X0110Y0240R270 S1      
327P5V_AUX          PU35  -10         A01X+075688Y+021513X0110Y0240R270 S1      
327P5V_AUX          PU37  -10         A01X+085924Y+021513X0110Y0240R270 S1      
327P5V_AUX          PU38  -10         A01X+100924Y+021513X0110Y0240R270 S1      
327P5V_AUX          PU39  -10         A01X+146633Y+021513X0110Y0240R270 S1      
327P5V_AUX          PU40  -10         A01X+111160Y+021513X0110Y0240R270 S1      
327P5V_AUX          PU41  -10         A01X+156869Y+021513X0110Y0240R270 S1      
327P5V_AUX          PU42  -10         A01X+121396Y+021513X0110Y0240R270 S1      
327P5V_AUX          PU43  -10         A01X+167105Y+021513X0110Y0240R270 S1      
327P5V_AUX          PU44  -10         A01X+131633Y+021513X0110Y0240R270 S1      
327P5V_AUX          PU45  -10         A01X+177341Y+021513X0110Y0240R270 S1      
327P5V_AUX          PU52  -10         A01X+083808Y+047351X0110Y0240R270 S1      
327P5V_AUX          PU54  -10         A01X+002615Y+022506X0110Y0240     S1      
327P5V_AUX          PU55  -10         A01X+048323Y+022506X0110Y0240     S1      
327P5V_AUX          PU56  -10         A01X+012851Y+022506X0110Y0240     S1      
327P5V_AUX          PU57  -10         A01X+058560Y+022506X0110Y0240     S1      
327P5V_AUX          PU59  -10         A01X+023087Y+022506X0110Y0240     S1      
327P5V_AUX          PU58  -10         A01X+068796Y+022506X0110Y0240     S1      
327P5V_AUX          PU60  -10         A01X+033323Y+022506X0110Y0240     S1      
327P5V_AUX          PU61  -10         A01X+079032Y+022506X0110Y0240     S1      
327P5V_AUX          PU62  -10         A01X+094098Y+021023X0110Y0240     S1      
327P5V_AUX          PU63  -10         A01X+139741Y+022506X0110Y0240     S1      
327P5V_AUX          PU64  -10         A01X+104268Y+022506X0110Y0240     S1      
327P5V_AUX          PU65  -10         A01X+149977Y+022506X0110Y0240     S1      
327P5V_AUX          PU67  -10         A01X+160213Y+022506X0110Y0240     S1      
327P5V_AUX          PU66  -10         A01X+114504Y+022506X0110Y0240     S1      
327P5V_AUX          PU68  -10         A01X+170449Y+022506X0110Y0240     S1      
327P5V_AUX          PU69  -10         A01X+124740Y+022506X0110Y0240     S1      
327P5V_AUX          J2    -A14        A01X+091542Y+026220X0150Y0530R090 S1      
327P5V_AUX          J2    -A8         A01X+091542Y+024803X0150Y0530R090 S1      
327P5V_AUX          J2    -A6         A01X+091542Y+024331X0150Y0530R090 S1      
327P5V_AUX          J2    -B18        A01X+090330Y+027165X0150Y0530R090 S1      
317P5V_AUX          VIA   -    MD0100PA00X+091958Y+026457X0200Y    R180 S0      
327P5V_AUX          J2    -A15        A01X+091542Y+026457X0150Y0530R090 S1      
317P5V_AUX          VIA   -    MD0100PA00X+091962Y+026846X0200Y    R180 S0      
327P5V_AUX          J2    -A17        A01X+091542Y+026929X0150Y0530R090 S1      
317P5V_AUX          VIA   -    MD0100PA00X+091958Y+027165X0200Y    R180 S0      
327P5V_AUX          J2    -A18        A01X+091542Y+027165X0150Y0530R090 S1      
317P5V_AUX          VIA   -    MD0100PA00X+091098Y+026220X0200Y         S0      
327P5V_AUX          VIA   -           A18X+060355Y+025078X0260Y         S2      
327P5V_AUX          J2    -A5         A01X+091542Y+024094X0150Y0530R090 S1      
327P5V_AUX          J2    -A9         A01X+091542Y+025039X0150Y0530R090 S1      
327P5V_AUX          VIA   -           A18X+087282Y+024439X0260Y         S2      
327P5V_AUX          VIA   -           A18X+061340Y+024291X0260Y         S2      
327P5V_AUX          VIA   -           A18X+005103Y+024291X0260Y         S2      
317P5V_AUX          VIA   -    MD0100PA00X+084423Y+047988X0200Y         S0      
317P5V_AUX          VIA   -    MD0100PA00X+003168Y+024687X0200Y         S0      
327P5V_AUX          R5840 -1          A01X+003351Y+025060X0198Y0197R180 S1      
317P5V_AUX          VIA   -    MD0100PA00X+002156Y+023297X0200Y    R090 S0      
327P5V_AUX          PC541 -1   M      A01X+002409Y+023297X0198Y0197R090 S1      
317P5V_AUX          VIA   -    MD0100PA00X+010321Y+021938X0200Y         S0      
327P5V_AUX          PC385 -1   M      A01X+010184Y+021686X0198Y0197     S1      
317P5V_AUX          VIA   -    MD0100PA00X+013404Y+024687X0200Y         S0      
317P5V_AUX          VIA   -    MD0100PA00X+012392Y+023297X0200Y    R090 S0      
327P5V_AUX          PC516 -1   M      A01X+012645Y+023297X0198Y0197R090 S1      
317P5V_AUX          VIA   -    MD0100PA00X+020558Y+021938X0200Y         S0      
327P5V_AUX          PC421 -1   M      A01X+020420Y+021686X0198Y0197     S1      
317P5V_AUX          VIA   -    MD0100PA00X+022628Y+023297X0200Y    R090 S0      
327P5V_AUX          PC517 -1   M      A01X+022882Y+023297X0198Y0197R090 S1      
317P5V_AUX          VIA   -    MD0100PA00X+023641Y+024687X0200Y         S0      
327P5V_AUX          R5850 -1          A01X+023823Y+025060X0198Y0197R180 S1      
317P5V_AUX          VIA   -    MD0100PA00X+030794Y+021938X0200Y         S0      
327P5V_AUX          PC397 -1   M      A01X+030657Y+021686X0198Y0197     S1      
317P5V_AUX          VIA   -    MD0100PA00X+032864Y+023297X0200Y    R090 S0      
317P5V_AUX          VIA   -    MD0100PA00X+033877Y+024687X0200Y         S0      
317P5V_AUX          VIA   -    MD0100PA00X+039174Y+037758X0200Y    R270 S0      
327P5V_AUX          PC456 -1   M      A01X+038924Y+037663X0198Y0197R270 S1      
327P5V_AUX          PC373 -1   M      A01X+040893Y+021686X0198Y0197     S1      
317P5V_AUX          VIA   -    MD0100PA00X+041030Y+021938X0200Y         S0      
317P5V_AUX          VIA   -    MD0100PA00X+048877Y+024687X0200Y         S0      
327P5V_AUX          R5976 -1          A01X+049059Y+025060X0198Y0197R180 S1      
317P5V_AUX          VIA   -    MD0100PA00X+047864Y+023297X0200Y    R090 S0      
327P5V_AUX          PC540 -1   M      A01X+048118Y+023297X0198Y0197R090 S1      
317P5V_AUX          VIA   -    MD0100PA00X+056030Y+021938X0200Y         S0      
327P5V_AUX          PC313 -1   M      A01X+055893Y+021686X0198Y0197     S1      
317P5V_AUX          VIA   -    MD0100PA00X+058100Y+023297X0200Y    R090 S0      
327P5V_AUX          PC505 -1   M      A01X+058354Y+023297X0198Y0197R090 S1      
317P5V_AUX          VIA   -    MD0100PA00X+059113Y+024687X0200Y         S0      
327P5V_AUX          R5977 -1          A01X+059296Y+025060X0198Y0197R180 S1      
317P5V_AUX          VIA   -    MD0100PA00X+066266Y+021938X0200Y         S0      
327P5V_AUX          PC396 -1   M      A01X+066129Y+021686X0198Y0197     S1      
317P5V_AUX          VIA   -    MD0100PA00X+068337Y+023297X0200Y    R090 S0      
327P5V_AUX          PC504 -1   M      A01X+068590Y+023297X0198Y0197R090 S1      
317P5V_AUX          VIA   -    MD0100PA00X+069349Y+024687X0200Y         S0      
327P5V_AUX          R5986 -1          A01X+069532Y+025060X0198Y0197R180 S1      
317P5V_AUX          VIA   -    MD0100PA00X+076502Y+021938X0200Y         S0      
327P5V_AUX          PC372 -1   M      A01X+076365Y+021686X0198Y0197     S1      
317P5V_AUX          VIA   -    MD0100PA00X+079586Y+024687X0200Y         S0      
327P5V_AUX          R5987 -1          A01X+079768Y+025060X0198Y0197R180 S1      
317P5V_AUX          VIA   -    MD0100PA00X+078573Y+023297X0200Y    R090 S0      
327P5V_AUX          PC528 -1   M      A01X+078826Y+023297X0198Y0197R090 S1      
317P5V_AUX          VIA   -    MD0100PA00X+086739Y+021938X0200Y         S0      
327P5V_AUX          PC384 -1   M      A01X+086602Y+021686X0198Y0197     S1      
317P5V_AUX          VIA   -    MD0100PA00X+089125Y+038748X0200Y    R270 S0      
327P5V_AUX          PC469 -1   M      A01X+088874Y+038886X0198Y0197R270 S1      
317P5V_AUX          VIA   -    MD0100PA00X+089695Y+027201X0200Y         S0      
317P5V_AUX          VIA   -    MD0100PA00X+091098Y+024803X0200Y         S0      
317P5V_AUX          VIA   -    MD0100PA00X+091098Y+024331X0200Y         S0      
317P5V_AUX          VIA   -    MD0100PA00X+091958Y+025039X0200Y    R180 S0      
317P5V_AUX          VIA   -    MD0100PA00X+091958Y+024094X0200Y    R180 S0      
317P5V_AUX          VIA   -    MD0100PA00X+093640Y+021814X0200Y    R090 S0      
327P5V_AUX          PC553 -1   M      A01X+093893Y+021814X0198Y0197R090 S1      
317P5V_AUX          VIA   -    MD0100PA00X+094648Y+025594X0200Y    R090 S0      
327P5V_AUX          R5996 -1          A01X+094276Y+025776X0198Y0197R270 S1      
317P5V_AUX          VIA   -    MD0100PA00X+101739Y+021938X0200Y         S0      
327P5V_AUX          PC408 -1   M      A01X+101602Y+021686X0198Y0197     S1      
317P5V_AUX          VIA   -    MD0100PA00X+103809Y+023297X0200Y    R090 S0      
327P5V_AUX          PC552 -1   M      A01X+104063Y+023297X0198Y0197R090 S1      
317P5V_AUX          VIA   -    MD0100PA00X+104822Y+024687X0200Y         S0      
327P5V_AUX          R5997 -1          A01X+105004Y+025060X0198Y0197R180 S1      
317P5V_AUX          VIA   -    MD0100PA00X+111975Y+021938X0200Y         S0      
327P5V_AUX          PC444 -1   M      A01X+111838Y+021686X0198Y0197     S1      
317P5V_AUX          VIA   -    MD0100PA00X+114045Y+023297X0200Y    R090 S0      
327P5V_AUX          PC565 -1   M      A01X+114299Y+023297X0198Y0197R090 S1      
317P5V_AUX          VIA   -    MD0100PA00X+115058Y+024687X0200Y         S0      
327P5V_AUX          R6006 -1          A01X+115240Y+025060X0198Y0197R180 S1      
327P5V_AUX          PC361 -1   M      A01X+122074Y+021686X0198Y0197     S1      
317P5V_AUX          VIA   -    MD0100PA00X+122211Y+021938X0200Y         S0      
317P5V_AUX          VIA   -    MD0100PA00X+124282Y+023297X0200Y    R090 S0      
327P5V_AUX          PC577 -1   M      A01X+124535Y+023297X0198Y0197R090 S1      
317P5V_AUX          VIA   -    MD0100PA00X+125294Y+024687X0200Y         S0      
327P5V_AUX          R6007 -1          A01X+125476Y+025060X0198Y0197R180 S1      
317P5V_AUX          VIA   -    MD0100PA00X+132447Y+021938X0200Y         S0      
327P5V_AUX          PC432 -1   M      A01X+132310Y+021686X0198Y0197     S1      
317P5V_AUX          VIA   -    MD0100PA00X+139282Y+023297X0200Y    R090 S0      
327P5V_AUX          PC576 -1   M      A01X+139535Y+023297X0198Y0197R090 S1      
317P5V_AUX          VIA   -    MD0100PA00X+140294Y+024687X0200Y         S0      
327P5V_AUX          R6016 -1          A01X+140477Y+025060X0198Y0197R180 S1      
317P5V_AUX          VIA   -    MD0100PA00X+147447Y+021938X0200Y         S0      
327P5V_AUX          PC409 -1   M      A01X+147310Y+021686X0198Y0197     S1      
317P5V_AUX          VIA   -    MD0100PA00X+149518Y+023297X0200Y    R090 S0      
327P5V_AUX          PC564 -1   M      A01X+149771Y+023297X0198Y0197R090 S1      
317P5V_AUX          VIA   -    MD0100PA00X+150530Y+024687X0200Y         S0      
327P5V_AUX          R6017 -1          A01X+150713Y+025060X0198Y0197R180 S1      
317P5V_AUX          VIA   -    MD0100PA00X+157684Y+021938X0200Y         S0      
327P5V_AUX          PC445 -1   M      A01X+157546Y+021686X0198Y0197     S1      
317P5V_AUX          VIA   -    MD0100PA00X+159754Y+023297X0200Y    R090 S0      
327P5V_AUX          PC588 -1   M      A01X+160008Y+023297X0198Y0197R090 S1      
317P5V_AUX          VIA   -    MD0100PA00X+160767Y+024687X0200Y         S0      
327P5V_AUX          R6026 -1          A01X+160949Y+025060X0198Y0197R180 S1      
317P5V_AUX          VIA   -    MD0100PA00X+167920Y+021938X0200Y         S0      
327P5V_AUX          PC420 -1   M      A01X+167783Y+021686X0198Y0197     S1      
317P5V_AUX          VIA   -    MD0100PA00X+171003Y+024687X0200Y         S0      
327P5V_AUX          R6027 -1          A01X+171185Y+025060X0198Y0197R180 S1      
317P5V_AUX          VIA   -    MD0100PA00X+169990Y+023297X0200Y    R090 S0      
327P5V_AUX          PC433 -1   M      A01X+170244Y+023297X0198Y0197R090 S1      
317P5V_AUX          VIA   -    M      A01X+178156Y+021938X0200Y         S2      
017P5V_AUX          VIA   -    M      A18X+178156Y+021938X0260Y         S2      
017P5V_AUX                -    MD0100PA00X+178156Y+021938                       
327P5V_AUX          PC589 -1   M      A01X+178019Y+021686X0198Y0197     S1      
327P5V_AUX          R5851 -1          A01X+034059Y+025060X0198Y0197R180 S1      
327P5V_AUX          PC529 -1   M      A01X+033118Y+023297X0198Y0197R090 S1      
327P5V_AUX          R5841 -1          A01X+013587Y+025060X0198Y0197R180 S1      
327P5V_AUX          PC337 -1   M      A01X+084518Y+047738X0198Y0197     S1      
317P0V8_PEX0_VREF   VIA   -    MD0100PA00X+049065Y+110192X0200Y    R180 S0      
327P0V8_PEX0_VREF   PC89  -1   M      A01X+049350Y+110192X0198Y0197R270 S1      
327P0V8_PEX0_VREF   PU9   -39         A01X+049063Y+111023X0090Y0240R180 S1      
327P0V8_PEX0_VREF   PC122 -1   M      A01X+046004Y+110192X0198Y0197R270 S1      
327P0V8_PEX0_VREF   PU8   -39         A01X+045717Y+111023X0090Y0240R180 S1      
317P0V8_PEX0_VREF   VIA   -    MD0100PA00X+045719Y+110192X0200Y    R090 S0      
317P0V8_PEX0_VREF   VIA   -    MD0100PA00X+042506Y+110192X0200Y    R180 S0      
327P0V8_PEX0_VREF   PC73  -1   M      A01X+042791Y+110192X0198Y0197R270 S1      
327P0V8_PEX0_VREF   PU7   -39         A01X+042505Y+111023X0090Y0240R180 S1      
327P0V8_PEX0_VREF   PU10  -39         A01X+052276Y+111023X0090Y0240R180 S1      
327P0V8_PEX0_VREF   PC106 -1   M      A01X+052510Y+110372X0198Y0197     S1      
317P0V8_PEX0_VREF   VIA   -    MD0100PA00X+052278Y+110192X0200Y    R090 S0      
327P0V8_PEX0_VREF   PR91  -1          A01X+044552Y+102627X0198Y0197     S1      
317P0V8_PEX0_VREF   VIA   -    M      A01X+044309Y+102627X0200Y         S2      
017P0V8_PEX0_VREF   VIA   -    M      A18X+044309Y+102627X0260Y         S2      
017P0V8_PEX0_VREF         -    MD0100PA00X+044309Y+102627                       
317P0V8_PEX0_VREF   VIA   -    MD0100PA00X+046480Y+100065X0200Y         S0      
327P0V8_PEX0_VREF   PC46  -1          A01X+045959Y+099677X0400Y0500     S1      
327P0V8_PEX0_VREF   PC47  -1          A01X+045936Y+100218X0198Y0197R180 S1      
327P0V8_PEX0_VREF   PU6   -40         A01X+046605Y+101022X0070Y0240R090 S1      
327P0V8_PEX0_VREF   PR7140-1          A18X+049651Y+102416X0198Y0197     S2      
327P3V3_AUX         C2008 -1          A18X+090184Y+084687X0164Y0164R090 S2      
327P3V3_AUX         C2026 -1          A18X+090814Y+084687X0164Y0164R090 S2      
327P3V3_AUX         C2007 -1          A18X+090499Y+084687X0164Y0164R090 S2      
317P3V3_AUX         VIA   -    MD0100PA00X+038970Y+153690X0200Y         S0      
327P3V3_AUX         R5448 -1   M      A01X+038444Y+153970X0198Y0197     S1      
327P3V3_AUX         R3148 -2          A01X+091004Y+068777X0198Y0197     S1      
317P3V3_AUX         VIA   -    MD0100PA00X+081015Y+137488X0200Y    R270 S0      
327P3V3_AUX         R6247 -1          A01X+079990Y+147268X0198Y0197R270 S1      
317P3V3_AUX         VIA   -    MD0100PA00X+079931Y+147569X0200Y         S0      
327P3V3_AUX         R496  -1          A01X+081015Y+137761X0198Y0197R090 S1      
327P3V3_AUX         R6045 -1          A01X+177099Y+046756X0198Y0197     S1      
317P3V3_AUX         VIA   -    MD0100PA00X+144682Y+133585X0200Y         S0      
317P3V3_AUX         VIA   -    MD0100PA00X+142393Y+152036X0200Y    R270 S0      
327P3V3_AUX         R6709 -1          A01X+142636Y+152036X0198Y0197     S1      
327P3V3_AUX         R6696 -2          A01X+140854Y+153956X0198Y0197R180 S1      
317P3V3_AUX         VIA   -    MD0100PA00X+140854Y+153657X0200Y         S0      
317P3V3_AUX         VIA   -    MD0100PA00X+143340Y+154600X0200Y    R180 S0      
327P3V3_AUX         R6697 -1          A01X+143340Y+154357X0198Y0197R270 S1      
327P3V3_AUX         R6702 -2          A01X+140804Y+156224X0198Y0197R180 S1      
317P3V3_AUX         VIA   -    MD0100PA00X+140804Y+155931X0200Y         S0      
317P3V3_AUX         VIA   -    MD0100PA00X+140775Y+154905X0200Y    R180 S0      
327P3V3_AUX         R6695 -2          A01X+140775Y+154654X0198Y0197R090 S1      
317P3V3_AUX         VIA   -    MD0100PA00X+140726Y+157173X0200Y    R180 S0      
327P3V3_AUX         R6701 -2          A01X+140726Y+156921X0198Y0197R090 S1      
317P3V3_AUX         VIA   -    MD0100PA00X+143291Y+156868X0200Y    R180 S0      
327P3V3_AUX         R6703 -1          A01X+143291Y+156624X0198Y0197R270 S1      
317P3V3_AUX         VIA   -    MD0100PA00X+142088Y+149471X0200Y    R270 S0      
327P3V3_AUX         R6707 -2          A01X+142340Y+149471X0198Y0197R180 S1      
327P3V3_AUX         R6708 -2          A01X+143037Y+149550X0198Y0197R270 S1      
317P3V3_AUX         VIA   -    MD0100PA00X+143037Y+149247X0200Y         S0      
327P3V3_AUX         R6793 -1          A01X+105441Y+131144X0198Y0197     S1      
327P3V3_AUX         C2571 -2   M      A01X+083273Y+084363X0198Y0197R090 S1      
327P3V3_AUX         R6815 -2          A18X+095736Y+092312X0198Y0197     S2      
327P3V3_AUX         R6813 -2          A18X+090058Y+088452X0198Y0197     S2      
327P3V3_AUX         R6822 -2          A18X+081842Y+089388X0198Y0197     S2      
327P3V3_AUX         R6814 -2          A18X+081697Y+087660X0198Y0197R180 S2      
327P3V3_AUX         R6821 -2          A18X+093126Y+088055X0198Y0197R090 S2      
327P3V3_AUX         R4885 -2          A01X+083631Y+087716X0198Y0197R090 S1      
327P3V3_AUX         R4884 -2          A01X+084267Y+087551X0198Y0197R180 S1      
327P3V3_AUX         R6790 -1   M      A01X+102005Y+133391X0198Y0197R270 S1      
317P3V3_AUX         VIA   -    MD0100PA00X+073832Y+163448X0200Y         S0      
327P3V3_AUX         R6778 -1          A01X+073533Y+163448X0198Y0197R180 S1      
317P3V3_AUX         VIA   -    MD0100PA00X+077836Y+162742X0200Y         S0      
327P3V3_AUX         R6781 -1          A01X+077836Y+163013X0198Y0197R090 S1      
327P3V3_AUX         PU21  -13         A01X+044870Y+049864X0780Y1070     S1      
327P3V3_AUX         PU21  -12         A01X+045461Y+050356X0110Y0240R270 S1      
327P3V3_AUX         PU46  -13         A01X+005406Y+049270X0780Y1070R180 S1      
327P3V3_AUX         PU46  -12         A01X+004815Y+048778X0110Y0240R090 S1      
327P3V3_AUX         PU47  -13         A01X+096823Y+049270X0780Y1070R180 S1      
327P3V3_AUX         PU47  -12         A01X+096233Y+048778X0110Y0240R090 S1      
327P3V3_AUX         PU48  -13         A01X+037508Y+047753X0780Y1070     S1      
327P3V3_AUX         PU48  -12         A01X+038099Y+048245X0110Y0240R270 S1      
327P3V3_AUX         PU50  -13         A01X+051115Y+049270X0780Y1070R180 S1      
327P3V3_AUX         PU50  -12         A01X+050524Y+048778X0110Y0240R090 S1      
327P3V3_AUX         PU52  -13         A01X+083217Y+047253X0780Y1070     S1      
327P3V3_AUX         PU52  -12         A01X+083808Y+047745X0110Y0240R270 S1      
327P3V3_AUX         PU49  -13         A01X+128926Y+047753X0780Y1070     S1      
327P3V3_AUX         PU49  -12         A01X+129516Y+048245X0110Y0240R270 S1      
327P3V3_AUX         PU51  -13         A01X+142532Y+049270X0780Y1070R180 S1      
327P3V3_AUX         PU51  -12         A01X+141941Y+048778X0110Y0240R090 S1      
327P3V3_AUX         PU53  -13         A01X+174634Y+047753X0780Y1070     S1      
327P3V3_AUX         PU53  -12         A01X+175225Y+048245X0110Y0240R270 S1      
327P3V3_AUX         PU54  -13         A01X+002713Y+021915X0780Y1070R090 S1      
327P3V3_AUX         PU54  -12         A01X+002221Y+022506X0110Y0240     S1      
327P3V3_AUX         PU55  -13         A01X+048422Y+021915X0780Y1070R090 S1      
327P3V3_AUX         PU55  -12         A01X+047930Y+022506X0110Y0240     S1      
327P3V3_AUX         PU56  -13         A01X+012949Y+021915X0780Y1070R090 S1      
327P3V3_AUX         PU57  -13         A01X+058658Y+021915X0780Y1070R090 S1      
327P3V3_AUX         PU56  -12         A01X+012457Y+022506X0110Y0240     S1      
327P3V3_AUX         PU57  -12         A01X+058166Y+022506X0110Y0240     S1      
327P3V3_AUX         PU59  -13         A01X+023185Y+021915X0780Y1070R090 S1      
327P3V3_AUX         PU58  -13         A01X+068894Y+021915X0780Y1070R090 S1      
327P3V3_AUX         PU59  -12         A01X+022693Y+022506X0110Y0240     S1      
327P3V3_AUX         PU58  -12         A01X+068402Y+022506X0110Y0240     S1      
327P3V3_AUX         PU60  -13         A01X+033422Y+021915X0780Y1070R090 S1      
327P3V3_AUX         PU61  -13         A01X+079130Y+021915X0780Y1070R090 S1      
327P3V3_AUX         PU60  -12         A01X+032930Y+022506X0110Y0240     S1      
327P3V3_AUX         PU61  -12         A01X+078638Y+022506X0110Y0240     S1      
327P3V3_AUX         PU62  -13         A01X+094197Y+020432X0780Y1070R090 S1      
327P3V3_AUX         PU63  -13         A01X+139839Y+021915X0780Y1070R090 S1      
327P3V3_AUX         PU62  -12         A01X+093705Y+021023X0110Y0240     S1      
327P3V3_AUX         PU63  -12         A01X+139347Y+022506X0110Y0240     S1      
327P3V3_AUX         PU64  -13         A01X+104366Y+021915X0780Y1070R090 S1      
327P3V3_AUX         PU65  -13         A01X+150075Y+021915X0780Y1070R090 S1      
327P3V3_AUX         PU64  -12         A01X+103874Y+022506X0110Y0240     S1      
327P3V3_AUX         PU65  -12         A01X+149583Y+022506X0110Y0240     S1      
327P3V3_AUX         PU67  -13         A01X+160311Y+021915X0780Y1070R090 S1      
327P3V3_AUX         PU66  -13         A01X+114603Y+021915X0780Y1070R090 S1      
327P3V3_AUX         PU67  -12         A01X+159819Y+022506X0110Y0240     S1      
327P3V3_AUX         PU66  -12         A01X+114111Y+022506X0110Y0240     S1      
327P3V3_AUX         PU68  -13         A01X+170548Y+021915X0780Y1070R090 S1      
327P3V3_AUX         PU69  -13         A01X+124839Y+021915X0780Y1070R090 S1      
327P3V3_AUX         PU68  -12         A01X+170056Y+022506X0110Y0240     S1      
327P3V3_AUX         PU69  -12         A01X+124347Y+022506X0110Y0240     S1      
327P3V3_AUX         J2    -B17        A01X+090330Y+026929X0150Y0530R090 S1      
327P3V3_AUX         R1782 -2          A01X+128950Y+094708X0198Y0197R090 S1      
317P3V3_AUX         VIA   -    MD0100PA00X+128950Y+094950X0200Y         S0      
327P3V3_AUX         U432  -7          A01X+101512Y+094669X0110Y0360R090 S1      
327P3V3_AUX         U432  -8          A01X+101512Y+094472X0110Y0360R090 S1      
327P3V3_AUX         U432  -9          A01X+101512Y+094275X0110Y0360R090 S1      
317P3V3_AUX         VIA   -    MD0100PA00X+100472Y+094882X0200Y         S0      
317P3V3_AUX         VIA   -    MD0100PA00X+101102Y+094882X0200Y         S0      
317P3V3_AUX         VIA   -    MD0100PA00X+100792Y+094882X0200Y         S0      
327P3V3_AUX         C4425 -1          A01X+100762Y+094482X0400Y0500R090 S1      
327P3V3_AUX         R6581 -1          A18X+103037Y+095422X0198Y0197     S2      
327P3V3_AUX         R6577 -1   M      A18X+100772Y+095640X0198Y0197R090 S2      
317P3V3_AUX         VIA   -    MD0100PA00X+100499Y+095537X0200Y         S0      
327P3V3_AUX         R6602 -1          A01X+175412Y+093110X0198Y0197     S1      
317P3V3_AUX         VIA   -    MD0100PA00X+175120Y+093110X0200Y         S0      
317P3V3_AUX         VIA   -    MD0100PA00X+177805Y+091612X0200Y         S0      
327P3V3_AUX         U434  -58         A01X+177805Y+091292X0110Y0340R180 S1      
317P3V3_AUX         VIA   -    MD0100PA00X+177590Y+092455X0200Y         S0      
317P3V3_AUX         VIA   -    MD0100PA00X+177379Y+093066X0200Y         S0      
317P3V3_AUX         VIA   -    MD0100PA00X+177379Y+092766X0200Y         S0      
327P3V3_AUX         C4439 -1          A01X+177839Y+092455X0198Y0197     S1      
327P3V3_AUX         C4441 -1          A01X+177725Y+092925X0280Y0320R270 S1      
327P3V3_AUX         U434  -60         A01X+177411Y+091292X0110Y0340R180 S1      
327P3V3_AUX         U434  -61         A01X+177214Y+091292X0110Y0340R180 S1      
327P3V3_AUX         C2584 -1   M      A18X+147092Y+092350X0198Y0197R180 S2      
327P3V3_AUX         U97   -6          A18X+146583Y+092811X0240Y0440R270 S2      
317P3V3_AUX         VIA   -    MD0100PA00X+147092Y+092058X0200Y         S0      
327P3V3_AUX         R909  -2          A18X+144358Y+092700X0198Y0197R180 S2      
317P3V3_AUX         VIA   -    MD0100PA00X+144602Y+092700X0200Y         S0      
327P3V3_AUX         R2621 -2          A18X+129688Y+091148X0198Y0197     S2      
327P3V3_AUX         R1781 -2          A01X+129800Y+091992X0198Y0197R270 S1      
317P3V3_AUX         VIA   -    MD0100PA00X+129800Y+091700X0200Y         S0      
317P3V3_AUX         VIA   -    MD0100PA00X+175092Y+090206X0200Y         S0      
317P3V3_AUX         VIA   -    MD0100PA00X+174490Y+090016X0200Y         S0      
317P3V3_AUX         VIA   -    MD0100PA00X+174790Y+090016X0200Y         S0      
327P3V3_AUX         U434  -3          A01X+176348Y+090623X0110Y0340R270 S1      
327P3V3_AUX         C4440 -1          A01X+175090Y+090482X0198Y0197R090 S1      
327P3V3_AUX         C4442 -1          A01X+174627Y+090341X0280Y0320     S1      
327P3V3_AUX         PR7181-2          A18X+140795Y+112604X0198Y0197R270 S2      
317P3V3_AUX         VIA   -    MD0100PA00X+140942Y+112924X0200Y         S0      
327P3V3_AUX         PR7179-2          A18X+134608Y+112583X0198Y0197R270 S2      
317P3V3_AUX         VIA   -    MD0100PA00X+134730Y+112833X0200Y         S0      
317P3V3_AUX         VIA   -    MD0100PA00X+135726Y+103427X0200Y         S0      
327P3V3_AUX         PR131 -2          A01X+135969Y+103427X0198Y0197R180 S1      
317P3V3_AUX         VIA   -    MD0100PA00X+136744Y+100376X0200Y         S0      
327P3V3_AUX         PR116 -1          A18X+137038Y+100218X0198Y0197R180 S2      
327P3V3_AUX         U144  -5          A01X+132950Y+094806X0140Y0440R180 S1      
327P3V3_AUX         C2745 -1   M      A01X+133769Y+095172X0198Y0197R270 S1      
327P3V3_AUX         C2572 -1          A18X+153500Y+095192X0198Y0197R270 S2      
327P3V3_AUX         U70   -31         A01X+153673Y+095201X0110Y0540R090 S1      
317P3V3_AUX         VIA   -    MD0100PA00X+152913Y+095298X0200Y    R180 S0      
327P3V3_AUX         U70   -20         A01X+153673Y+093036X0110Y0540R090 S1      
327P3V3_AUX         C2566 -1          A18X+153500Y+093042X0198Y0197R270 S2      
327P3V3_AUX         L4    -1          A18X+152236Y+093424X0280Y0320R090 S2      
317P3V3_AUX         VIA   -    MD0100PA00X+152221Y+093785X0200Y         S0      
317P3V3_AUX         VIA   -    MD0100PA00X+152727Y+093265X0200Y    R180 S0      
327P3V3_AUX         R910  -2          A18X+148027Y+093132X0198Y0197R180 S2      
317P3V3_AUX         VIA   -    MD0100PA00X+148292Y+093132X0200Y         S0      
327P3V3_AUX         R911  -2          A18X+148027Y+093932X0198Y0197R180 S2      
317P3V3_AUX         VIA   -    MD0100PA00X+148332Y+093932X0200Y         S0      
327P3V3_AUX         U70   -56         A01X+149166Y+094020X0110Y0540R090 S1      
327P3V3_AUX         C2565 -1   M      A18X+149350Y+093992X0198Y0197R270 S2      
327P3V3_AUX         C2564 -1          A18X+148850Y+093810X0280Y0320     S2      
317P3V3_AUX         VIA   -    MD0100PA00X+149607Y+094020X0200Y         S0      
327P3V3_AUX         L5    -1          A18X+149706Y+093074X0280Y0320R270 S2      
317P3V3_AUX         VIA   -    MD0100PA00X+149706Y+093400X0200Y         S0      
327P3V3_AUX         C2568 -1          A18X+149050Y+095158X0198Y0197R090 S2      
327P3V3_AUX         U70   -50         A01X+149166Y+095201X0110Y0540R090 S1      
317P3V3_AUX         VIA   -    MD0100PA00X+148724Y+095201X0200Y    R180 S0      
317P3V3_AUX         VIA   -    MD0100PA00X+140988Y+090785X0200Y         S0      
317P3V3_AUX         VIA   -    MD0100PA00X+141738Y+090785X0200Y         S0      
317P3V3_AUX         VIA   -    MD0100PA00X+141488Y+090785X0200Y         S0      
317P3V3_AUX         VIA   -    MD0100PA00X+141238Y+090785X0200Y         S0      
327P3V3_AUX         R2622 -2          A01X+141089Y+091114X0198Y0197     S1      
317P3V3_AUX         VIA   -    MD0100PA00X+141373Y+091114X0200Y         S0      
327P3V3_AUX         R5912 -2          A01X+138835Y+092407X0198Y0197R270 S1      
327P3V3_AUX         R5777 -1          A18X+138630Y+092108X0198Y0197R090 S2      
317P3V3_AUX         VIA   -    MD0100PA00X+138898Y+092108X0200Y         S0      
327P3V3_AUX         R6283 -1          A01X+132250Y+092308X0198Y0197R270 S1      
327P3V3_AUX         R1793 -1          A01X+132650Y+093092X0198Y0197R090 S1      
317P3V3_AUX         VIA   -    MD0100PA00X+132400Y+093092X0200Y         S0      
327P3V3_AUX         R1792 -1          A01X+133600Y+093092X0198Y0197R090 S1      
317P3V3_AUX         VIA   -    MD0100PA00X+133342Y+093092X0200Y         S0      
327P3V3_AUX         R1796 -1          A01X+131700Y+094108X0198Y0197R270 S1      
317P3V3_AUX         VIA   -    MD0100PA00X+131578Y+094374X0200Y         S0      
327P3V3_AUX         R1786 -1          A01X+130495Y+093414X0198Y0197R270 S1      
317P3V3_AUX         VIA   -    MD0100PA00X+130650Y+093650X0200Y         S0      
327P3V3_AUX         R1787 -1          A01X+130910Y+093414X0198Y0197R270 S1      
317P3V3_AUX         VIA   -    MD0100PA00X+130910Y+093656X0200Y         S0      
327P3V3_AUX         U143  -5          A01X+130391Y+094822X0140Y0440R180 S1      
327P3V3_AUX         C2744 -1   M      A01X+130408Y+094250X0198Y0197R180 S1      
317P3V3_AUX         VIA   -    MD0100PA00X+130250Y+093950X0200Y         S0      
327P3V3_AUX         R4102 -2   M      A18X+119322Y+094321X0198Y0197R090 S2      
327P3V3_AUX         R4101 -2          A18X+119722Y+094321X0198Y0197R090 S2      
317P3V3_AUX         VIA   -    MD0100PA00X+119322Y+094070X0200Y         S0      
327P3V3_AUX         R1859 -1          A18X+119115Y+093361X0198Y0197R090 S2      
317P3V3_AUX         VIA   -    MD0100PA00X+119115Y+093630X0200Y    R090 S0      
327P3V3_AUX         C2779 -2   M      A18X+119814Y+095379X0198Y0197     S2      
327P3V3_AUX         U318  -1          A18X+119622Y+095960X0240Y0460R180 S2      
317P3V3_AUX         VIA   -    MD0100PA00X+119635Y+095103X0200Y    R270 S0      
327P3V3_AUX         R1863 -1          A18X+118715Y+092346X0198Y0197R270 S2      
317P3V3_AUX         VIA   -    MD0100PA00X+118715Y+092100X0200Y         S0      
327P3V3_AUX         R1858 -1          A18X+118115Y+093361X0198Y0197R090 S2      
317P3V3_AUX         VIA   -    MD0100PA00X+118200Y+093650X0200Y    R090 S0      
327P3V3_AUX         R5637 -1          A18X+139625Y+085412X0280Y0320R090 S2      
327P3V3_AUX         R5635 -1          A18X+139472Y+088091X0280Y0320R090 S2      
327P3V3_AUX         R5636 -1          A18X+139678Y+090191X0280Y0320R180 S2      
327P3V3_AUX         R4047 -1          A01X+129650Y+096392X0198Y0197R090 S1      
317P3V3_AUX         VIA   -    MD0100PA00X+129650Y+096150X0200Y         S0      
327P3V3_AUX         R1798 -1          A01X+131100Y+096392X0198Y0197R090 S1      
317P3V3_AUX         VIA   -    MD0100PA00X+131100Y+096150X0200Y         S0      
327P3V3_AUX         C2746 -1   M      A01X+131850Y+096192X0198Y0197R090 S1      
327P3V3_AUX         U145  -5          A01X+131800Y+095594X0140Y0440     S1      
317P3V3_AUX         VIA   -    MD0100PA00X+132103Y+096175X0200Y         S0      
327P3V3_AUX         R1785 -1          A01X+130050Y+096708X0198Y0197R270 S1      
317P3V3_AUX         VIA   -    MD0100PA00X+130050Y+097019X0200Y         S0      
327P3V3_AUX         R1784 -1          A01X+130700Y+096708X0198Y0197R270 S1      
317P3V3_AUX         VIA   -    MD0100PA00X+130700Y+097000X0200Y         S0      
327P3V3_AUX         R1791 -1          A01X+132700Y+096708X0198Y0197R270 S1      
317P3V3_AUX         VIA   -    MD0100PA00X+132700Y+096950X0200Y         S0      
327P3V3_AUX         R1790 -1          A01X+133200Y+096708X0198Y0197R270 S1      
317P3V3_AUX         VIA   -    MD0100PA00X+133200Y+096950X0200Y         S0      
327P3V3_AUX         R5893 -1          A18X+140521Y+096118X0198Y0197     S2      
317P3V3_AUX         VIA   -    MD0100PA00X+140521Y+096507X0200Y         S0      
317P3V3_AUX         VIA   -    MD0100PA00X+149708Y+096100X0200Y         S0      
327P3V3_AUX         R931  -2          A18X+149704Y+095838X0198Y0197R180 S2      
327P3V3_AUX         R932  -2          A18X+149708Y+096350X0198Y0197R180 S2      
317P3V3_AUX         VIA   -    MD0100PA00X+151216Y+095754X0200Y    R270 S0      
327P3V3_AUX         C2567 -1          A18X+150904Y+096274X0198Y0197     S2      
327P3V3_AUX         C2563 -1   M      A18X+150904Y+095824X0198Y0197     S2      
327P3V3_AUX         U70   -42         A01X+151124Y+096176X0110Y0540     S1      
317P3V3_AUX         VIA   -    MD0100PA00X+119122Y+096776X0200Y    R270 S0      
327P3V3_AUX         R4100 -2          A18X+118278Y+096867X0198Y0197R090 S2      
317P3V3_AUX         VIA   -    MD0100PA00X+149897Y+097544X0200Y         S0      
327P3V3_AUX         R964  -2          A18X+149672Y+097718X0198Y0197R180 S2      
327P3V3_AUX         R943  -2          A18X+149708Y+096800X0198Y0197R180 S2      
317P3V3_AUX         VIA   -    MD0100PA00X+152558Y+096850X0200Y         S0      
327P3V3_AUX         U102  -5          A18X+152300Y+096144X0140Y0440     S2      
327P3V3_AUX         C2606 -2   M      A18X+152300Y+096792X0198Y0197R090 S2      
317P3V3_AUX         VIA   -    MD0100PA00X+119864Y+098529X0200Y    R270 S0      
327P3V3_AUX         U318  -8          A18X+119622Y+097672X0240Y0460R180 S2      
327P3V3_AUX         C2780 -2   M      A18X+119814Y+098279X0198Y0197     S2      
317P3V3_AUX         VIA   -    MD0100PA00X+119193Y+098731X0200Y    R270 S0      
327P3V3_AUX         R4099 -2          A18X+118922Y+098971X0198Y0197R090 S2      
327P3V3_AUX         R4098 -2   M      A18X+119322Y+098971X0198Y0197R090 S2      
317P3V3_AUX         VIA   -    MD0100PA00X+142874Y+101627X0200Y         S0      
327P3V3_AUX         R839  -1          A01X+142634Y+101627X0198Y0197R180 S1      
317P3V3_AUX         VIA   -    MD0100PA00X+142074Y+101227X0200Y         S0      
327P3V3_AUX         PR132 -2          A01X+141834Y+101227X0198Y0197     S1      
317P3V3_AUX         VIA   -    MD0100PA00X+142074Y+099677X0200Y         S0      
327P3V3_AUX         PR124 -1          A01X+141834Y+099677X0198Y0197R180 S1      
317P3V3_AUX         VIA   -    MD0100PA00X+142874Y+100077X0200Y         S0      
327P3V3_AUX         R833  -1          A01X+142634Y+100077X0198Y0197R180 S1      
317P3V3_AUX         VIA   -    MD0100PA00X+142074Y+100877X0200Y         S0      
327P3V3_AUX         PR134 -1          A01X+141834Y+100877X0198Y0197R180 S1      
327P3V3_AUX         R1762 -1          A01X+141414Y+099231X0198Y0197R180 S1      
317P3V3_AUX         VIA   -    MD0100PA00X+141662Y+099231X0200Y         S0      
317P3V3_AUX         VIA   -    MD0100PA00X+143400Y+098144X0200Y         S0      
327P3V3_AUX         J57   -1          A01X+144167Y+098608X0500Y1350R090 S1      
317P3V3_AUX         VIA   -    MD0100PA00X+128283Y+115009X0200Y         S0      
317P3V3_AUX         VIA   -    MD0100PA00X+128242Y+113713X0200Y         S0      
327P3V3_AUX         R3978 -2          A01X+127992Y+113713X0198Y0197R270 S1      
317P3V3_AUX         VIA   -    MD0100PA00X+127579Y+112409X0200Y         S0      
317P3V3_AUX         VIA   -    MD0100PA00X+126054Y+113473X0200Y         S0      
327P3V3_AUX         R3979 -2          A01X+125992Y+113713X0198Y0197R270 S1      
327P3V3_AUX         R1464 -2          A01X+146585Y+102118X0198Y0197     S1      
317P3V3_AUX         VIA   -    MD0100PA00X+146585Y+102390X0200Y         S0      
317P3V3_AUX         VIA   -    MD0100PA00X+143520Y+102837X0200Y         S0      
327P3V3_AUX         C3657 -1   M      A01X+143798Y+102837X0198Y0197R090 S1      
327P3V3_AUX         U379  -5          A01X+143831Y+102306X0160Y0360     S1      
327P3V3_AUX         C2758 -2   M      A01X+128033Y+115009X0198Y0197R090 S1      
327P3V3_AUX         U315  -8          A01X+127516Y+114684X0240Y0460     S1      
327P3V3_AUX         U429  -8          A01X+145380Y+094597X0140Y0520R270 S1      
327P3V3_AUX         C4189 -2   M      A01X+145654Y+095098X0198Y0197R180 S1      
317P3V3_AUX         VIA   -    MD0100PA00X+144814Y+094944X0200Y         S0      
317P3V3_AUX         VIA   -    MD0100PA00X+133534Y+096173X0200Y         S0      
327P3V3_AUX         C2841 -2   M      A01X+128108Y+091400X0198Y0197     S1      
327P3V3_AUX         U336  -5          A01X+128594Y+091333X0160Y0360     S1      
317P3V3_AUX         VIA   -    MD0100PA00X+128108Y+091108X0200Y         S0      
317P3V3_AUX         VIA   -    MD0100PA00X+180200Y+089245X0200Y         S0      
327P3V3_AUX         U434  -39         A01X+179852Y+089245X0110Y0340R090 S1      
327P3V3_AUX         R1862 -1          A18X+119243Y+088189X0198Y0197R090 S2      
317P3V3_AUX         VIA   -    MD0100PA00X+119215Y+088440X0200Y    R090 S0      
327P3V3_AUX         C2748 -2   M      A18X+117973Y+088890X0198Y0197R180 S2      
327P3V3_AUX         U309  -8          A18X+118531Y+089575X0140Y0520R180 S2      
317P3V3_AUX         VIA   -    MD0100PA00X+117973Y+088620X0200Y    R090 S0      
327P3V3_AUX         R1861 -1          A18X+117743Y+088189X0198Y0197R090 S2      
317P3V3_AUX         VIA   -    MD0100PA00X+117986Y+088346X0200Y    R090 S0      
317P3V3_AUX         VIA   -    MD0100PA00X+178002Y+087440X0200Y         S0      
327P3V3_AUX         U434  -24         A01X+178002Y+087788X0110Y0340     S1      
327P3V3_AUX         U100  -5          A18X+150663Y+087634X0140Y0440R090 S2      
327P3V3_AUX         C2604 -2   M      A18X+150064Y+087634X0198Y0197R180 S2      
317P3V3_AUX         VIA   -    MD0100PA00X+150064Y+087384X0200Y         S0      
327P3V3_AUX         C2503 -2   M      A18X+143989Y+087661X0198Y0197     S2      
327P3V3_AUX         U68   -16         A18X+144014Y+088323X0140Y0610R180 S2      
317P3V3_AUX         VIA   -    MD0100PA00X+143989Y+087382X0200Y         S0      
327P3V3_AUX         R1860 -1          A18X+118743Y+087124X0198Y0197R270 S2      
317P3V3_AUX         VIA   -    MD0100PA00X+118743Y+086834X0200Y         S0      
327P3V3_AUX         U67   -16         A18X+098305Y+088323X0140Y0610R180 S2      
327P3V3_AUX         C2405 -2   M      A18X+098280Y+087661X0198Y0197     S2      
317P3V3_AUX         VIA   -    MD0100PA00X+097989Y+087659X0200Y         S0      
327P3V3_AUX         C2216 -2   M      A18X+006878Y+087661X0198Y0197     S2      
327P3V3_AUX         U65   -16         A18X+006903Y+088323X0140Y0610R180 S2      
317P3V3_AUX         VIA   -    MD0100PA00X+006878Y+087382X0200Y         S0      
327P3V3_AUX         R4622 -2          A01X+151008Y+083600X0198Y0197     S1      
317P3V3_AUX         VIA   -    MD0100PA00X+151053Y+083350X0200Y         S0      
327P3V3_AUX         C3597 -1   M      A01X+148850Y+084242X0198Y0197R090 S1      
327P3V3_AUX         U343  -24         A01X+148202Y+084197X0240Y0540R270 S1      
317P3V3_AUX         VIA   -    MD0100PA00X+149142Y+084242X0200Y         S0      
327P3V3_AUX         R4620 -2          A01X+142942Y+083850X0198Y0197R180 S1      
317P3V3_AUX         VIA   -    MD0100PA00X+142700Y+083850X0200Y    R180 S0      
327P3V3_AUX         R4621 -2          A01X+142942Y+084250X0198Y0197R180 S1      
317P3V3_AUX         VIA   -    MD0100PA00X+142700Y+084250X0200Y    R180 S0      
327P3V3_AUX         U430  -7          A01X+005645Y+083558X0110Y0360R090 S1      
327P3V3_AUX         U430  -8          A01X+005645Y+083361X0110Y0360R090 S1      
327P3V3_AUX         U430  -9          A01X+005645Y+083164X0110Y0360R090 S1      
327P3V3_AUX         R6568 -1          A18X+006056Y+084763X0198Y0197R180 S2      
327P3V3_AUX         R6565 -1   M      A18X+004905Y+084529X0198Y0197R090 S2      
317P3V3_AUX         VIA   -    MD0100PA00X+004605Y+083772X0200Y         S0      
317P3V3_AUX         VIA   -    MD0100PA00X+005235Y+083772X0200Y         S0      
317P3V3_AUX         VIA   -    MD0100PA00X+004925Y+083772X0200Y         S0      
327P3V3_AUX         C4415 -1          A01X+004895Y+083372X0400Y0500R090 S1      
327P3V3_AUX         R6443 -2          A01X+161643Y+082812X0198Y0197R180 S1      
317P3V3_AUX         VIA   -    MD0100PA00X+161312Y+082812X0200Y         S0      
327P3V3_AUX         R4602 -1          A01X+149942Y+082100X0198Y0197     S1      
317P3V3_AUX         VIA   -    MD0100PA00X+149645Y+082100X0200Y         S0      
327P3V3_AUX         R4608 -1          A01X+149942Y+082900X0198Y0197     S1      
317P3V3_AUX         VIA   -    MD0100PA00X+149662Y+082900X0200Y         S0      
327P3V3_AUX         R4604 -1          A01X+142942Y+082650X0198Y0197     S1      
317P3V3_AUX         VIA   -    MD0100PA00X+142700Y+082650X0200Y    R180 S0      
327P3V3_AUX         R4598 -1          A01X+142942Y+083050X0198Y0197     S1      
317P3V3_AUX         VIA   -    MD0100PA00X+142700Y+083050X0200Y    R180 S0      
327P3V3_AUX         R6439 -2          A01X+163138Y+080143X0198Y0197R270 S1      
317P3V3_AUX         VIA   -    MD0100PA00X+162803Y+080143X0200Y         S0      
327P3V3_AUX         R4599 -1          A01X+142942Y+081450X0198Y0197     S1      
317P3V3_AUX         VIA   -    MD0100PA00X+142700Y+081450X0200Y    R180 S0      
327P3V3_AUX         R4605 -1          A01X+142942Y+081050X0198Y0197     S1      
317P3V3_AUX         VIA   -    MD0100PA00X+142700Y+081050X0200Y    R180 S0      
327P3V3_AUX         D24   -1          A01X+104514Y+081226X0460Y0690R090 S1      
317P3V3_AUX         VIA   -    MD0100PA00X+103925Y+081234X0200Y         S0      
317P3V3_AUX         VIA   -    MD0100PA00X+159133Y+150198X0200Y         S0      
317P3V3_AUX         VIA   -    MD0100PA00X+159192Y+151208X0200Y         S0      
317P3V3_AUX         VIA   -    MD0100PA00X+159178Y+147309X0200Y         S0      
317P3V3_AUX         VIA   -    MD0100PA00X+160850Y+151500X0200Y         S0      
327P3V3_AUX         R6282 -1          A01X+160500Y+151208X0198Y0197R270 S1      
327P3V3_AUX         R6272 -2   M      A01X+160850Y+151208X0198Y0197R090 S1      
327P3V3_AUX         U422  -1          A01X+159431Y+147919X0240Y0460R180 S1      
327P3V3_AUX         C3996 -2   M      A01X+159426Y+147309X0198Y0197R090 S1      
327P3V3_AUX         R6281 -1          A01X+159450Y+151208X0198Y0197R270 S1      
327P3V3_AUX         U422  -8          A01X+159431Y+149632X0240Y0460R180 S1      
327P3V3_AUX         C3997 -2   M      A01X+159431Y+150198X0198Y0197R270 S1      
327P3V3_AUX         R6678 -2          A01X+159386Y+144649X0198Y0197     S1      
317P3V3_AUX         VIA   -    MD0100PA00X+159684Y+144649X0200Y         S0      
327P3V3_AUX         R6681 -1          A01X+160244Y+146802X0198Y0197R180 S1      
317P3V3_AUX         VIA   -    MD0100PA00X+160543Y+146802X0200Y         S0      
317P3V3_AUX         VIA   -    MD0100PA00X+098714Y+140164X0200Y         S0      
327P3V3_AUX         C2849 -1          A01X+101470Y+084316X0400Y0500R180 S1      
327P3V3_AUX         U342  -9          A01X+100744Y+084423X0110Y0360R270 S1      
327P3V3_AUX         U342  -8          A01X+100744Y+084226X0110Y0360R270 S1      
327P3V3_AUX         U342  -7          A01X+100744Y+084029X0110Y0360R270 S1      
327P3V3_AUX         R2520 -1          A01X+101828Y+083766X0198Y0197R180 S1      
327P3V3_AUX         R4433 -1          A01X+098163Y+082916X0198Y0197     S1      
317P3V3_AUX         VIA   -    MD0100PA00X+102070Y+083766X0200Y         S0      
317P3V3_AUX         VIA   -    MD0100PA00X+101098Y+084174X0200Y         S0      
317P3V3_AUX         VIA   -    MD0100PA00X+101114Y+084434X0200Y         S0      
317P3V3_AUX         VIA   -    MD0100PA00X+097920Y+082916X0200Y         S0      
327P3V3_AUX         J69   -21         A01X+097251Y+140512X0240Y0950R270 S1      
317P3V3_AUX         VIA   -    MD0100PA00X+098414Y+140164X0200Y         S0      
327P3V3_AUX         R6653 -1          A01X+101091Y+138080X0198Y0197     S1      
327P3V3_AUX         R6652 -1          A01X+103586Y+135737X0198Y0197     S1      
317P3V3_AUX         VIA   -    MD0100PA00X+100839Y+138080X0200Y         S0      
327P3V3_AUX         R6691 -1          A01X+177823Y+144053X0198Y0197R090 S1      
317P3V3_AUX         VIA   -    MD0100PA00X+177823Y+143810X0200Y         S0      
317P3V3_AUX         VIA   -    MD0100PA00X+180934Y+147673X0200Y         S0      
327P3V3_AUX         R6684 -2          A01X+180297Y+147673X0198Y0197     S1      
317P3V3_AUX         VIA   -    MD0100PA00X+180643Y+144454X0200Y         S0      
327P3V3_AUX         R6690 -2          A01X+180310Y+144454X0198Y0197     S1      
327P3V3_AUX         R4871 -1          A18X+083979Y+089150X0198Y0197R180 S2      
327P3V3_AUX         R4113 -1          A18X+083988Y+088346X0198Y0197R180 S2      
327P3V3_AUX         R4881 -2          A01X+083988Y+088346X0198Y0197R180 S1      
327P3V3_AUX         R6689 -2          A01X+180388Y+143756X0198Y0197R270 S1      
317P3V3_AUX         VIA   -    MD0100PA00X+180388Y+143505X0200Y         S0      
317P3V3_AUX         VIA   -    MD0100PA00X+180376Y+146724X0200Y         S0      
327P3V3_AUX         R6683 -2          A01X+180376Y+146976X0198Y0197R270 S1      
317P3V3_AUX         VIA   -    MD0100PA00X+177810Y+147029X0200Y         S0      
327P3V3_AUX         R6685 -1          A01X+177810Y+147272X0198Y0197R090 S1      
317P3V3_AUX         VIA   -    MD0100PA00X+160033Y+144050X0200Y         S0      
327P3V3_AUX         R6677 -2          A01X+160033Y+144341X0198Y0197R270 S1      
327P3V3_AUX         R3934 -2          A01X+080284Y+113713X0198Y0197R270 S1      
317P3V3_AUX         VIA   -    MD0100PA00X+080345Y+113473X0200Y         S0      
327P3V3_AUX         R3933 -2          A01X+082284Y+113713X0198Y0197R270 S1      
317P3V3_AUX         VIA   -    MD0100PA00X+082534Y+113713X0200Y         S0      
317P3V3_AUX         VIA   -    MD0100PA00X+101399Y+136084X0200Y         S0      
327P3V3_AUX         C3869 -1   M      A01X+081415Y+138076X0198Y0197R270 S1      
327P3V3_AUX         U415  -5          A01X+081380Y+138786X0220Y0530R180 S1      
317P3V3_AUX         VIA   -    MD0100PA00X+081665Y+138076X0200Y    R270 S0      
327P3V3_AUX         U433  -7          A01X+178976Y+097752X0110Y0360R090 S1      
327P3V3_AUX         U433  -8          A01X+178976Y+097556X0110Y0360R090 S1      
327P3V3_AUX         U433  -9          A01X+178976Y+097359X0110Y0360R090 S1      
327P3V3_AUX         C4430 -1          A01X+178226Y+097566X0400Y0500R090 S1      
317P3V3_AUX         VIA   -    MD0100PA00X+177936Y+097966X0200Y         S0      
317P3V3_AUX         VIA   -    MD0100PA00X+178566Y+097966X0200Y         S0      
317P3V3_AUX         VIA   -    MD0100PA00X+178256Y+097966X0200Y         S0      
327P3V3_AUX         L148  -1          A18X+094280Y+087807X0280Y0320R180 S2      
317P3V3_AUX         VIA   -    MD0100PA00X+173992Y+115009X0200Y         S0      
327P3V3_AUX         C2760 -2   M      A01X+173742Y+115009X0198Y0197R090 S1      
327P3V3_AUX         U316  -8          A01X+173224Y+114684X0240Y0460     S1      
327P3V3_AUX         R6412 -2          A01X+085365Y+083147X0198Y0197R180 S1      
317P3V3_AUX         VIA   -    MD0100PA00X+085050Y+083147X0200Y         S0      
327P3V3_AUX         R5523 -1          A01X+083827Y+082746X0198Y0197     S1      
327P3V3_AUX         R6414 -2          A18X+084069Y+084753X0198Y0197     S2      
327P3V3_AUX         R1536 -2          A01X+083242Y+096227X0198Y0197R090 S1      
317P3V3_AUX         VIA   -    MD0100PA00X+084014Y+083090X0200Y         S0      
327P3V3_AUX         R6413 -2          A01X+084271Y+083156X0198Y0197R180 S1      
327P3V3_AUX         R3998 -2          A01X+171701Y+113713X0198Y0197R270 S1      
317P3V3_AUX         VIA   -    MD0100PA00X+171763Y+113473X0200Y         S0      
317P3V3_AUX         VIA   -    MD0100PA00X+183092Y+110915X0200Y         S0      
327P3V3_AUX         R1746 -1          A01X+182827Y+110915X0198Y0197R270 S1      
317P3V3_AUX         VIA   -    MD0100PA00X+181676Y+109714X0200Y         S0      
327P3V3_AUX         R801  -1          A01X+181916Y+109714X0198Y0197     S1      
317P3V3_AUX         VIA   -    MD0100PA00X+180081Y+110325X0200Y         S0      
327P3V3_AUX         U95   -9          A01X+180184Y+109711X0090Y0240R090 S1      
327P3V3_AUX         C631  -1   M      A01X+179841Y+110325X0198Y0197R180 S1      
327P3V3_AUX         R802  -2          A01X+182231Y+107714X0198Y0197     S1      
317P3V3_AUX         VIA   -    MD0100PA00X+182495Y+107714X0200Y         S0      
327P3V3_AUX         R803  -2          A01X+182231Y+108514X0198Y0197     S1      
317P3V3_AUX         VIA   -    MD0100PA00X+182471Y+108514X0200Y         S0      
327P3V3_AUX         C628  -1   M      A01X+095443Y+110276X0198Y0197R180 S1      
317P3V3_AUX         VIA   -    MD0100PA00X+095683Y+110276X0200Y         S0      
327P3V3_AUX         R790  -1          A01X+097518Y+109666X0198Y0197     S1      
317P3V3_AUX         VIA   -    MD0100PA00X+097278Y+109666X0200Y         S0      
327P3V3_AUX         U94   -9          A01X+095786Y+109662X0090Y0240R090 S1      
327P3V3_AUX         R779  -1          A01X+091120Y+109666X0198Y0197     S1      
317P3V3_AUX         VIA   -    MD0100PA00X+090880Y+109666X0200Y         S0      
317P3V3_AUX         VIA   -    MD0100PA00X+089286Y+110276X0200Y         S0      
327P3V3_AUX         C826  -1   M      A01X+089046Y+110276X0198Y0197R180 S1      
327P3V3_AUX         U90   -9          A01X+089388Y+109662X0090Y0240R090 S1      
317P3V3_AUX         VIA   -    MD0100PA00X+098073Y+108466X0200Y         S0      
327P3V3_AUX         R791  -2          A01X+097833Y+108466X0198Y0197     S1      
317P3V3_AUX         VIA   -    MD0100PA00X+098097Y+107666X0200Y         S0      
327P3V3_AUX         R793  -2          A01X+097833Y+107666X0198Y0197     S1      
317P3V3_AUX         VIA   -    MD0100PA00X+091699Y+107666X0200Y         S0      
327P3V3_AUX         R780  -2          A01X+091435Y+107666X0198Y0197     S1      
317P3V3_AUX         VIA   -    MD0100PA00X+091675Y+108466X0200Y         S0      
327P3V3_AUX         R782  -2          A01X+091435Y+108466X0198Y0197     S1      
327P3V3_AUX         R1537 -2   M      A01X+083642Y+096227X0198Y0197R090 S1      
317P3V3_AUX         VIA   -    MD0100PA00X+083642Y+096467X0200Y    R090 S0      
327P3V3_AUX         C2707 -2   M      A01X+082842Y+095912X0198Y0197R270 S1      
327P3V3_AUX         U123  -8          A01X+083083Y+095290X0240Y0460R180 S1      
317P3V3_AUX         VIA   -    MD0100PA00X+082567Y+096467X0200Y    R090 S0      
327P3V3_AUX         R5916 -1          A01X+081540Y+089342X0198Y0197R180 S1      
327P3V3_AUX         R5918 -2          A01X+080875Y+083692X0198Y0197R180 S1      
317P3V3_AUX         VIA   -    MD0100PA00X+090027Y+087994X0180Y         S0      
317P3V3_AUX         VIA   -    MD0100PA00X+173951Y+113713X0200Y         S0      
327P3V3_AUX         R3997 -2          A01X+173701Y+113713X0198Y0197R270 S1      
317P3V3_AUX         VIA   -    MD0100PA00X+178016Y+095610X0200Y         S0      
317P3V3_AUX         VIA   -    MD0100PA00X+178296Y+095610X0200Y         S0      
317P3V3_AUX         VIA   -    MD0100PA00X+178296Y+095330X0200Y         S0      
317P3V3_AUX         VIA   -    MD0100PA00X+178576Y+095330X0200Y         S0      
317P3V3_AUX         VIA   -    MD0100PA00X+178576Y+095610X0200Y         S0      
317P3V3_AUX         VIA   -    MD0100PA00X+178016Y+095330X0200Y         S0      
317P3V3_AUX         VIA   -    MD0100PA00X+181002Y+129874X0200Y         S0      
317P3V3_AUX         VIA   -    MD0100PA00X+181282Y+129874X0200Y         S0      
317P3V3_AUX         VIA   -    MD0100PA00X+181562Y+129594X0200Y         S0      
317P3V3_AUX         VIA   -    MD0100PA00X+181562Y+129874X0200Y         S0      
317P3V3_AUX         VIA   -    MD0100PA00X+181282Y+129594X0200Y         S0      
317P3V3_AUX         VIA   -    MD0100PA00X+181002Y+129594X0200Y         S0      
327P3V3_AUX         C2010 -1          A18X+087399Y+083304X0280Y0320R090 S2      
327P3V3_AUX         C2011 -1          A18X+087399Y+082756X0280Y0320R090 S2      
327P3V3_AUX         C2012 -1          A18X+087399Y+082218X0280Y0320R090 S2      
327P3V3_AUX         L147  -1          A18X+093944Y+081949X0280Y0320     S2      
317P3V3_AUX         VIA   -    MD0100PA00X+095367Y+099156X0200Y         S0      
327P3V3_AUX         R6220 -1          A01X+095367Y+098882X0198Y0197R270 S1      
317P3V3_AUX         VIA   -    MD0100PA00X+098375Y+107868X0200Y         S0      
317P3V3_AUX         VIA   -    MD0100PA00X+098491Y+108107X0200Y         S0      
317P3V3_AUX         VIA   -    MD0100PA00X+096167Y+099156X0200Y         S0      
327P3V3_AUX         R6226 -1   M      A01X+096167Y+098882X0198Y0197R270 S1      
317P3V3_AUX         VIA   -    MD0100PA00X+096567Y+099156X0200Y         S0      
327P3V3_AUX         R6219 -1   M      A01X+096567Y+098882X0198Y0197R270 S1      
317P3V3_AUX         VIA   -    MD0100PA00X+100876Y+102390X0200Y         S0      
317P3V3_AUX         VIA   -    MD0100PA00X+100622Y+098034X0200Y         S0      
327P3V3_AUX         R1397 -2          A01X+100876Y+102118X0198Y0197     S1      
317P3V3_AUX         VIA   -    MD0100PA00X+081301Y+081973X0200Y         S0      
317P3V3_AUX         VIA   -    MD0100PA00X+081715Y+089638X0200Y    R270 S0      
327P3V3_AUX         R5474 -2          A01X+081963Y+089570X0198Y0197R090 S1      
317P3V3_AUX         VIA   -    MD0100PA00X+082607Y+089301X0200Y    R270 S0      
327P3V3_AUX         U302  -5          A01X+082680Y+088717X0160Y0360     S1      
327P3V3_AUX         C2569 -2   M      A01X+082864Y+089301X0198Y0197R270 S1      
317P3V3_AUX         VIA   -    MD0100PA00X+082323Y+087083X0200Y    R270 S0      
327P3V3_AUX         C3644 -2   M      A01X+082003Y+087083X0198Y0197R090 S1      
327P3V3_AUX         U356  -5          A01X+081992Y+087686X0160Y0360R180 S1      
317P3V3_AUX         VIA   -    MD0100PA00X+082621Y+086605X0200Y    R270 S0      
327P3V3_AUX         R2740 -2          A01X+082888Y+086729X0198Y0197R270 S1      
317P3V3_AUX         VIA   -    MD0100PA00X+082572Y+083982X0200Y    R270 S0      
327P3V3_AUX         C2570 -2   M      A01X+082283Y+083982X0198Y0197R090 S1      
327P3V3_AUX         U88   -8          A01X+081998Y+084857X0110Y0280R180 S1      
327P3V3_AUX         R5532 -1          A01X+083311Y+082664X0198Y0197R090 S1      
317P3V3_AUX         VIA   -    MD0100PA00X+083819Y+084346X0200Y         S0      
327P3V3_AUX         R5530 -1   M      A18X+084069Y+084349X0198Y0197R180 S2      
317P3V3_AUX         VIA   -    MD0100PA00X+083563Y+084363X0200Y    R270 S0      
327P3V3_AUX         U89   -8          A01X+083207Y+084865X0110Y0280R180 S1      
317P3V3_AUX         VIA   -    MD0100PA00X+084283Y+089544X0200Y         S0      
327P3V3_AUX         R6214 -2          A01X+084200Y+089842X0198Y0197R270 S1      
317P3V3_AUX         VIA   -    MD0100PA00X+083729Y+088749X0200Y         S0      
327P3V3_AUX         R4872 -1   M      A18X+083979Y+088749X0198Y0197R180 S2      
317P3V3_AUX         VIA   -    MD0100PA00X+084023Y+087546X0200Y         S0      
317P3V3_AUX         VIA   -    MD0100PA00X+083740Y+087146X0200Y         S0      
327P3V3_AUX         R4886 -2          A01X+084019Y+087146X0198Y0197R180 S1      
327P3V3_AUX         R4883 -2   M      A18X+084021Y+087146X0198Y0197     S2      
317P3V3_AUX         VIA   -    MD0100PA00X+083738Y+087953X0200Y         S0      
327P3V3_AUX         R4114 -1          A18X+083988Y+087946X0198Y0197R180 S2      
327P3V3_AUX         R4882 -2   M      A01X+083988Y+087946X0198Y0197R180 S1      
317P3V3_AUX         VIA   -    MD0100PA00X+085663Y+091804X0200Y         S0      
327P3V3_AUX         R4552 -2          A01X+085263Y+091266X0198Y0197R090 S1      
317P3V3_AUX         VIA   -    MD0100PA00X+086425Y+091804X0200Y         S0      
327P3V3_AUX         R4550 -2          A01X+086063Y+091266X0198Y0197R090 S1      
317P3V3_AUX         VIA   -    MD0100PA00X+087663Y+091524X0200Y         S0      
327P3V3_AUX         R4545 -2          A01X+087663Y+091266X0198Y0197R090 S1      
317P3V3_AUX         VIA   -    MD0100PA00X+087263Y+091804X0200Y         S0      
327P3V3_AUX         R4546 -2          A01X+086863Y+091266X0198Y0197R090 S1      
317P3V3_AUX         VIA   -    MD0100PA00X+087648Y+083037X0200Y         S0      
317P3V3_AUX         VIA   -    MD0100PA00X+087782Y+082421X0200Y         S0      
317P3V3_AUX         VIA   -    MD0100PA00X+087741Y+082802X0200Y         S0      
317P3V3_AUX         VIA   -    MD0100PA00X+088463Y+091524X0200Y         S0      
327P3V3_AUX         R4544 -2          A01X+088463Y+091266X0198Y0197R090 S1      
317P3V3_AUX         VIA   -    MD0100PA00X+090376Y+095136X0200Y         S0      
327P3V3_AUX         U418  -5          A01X+089607Y+094838X0220Y0530R270 S1      
327P3V3_AUX         R6257 -1          A01X+090613Y+095602X0198Y0197R090 S1      
327P3V3_AUX         C3988 -1   M      A01X+090376Y+094861X0198Y0197     S1      
317P3V3_AUX         VIA   -    MD0100PA00X+090063Y+091804X0200Y         S0      
327P3V3_AUX         R4551 -2          A18X+089929Y+091191X0198Y0197R270 S2      
317P3V3_AUX         VIA   -    MD0100PA00X+090392Y+081081X0200Y    R090 S0      
327P3V3_AUX         R1506 -2          A01X+090392Y+081346X0198Y0197R270 S1      
317P3V3_AUX         VIA   -    MD0100PA00X+093576Y+087832X0200Y         S0      
317P3V3_AUX         VIA   -    MD0100PA00X+093277Y+087823X0200Y         S0      
317P3V3_AUX         VIA   -    MD0100PA00X+094574Y+081940X0200Y         S0      
317P3V3_AUX         VIA   -    MD0100PA00X+094286Y+081943X0200Y         S0      
317P3V3_AUX         VIA   -    MD0100PA00X+093192Y+081702X0200Y    R090 S0      
327P3V3_AUX         R3286 -2          A01X+093192Y+081462X0198Y0197R090 S1      
317P3V3_AUX         VIA   -    MD0100PA00X+095457Y+092765X0200Y    R270 S0      
327P3V3_AUX         R6225 -1          A01X+095457Y+093024X0198Y0197R090 S1      
317P3V3_AUX         VIA   -    MD0100PA00X+096010Y+084666X0200Y         S0      
327P3V3_AUX         R474  -1          A01X+095763Y+084666X0198Y0197R180 S1      
317P3V3_AUX         VIA   -    MD0100PA00X+096851Y+093762X0200Y    R270 S0      
327P3V3_AUX         U419  -24         A01X+096275Y+094442X0240Y0540R180 S1      
327P3V3_AUX         C3989 -1   M      A01X+096675Y+093337X0198Y0197R270 S1      
317P3V3_AUX         VIA   -    MD0100PA00X+098750Y+081257X0200Y         S0      
327P3V3_AUX         U294  -14         A01X+099070Y+080630X0140Y0590     S1      
327P3V3_AUX         C2494 -1   M      A01X+099005Y+081377X0198Y0197R090 S1      
317P3V3_AUX         VIA   -    MD0100PA00X+099341Y+132705X0200Y         S0      
317P3V3_AUX         VIA   -    MD0100PA00X+099341Y+132425X0200Y         S0      
317P3V3_AUX         VIA   -    MD0100PA00X+099061Y+132705X0200Y         S0      
317P3V3_AUX         VIA   -    MD0100PA00X+099061Y+132425X0200Y         S0      
317P3V3_AUX         VIA   -    MD0100PA00X+099621Y+132705X0200Y         S0      
317P3V3_AUX         VIA   -    MD0100PA00X+099621Y+132425X0200Y         S0      
317P3V3_AUX         VIA   -    MD0100PA00X+100270Y+081948X0200Y         S0      
327P3V3_AUX         R5067 -1          A01X+100670Y+081698X0198Y0197R270 S1      
327P3V3_AUX         R5068 -1   M      A01X+100270Y+081698X0198Y0197R270 S1      
317P3V3_AUX         VIA   -    MD0100PA00X+102190Y+081897X0200Y    R270 S0      
327P3V3_AUX         R2620 -2          A01X+101947Y+081897X0198Y0197     S1      
327P3V3_AUX         C2009 -1          A18X+089239Y+085632X0164Y0164R180 S2      
327P3V3_AUX         C3624 -1          A18X+089239Y+086891X0164Y0164R180 S2      
327P3V3_AUX         C2025 -1          A18X+089869Y+087521X0164Y0164R090 S2      
327P3V3_AUX         C3622 -1          A18X+090814Y+087521X0164Y0164R090 S2      
327P3V3_AUX         C2006 -1          A18X+092074Y+085946X0164Y0164R270 S2      
327P3V3_AUX         U5    -E10        A01X+089869Y+085002X0160Y    R180 S1      
327P3V3_AUX         U5    -E9         A01X+090184Y+085002X0160Y    R180 S1      
327P3V3_AUX         U5    -E8         A01X+090499Y+085002X0160Y    R180 S1      
327P3V3_AUX         U5    -L5         A01X+091444Y+086891X0160Y    R180 S1      
327P3V3_AUX         U5    -H4         A01X+091759Y+085946X0160Y    R180 S1      
327P3V3_AUX         U5    -G4         A01X+091759Y+085632X0160Y    R180 S1      
327P3V3_AUX         U5    -N10        A01X+089869Y+087521X0160Y    R180 S1      
327P3V3_AUX         U5    -N7         A01X+090814Y+087521X0160Y    R180 S1      
327P3V3_AUX         U5    -L13        A01X+088924Y+086891X0160Y    R180 S1      
327P3V3_AUX         U5    -L12        A01X+089239Y+086891X0160Y    R180 S1      
327P3V3_AUX         U5    -K13        A01X+088924Y+086576X0160Y    R180 S1      
327P3V3_AUX         U5    -G13        A01X+088924Y+085632X0160Y    R180 S1      
327P3V3_AUX         U5    -G12        A01X+089239Y+085632X0160Y    R180 S1      
327P3V3_AUX         U5    -F13        A01X+088924Y+085317X0160Y    R180 S1      
317P3V3_AUX         VIA   -    MD0100PA00X+089712Y+084844X0180Y    R270 S0      
317P3V3_AUX         VIA   -    MD0100PA00X+090027Y+084844X0180Y    R270 S0      
317P3V3_AUX         VIA   -    MD0100PA00X+090656Y+084844X0180Y    R270 S0      
317P3V3_AUX         VIA   -    MD0100PA00X+091601Y+087049X0180Y    R270 S0      
317P3V3_AUX         VIA   -    MD0100PA00X+091916Y+085789X0180Y    R270 S0      
317P3V3_AUX         VIA   -    MD0100PA00X+091916Y+085474X0180Y    R270 S0      
317P3V3_AUX         VIA   -    MD0100PA00X+089712Y+087679X0180Y    R270 S0      
317P3V3_AUX         VIA   -    MD0100PA00X+090971Y+087679X0180Y    R270 S0      
317P3V3_AUX         VIA   -    MD0100PA00X+088767Y+087049X0180Y    R270 S0      
317P3V3_AUX         VIA   -    MD0100PA00X+089082Y+087049X0180Y    R270 S0      
317P3V3_AUX         VIA   -    MD0100PA00X+088767Y+086734X0180Y    R270 S0      
317P3V3_AUX         VIA   -    MD0100PA00X+088767Y+085474X0180Y    R270 S0      
317P3V3_AUX         VIA   -    MD0100PA00X+089082Y+085474X0180Y    R270 S0      
317P3V3_AUX         VIA   -    MD0100PA00X+088767Y+085159X0180Y    R270 S0      
327P3V3_AUX         R5601 -2          A01X+177242Y+163788X0198Y0197R090 S1      
317P3V3_AUX         VIA   -    MD0100PA00X+177242Y+164030X0200Y    R180 S0      
327P3V3_AUX         R5600 -2          A01X+176842Y+163788X0198Y0197R090 S1      
317P3V3_AUX         VIA   -    MD0100PA00X+176842Y+164030X0200Y    R180 S0      
327P3V3_AUX         R5599 -2          A01X+176042Y+163788X0198Y0197R090 S1      
317P3V3_AUX         VIA   -    MD0100PA00X+176042Y+164030X0200Y    R180 S0      
317P3V3_AUX         VIA   -    MD0100PA00X+175068Y+162165X0200Y    R180 S0      
327P3V3_AUX         U329  -8          A01X+175882Y+162522X0240Y0520     S1      
327P3V3_AUX         C3653 -1   M      A01X+175322Y+162165X0198Y0197R270 S1      
327P3V3_AUX         R457  -2          A18X+091287Y+083286X0280Y0320R270 S2      
327P3V3_AUX         R6151 -2          A18X+091435Y+081798X0198Y0197     S2      
327P3V3_AUX         R6152 -2          A18X+091425Y+082208X0198Y0197     S2      
317P3V3_AUX         VIA   -    MD0100PA00X+090978Y+081078X0200Y    R090 S0      
327P3V3_AUX         R1507 -2          A01X+090942Y+081346X0198Y0197R270 S1      
327P3V3_AUX         R5513 -1          A01X+091142Y+080332X0198Y0197R090 S1      
327P3V3_AUX         R5525 -1   M      A18X+090942Y+081346X0198Y0197R270 S2      
317P3V3_AUX         VIA   -    MD0100PA00X+092235Y+080081X0200Y    R090 S0      
327P3V3_AUX         R5534 -1          A01X+092379Y+080332X0198Y0197R090 S1      
317P3V3_AUX         VIA   -    MD0100PA00X+079963Y+102544X0200Y         S0      
327P3V3_AUX         R6360 -1          A18X+079963Y+102249X0198Y0197R090 S2      
327P3V3_AUX         U314  -8          A01X+081807Y+114684X0240Y0460     S1      
327P3V3_AUX         C2756 -2   M      A01X+082324Y+115009X0198Y0197R090 S1      
317P3V3_AUX         VIA   -    MD0100PA00X+082574Y+115009X0200Y         S0      
317P3V3_AUX         VIA   -    MD0100PA00X+073282Y+160410X0200Y    R090 S0      
327P3V3_AUX         R4416 -2          A01X+073282Y+160660X0198Y0197R180 S1      
317P3V3_AUX         VIA   -    MD0100PA00X+073789Y+160234X0200Y    R090 S0      
327P3V3_AUX         R4417 -2          A01X+073539Y+160234X0198Y0197R090 S1      
317P3V3_AUX         VIA   -    MD0100PA00X+074170Y+162202X0200Y    R090 S0      
327P3V3_AUX         R4420 -2          A01X+073930Y+162202X0198Y0197     S1      
327P3V3_AUX         C2846 -1   M      A01X+075945Y+161377X0198Y0197R090 S1      
317P3V3_AUX         VIA   -    MD0100PA00X+075636Y+161377X0200Y    R090 S0      
327P3V3_AUX         U340  -5          A01X+075980Y+160466X0220Y0530     S1      
317P3V3_AUX         VIA   -    MD0100PA00X+076267Y+161937X0200Y    R090 S0      
327P3V3_AUX         R499  -1          A01X+076345Y+161692X0198Y0197R270 S1      
327P3V3_AUX         R6583 -1   M      A18X+179255Y+098959X0198Y0197     S2      
327P3V3_AUX         R6587 -1          A18X+180501Y+098506X0198Y0197     S2      
327P3V3_AUX         R4887 -2          A18X+084016Y+086341X0198Y0197     S2      
327P3V3_AUX         R4888 -2   M      A18X+084016Y+086741X0198Y0197     S2      
317P3V3_AUX         VIA   -    MD0100PA00X+102336Y+136392X0200Y         S0      
327P3V3_AUX         PR7158-2          A18X+109186Y+153346X0198Y0197R180 S2      
317P3V3_AUX         VIA   -    MD0100PA00X+109525Y+153160X0200Y         S0      
327P3V3_AUX         PU6601-1          A01X+109166Y+152165X0170Y0590     S1      
327P3V3_AUX         PC6604-1   M      A01X+108611Y+152658X0198Y0197R270 S1      
317P3V3_AUX         VIA   -    MD0100PA00X+108328Y+152658X0200Y    R270 S0      
327P3V3_AUX         PR7159-2          A18X+109822Y+151340X0198Y0197     S2      
317P3V3_AUX         VIA   -    MD0100PA00X+109508Y+151340X0200Y         S0      
327P3V3_AUX         R1810 -1          A01X+108547Y+163185X0198Y0197R090 S1      
317P3V3_AUX         VIA   -    MD0100PA00X+108547Y+162903X0200Y    R090 S0      
327P3V3_AUX         R1814 -1          A01X+109347Y+163500X0198Y0197R270 S1      
317P3V3_AUX         VIA   -    MD0100PA00X+109347Y+163821X0200Y    R090 S0      
317P3V3_AUX         VIA   -    MD0100PA00X+110147Y+163782X0200Y    R090 S0      
327P3V3_AUX         R1809 -1          A01X+110147Y+163500X0198Y0197R270 S1      
317P3V3_AUX         VIA   -    MD0100PA00X+109090Y+159905X0200Y    R090 S0      
327P3V3_AUX         R1811 -1          A01X+109090Y+159636X0198Y0197R270 S1      
317P3V3_AUX         VIA   -    MD0100PA00X+110423Y+158798X0200Y    R090 S0      
327P3V3_AUX         R1806 -1          A01X+110423Y+158558X0198Y0197R270 S1      
317P3V3_AUX         VIA   -    MD0100PA00X+109850Y+159044X0200Y    R090 S0      
327P3V3_AUX         R1812 -1          A01X+109890Y+159321X0198Y0197R090 S1      
317P3V3_AUX         VIA   -    MD0100PA00X+109368Y+158243X0200Y    R090 S0      
327P3V3_AUX         U146  -5          A01X+109626Y+157481X0140Y0440     S1      
327P3V3_AUX         C2704 -2   M      A01X+109623Y+158243X0198Y0197R270 S1      
317P3V3_AUX         VIA   -    MD0100PA00X+108647Y+158844X0200Y    R090 S0      
327P3V3_AUX         R1805 -1          A01X+108647Y+158556X0198Y0197R270 S1      
327P3V3_AUX         C2747 -1   M      A01X+110461Y+160360X0198Y0197R090 S1      
327P3V3_AUX         U308  -8          A01X+109885Y+160695X0140Y0520R180 S1      
317P3V3_AUX         VIA   -    MD0100PA00X+110762Y+160360X0200Y         S0      
317P3V3_AUX         VIA   -    MD0100PA00X+108218Y+160060X0200Y    R090 S0      
327P3V3_AUX         R1813 -1          A01X+108374Y+160362X0198Y0197R090 S1      
317P3V3_AUX         VIA   -    MD0100PA00X+109088Y+155418X0200Y    R090 S0      
327P3V3_AUX         R1803 -1          A01X+109338Y+155418X0198Y0197R090 S1      
317P3V3_AUX         VIA   -    MD0100PA00X+110088Y+155418X0200Y    R090 S0      
327P3V3_AUX         R1804 -1          A01X+109838Y+155418X0198Y0197R090 S1      
327P3V3_AUX         R5475 -2          A18X+088792Y+080332X0198Y0197R090 S2      
327P3V3_AUX         R5280 -1          A01X+088792Y+080332X0198Y0197R090 S1      
317P3V3_AUX         VIA   -    MD0100PA00X+088792Y+080082X0200Y    R090 S0      
327P3V3_AUX         R5536 -1          A01X+087592Y+080332X0198Y0197R090 S1      
327P3V3_AUX         R5527 -1          A18X+087592Y+080332X0198Y0197R270 S2      
317P3V3_AUX         VIA   -    MD0100PA00X+087492Y+080075X0200Y    R090 S0      
327P3V3_AUX         R6433 -2          A01X+163258Y+078733X0198Y0197R270 S1      
317P3V3_AUX         VIA   -    MD0100PA00X+162993Y+078733X0200Y         S0      
327P3V3_AUX         R4684 -2          A01X+151008Y+079200X0198Y0197     S1      
317P3V3_AUX         VIA   -    MD0100PA00X+150450Y+079684X0200Y         S0      
327P3V3_AUX         C3600 -1   M      A01X+148850Y+079842X0198Y0197R090 S1      
327P3V3_AUX         U345  -24         A01X+148202Y+079797X0240Y0540R270 S1      
317P3V3_AUX         VIA   -    MD0100PA00X+149142Y+079842X0200Y         S0      
327P3V3_AUX         R4671 -1          A01X+149942Y+078500X0198Y0197     S1      
317P3V3_AUX         VIA   -    MD0100PA00X+149676Y+078500X0200Y         S0      
327P3V3_AUX         R4682 -2   M      A01X+142942Y+079450X0198Y0197R180 S1      
327P3V3_AUX         R4683 -2          A01X+142942Y+079850X0198Y0197R180 S1      
317P3V3_AUX         VIA   -    MD0100PA00X+142700Y+079450X0200Y    R180 S0      
327P3V3_AUX         U64   -5          A18X+116091Y+078287X0240Y0420     S2      
327P3V3_AUX         C2110 -2   M      A18X+115559Y+078843X0198Y0197R180 S2      
317P3V3_AUX         VIA   -    MD0100PA00X+115465Y+079106X0200Y         S0      
327P3V3_AUX         R4859 -1   M      A01X+095276Y+079250X0198Y0197R180 S1      
327P3V3_AUX         R6150 -2          A01X+095276Y+079923X0198Y0197     S1      
317P3V3_AUX         VIA   -    MD0100PA00X+095048Y+078936X0200Y         S0      
327P3V3_AUX         R6149 -2          A01X+095260Y+078247X0198Y0197     S1      
327P3V3_AUX         R6148 -2          A01X+095253Y+078637X0198Y0197     S1      
317P3V3_AUX         VIA   -    MD0100PA00X+095508Y+078486X0200Y         S0      
327P3V3_AUX         C3620 -1   M      A01X+094051Y+079233X0198Y0197     S1      
327P3V3_AUX         OSC2  -4          A01X+093836Y+079819X0400Y0480R180 S1      
317P3V3_AUX         VIA   -    MD0100PA00X+094268Y+078929X0200Y    R090 S0      
317P3V3_AUX         VIA   -    MD0100PA00X+040700Y+078470X0200Y         S0      
327P3V3_AUX         U435  -58         A01X+040535Y+078032X0110Y0340R180 S1      
327P3V3_AUX         PR7177-2          A18X+049736Y+112601X0198Y0197R270 S2      
317P3V3_AUX         VIA   -    MD0100PA00X+049873Y+112876X0200Y         S0      
327P3V3_AUX         PR7176-2          A18X+042800Y+112589X0198Y0197R270 S2      
317P3V3_AUX         VIA   -    MD0100PA00X+042935Y+112909X0200Y         S0      
327P3V3_AUX         R6621 -1          A01X+037471Y+079334X0198Y0197R270 S1      
317P3V3_AUX         VIA   -    MD0100PA00X+037144Y+079119X0200Y         S0      
327P3V3_AUX         C2307 -2   M      A18X+052572Y+087661X0198Y0197     S2      
327P3V3_AUX         U66   -16         A18X+052597Y+088323X0140Y0610R180 S2      
317P3V3_AUX         VIA   -    MD0100PA00X+052572Y+087382X0200Y         S0      
317P3V3_AUX         VIA   -    MD0100PA00X+050689Y+098517X0200Y         S0      
317P3V3_AUX         VIA   -    MD0100PA00X+050409Y+098517X0200Y         S0      
327P3V3_AUX         PR65  -1          A18X+045621Y+100218X0198Y0197R180 S2      
327P3V3_AUX         PR82  -2          A01X+044552Y+103427X0198Y0197R180 S1      
317P3V3_AUX         VIA   -    MD0100PA00X+045327Y+100376X0200Y         S0      
317P3V3_AUX         VIA   -    MD0100PA00X+044309Y+103427X0200Y         S0      
327P3V3_AUX         PR7131-1          A01X+050417Y+099677X0198Y0197R180 S1      
317P3V3_AUX         VIA   -    MD0100PA00X+050657Y+099677X0200Y         S0      
327P3V3_AUX         PR85  -1          A01X+050417Y+100877X0198Y0197R180 S1      
317P3V3_AUX         VIA   -    MD0100PA00X+050657Y+100877X0200Y         S0      
327P3V3_AUX         R825  -1          A01X+051217Y+100077X0198Y0197R180 S1      
317P3V3_AUX         VIA   -    MD0100PA00X+051457Y+100077X0200Y         S0      
327P3V3_AUX         PR83  -2          A01X+050417Y+101227X0198Y0197     S1      
317P3V3_AUX         VIA   -    MD0100PA00X+050657Y+101227X0200Y         S0      
327P3V3_AUX         R1328 -2          A01X+055167Y+102118X0198Y0197     S1      
317P3V3_AUX         VIA   -    MD0100PA00X+055167Y+102390X0200Y         S0      
327P3V3_AUX         R831  -1          A01X+051217Y+101627X0198Y0197R180 S1      
317P3V3_AUX         VIA   -    MD0100PA00X+051457Y+101627X0200Y         S0      
317P3V3_AUX         VIA   -    MD0100PA00X+037021Y+097181X0200Y    R180 S0      
327P3V3_AUX         R813  -2          A01X+037286Y+097181X0198Y0197R180 S1      
317P3V3_AUX         VIA   -    MD0100PA00X+037021Y+096381X0200Y    R180 S0      
327P3V3_AUX         R814  -2          A01X+037286Y+096381X0198Y0197R180 S1      
317P3V3_AUX         VIA   -    MD0100PA00X+039790Y+078900X0200Y    R090 S0      
317P3V3_AUX         VIA   -    MD0100PA00X+040002Y+079679X0200Y    R180 S0      
317P3V3_AUX         VIA   -    MD0100PA00X+039722Y+079679X0200Y    R180 S0      
327P3V3_AUX         C4445 -1          A01X+039930Y+079380X0280Y0320R270 S1      
327P3V3_AUX         C4446 -1          A01X+040062Y+078900X0198Y0197     S1      
327P3V3_AUX         U435  -61         A01X+039944Y+078032X0110Y0340R180 S1      
327P3V3_AUX         U435  -60         A01X+040141Y+078032X0110Y0340R180 S1      
327P3V3_AUX         U431  -7          A01X+057350Y+094967X0110Y0360R090 S1      
327P3V3_AUX         U431  -8          A01X+057350Y+094770X0110Y0360R090 S1      
327P3V3_AUX         U431  -9          A01X+057350Y+094573X0110Y0360R090 S1      
317P3V3_AUX         VIA   -    MD0100PA00X+056310Y+095181X0200Y         S0      
317P3V3_AUX         VIA   -    MD0100PA00X+056940Y+095181X0200Y         S0      
317P3V3_AUX         VIA   -    MD0100PA00X+056630Y+095181X0200Y         S0      
327P3V3_AUX         C4420 -1          A01X+056600Y+094781X0400Y0500R090 S1      
327P3V3_AUX         C2754 -2   M      A01X+036616Y+115009X0198Y0197R090 S1      
317P3V3_AUX         VIA   -    MD0100PA00X+036866Y+115009X0200Y         S0      
317P3V3_AUX         VIA   -    MD0100PA00X+028198Y+095393X0200Y         S0      
327P3V3_AUX         R3878 -2          A01X+034575Y+113713X0198Y0197R270 S1      
317P3V3_AUX         VIA   -    MD0100PA00X+034637Y+113473X0200Y         S0      
327P3V3_AUX         R3877 -2          A01X+036575Y+113713X0198Y0197R270 S1      
317P3V3_AUX         VIA   -    MD0100PA00X+036575Y+113432X0200Y         S0      
327P3V3_AUX         C2608 -2   M      A18X+058350Y+081097X0198Y0197R090 S2      
327P3V3_AUX         U104  -5          A18X+058350Y+080498X0140Y0440     S2      
317P3V3_AUX         VIA   -    MD0100PA00X+058100Y+081097X0200Y         S0      
327P3V3_AUX         C2589 -1          A18X+057024Y+080307X0198Y0197R270 S2      
327P3V3_AUX         U98   -20         A01X+057198Y+080301X0110Y0540R090 S1      
317P3V3_AUX         VIA   -    MD0100PA00X+056756Y+080301X0200Y    R180 S0      
327P3V3_AUX         L6    -1          A18X+055760Y+080689X0280Y0320R090 S2      
317P3V3_AUX         VIA   -    MD0100PA00X+056100Y+080689X0200Y         S0      
327P3V3_AUX         U98   -31         A01X+057198Y+082466X0110Y0540R090 S1      
327P3V3_AUX         C2590 -1          A18X+057024Y+082457X0198Y0197R270 S2      
317P3V3_AUX         VIA   -    MD0100PA00X+056756Y+082466X0200Y    R180 S0      
327P3V3_AUX         C2610 -2   M      A18X+055824Y+084057X0198Y0197R090 S2      
327P3V3_AUX         U106  -5          A18X+055824Y+083409X0140Y0440     S2      
317P3V3_AUX         VIA   -    MD0100PA00X+056081Y+084057X0200Y         S0      
327P3V3_AUX         C2587 -1   M      A18X+054428Y+083089X0198Y0197     S2      
327P3V3_AUX         C2588 -1          A18X+054428Y+083539X0198Y0197     S2      
327P3V3_AUX         U98   -42         A01X+054648Y+083440X0110Y0540     S1      
317P3V3_AUX         VIA   -    MD0100PA00X+054686Y+082995X0200Y    R270 S0      
327P3V3_AUX         U98   -56         A01X+052690Y+081285X0110Y0540R090 S1      
327P3V3_AUX         C2586 -1          A18X+052374Y+081075X0280Y0320     S2      
327P3V3_AUX         C2585 -1   M      A18X+052874Y+081257X0198Y0197R270 S2      
317P3V3_AUX         VIA   -    MD0100PA00X+053131Y+081285X0200Y         S0      
327P3V3_AUX         L7    -1          A18X+053230Y+080339X0280Y0320R270 S2      
317P3V3_AUX         VIA   -    MD0100PA00X+053230Y+080665X0200Y         S0      
327P3V3_AUX         R994  -2          A18X+053232Y+084065X0198Y0197R180 S2      
317P3V3_AUX         VIA   -    MD0100PA00X+053400Y+084300X0200Y         S0      
327P3V3_AUX         R982  -2          A18X+053228Y+083103X0198Y0197R180 S2      
327P3V3_AUX         R983  -2          A18X+053232Y+083615X0198Y0197R180 S2      
317P3V3_AUX         VIA   -    MD0100PA00X+053232Y+083365X0200Y         S0      
327P3V3_AUX         R995  -2          A18X+053196Y+084983X0198Y0197R180 S2      
317P3V3_AUX         VIA   -    MD0100PA00X+053463Y+084983X0200Y         S0      
327P3V3_AUX         R920  -2          A18X+051551Y+081197X0198Y0197R180 S2      
317P3V3_AUX         VIA   -    MD0100PA00X+051856Y+081197X0200Y         S0      
327P3V3_AUX         R919  -2          A18X+051551Y+080397X0198Y0197R180 S2      
317P3V3_AUX         VIA   -    MD0100PA00X+051816Y+080397X0200Y         S0      
327P3V3_AUX         U98   -50         A01X+052690Y+082466X0110Y0540R090 S1      
327P3V3_AUX         C2603 -1          A18X+052574Y+082422X0198Y0197R090 S2      
317P3V3_AUX         VIA   -    MD0100PA00X+052248Y+082466X0200Y    R180 S0      
327P3V3_AUX         U99   -6          A18X+050107Y+080076X0240Y0440R270 S2      
317P3V3_AUX         VIA   -    MD0100PA00X+048941Y+079756X0200Y         S0      
327P3V3_AUX         C829  -1   M      A01X+039675Y+094854X0198Y0197     S1      
327P3V3_AUX         U96   -9          A01X+039332Y+095467X0090Y0240R270 S1      
317P3V3_AUX         VIA   -    MD0100PA00X+039291Y+094854X0200Y    R180 S0      
327P3V3_AUX         R812  -1          A01X+037601Y+095181X0198Y0197R180 S1      
317P3V3_AUX         VIA   -    MD0100PA00X+037812Y+095370X0200Y    R180 S0      
327P3V3_AUX         R850  -1          A01X+038960Y+086441X0198Y0197     S1      
317P3V3_AUX         VIA   -    MD0100PA00X+038659Y+086441X0200Y    R180 S0      
327P3V3_AUX         C2591 -1   M      A18X+050617Y+079615X0198Y0197R180 S2      
327P3V3_AUX         R918  -2          A18X+049107Y+079502X0198Y0197R180 S2      
317P3V3_AUX         VIA   -    MD0100PA00X+050617Y+079322X0200Y         S0      
317P3V3_AUX         VIA   -    MD0100PA00X+009459Y+102390X0200Y         S0      
327P3V3_AUX         R1261 -2          A01X+009459Y+102118X0198Y0197     S1      
317P3V3_AUX         VIA   -    MD0100PA00X+007030Y+106766X0200Y         S0      
327P3V3_AUX         R771  -2          A01X+006766Y+106766X0198Y0197     S1      
317P3V3_AUX         VIA   -    MD0100PA00X+007006Y+107566X0200Y         S0      
327P3V3_AUX         R769  -2          A01X+006766Y+107566X0198Y0197     S1      
317P3V3_AUX         VIA   -    MD0100PA00X+006211Y+108766X0200Y         S0      
327P3V3_AUX         R768  -1          A01X+006451Y+108766X0198Y0197     S1      
317P3V3_AUX         VIA   -    MD0100PA00X+004617Y+109376X0200Y         S0      
327P3V3_AUX         C625  -1   M      A01X+004377Y+109376X0198Y0197R180 S1      
327P3V3_AUX         U87   -9          A01X+004720Y+108762X0090Y0240R090 S1      
327P3V3_AUX         U313  -8          A01X+036098Y+114684X0240Y0460     S1      
327P3V3_AUX         R6575 -1          A18X+057782Y+096180X0198Y0197R180 S2      
327P3V3_AUX         R6571 -1   M      A18X+056610Y+095938X0198Y0197R090 S2      
317P3V3_AUX         VIA   -    MD0100PA00X+056233Y+095731X0200Y    R270 S0      
327P3V3_AUX         R6428 -2          A01X+163408Y+077463X0198Y0197R270 S1      
317P3V3_AUX         VIA   -    MD0100PA00X+163033Y+077463X0200Y         S0      
327P3V3_AUX         R4665 -1          A01X+149942Y+077700X0198Y0197     S1      
317P3V3_AUX         VIA   -    MD0100PA00X+149676Y+077700X0200Y         S0      
327P3V3_AUX         R4662 -1          A01X+142942Y+077050X0198Y0197     S1      
317P3V3_AUX         VIA   -    MD0100PA00X+142700Y+077050X0200Y    R180 S0      
327P3V3_AUX         R4667 -1   M      A01X+142942Y+078250X0198Y0197     S1      
327P3V3_AUX         R4661 -1          A01X+142942Y+078650X0198Y0197     S1      
317P3V3_AUX         VIA   -    MD0100PA00X+142700Y+078183X0200Y    R180 S0      
327P3V3_AUX         R4236 -2          A01X+134237Y+077368X0198Y0197     S1      
317P3V3_AUX         VIA   -    MD0100PA00X+134477Y+077368X0200Y    R180 S0      
327P3V3_AUX         C2146 -1   M      A01X+132758Y+077903X0198Y0197R090 S1      
327P3V3_AUX         U324  -24         A01X+132128Y+077695X0240Y0540R270 S1      
317P3V3_AUX         VIA   -    MD0100PA00X+133032Y+077903X0200Y         S0      
327P3V3_AUX         R5503 -1          A18X+137800Y+081642X0198Y0197R270 S2      
317P3V3_AUX         VIA   -    MD0100PA00X+131072Y+081799X0200Y         S0      
317P3V3_AUX         VIA   -    MD0100PA00X+131072Y+082299X0200Y         S0      
317P3V3_AUX         VIA   -    MD0100PA00X+131072Y+082049X0200Y         S0      
327P3V3_AUX         R4404 -1          A01X+129549Y+079632X0198Y0197     S1      
317P3V3_AUX         VIA   -    MD0100PA00X+129549Y+079882X0200Y    R180 S0      
327P3V3_AUX         C2842 -1   M      A01X+129257Y+080740X0198Y0197R270 S1      
327P3V3_AUX         OSC1  -4          A01X+129872Y+080788X0400Y0480R090 S1      
317P3V3_AUX         VIA   -    MD0100PA00X+128973Y+080684X0200Y    R180 S0      
327P3V3_AUX         R4384 -2          A01X+128816Y+089492X0198Y0197R270 S1      
317P3V3_AUX         VIA   -    MD0100PA00X+128816Y+089235X0200Y         S0      
327P3V3_AUX         R4235 -2          A01X+128194Y+078058X0198Y0197R180 S1      
317P3V3_AUX         VIA   -    MD0100PA00X+127954Y+078058X0200Y         S0      
327P3V3_AUX         R4234 -2          A01X+128194Y+076858X0198Y0197R180 S1      
317P3V3_AUX         VIA   -    MD0100PA00X+127954Y+076858X0200Y         S0      
327P3V3_AUX         R4238 -1          A01X+128194Y+078458X0198Y0197     S1      
317P3V3_AUX         VIA   -    MD0100PA00X+127954Y+078458X0200Y         S0      
327P3V3_AUX         R5911 -2          A01X+128792Y+081950X0198Y0197R180 S1      
317P3V3_AUX         VIA   -    MD0100PA00X+128509Y+081950X0200Y         S0      
327P3V3_AUX         R2987 -1          A01X+126477Y+089487X0198Y0197R180 S1      
317P3V3_AUX         VIA   -    MD0100PA00X+127112Y+089251X0200Y         S0      
327P3V3_AUX         R5638 -1          A18X+130769Y+082227X0280Y0320     S2      
327P3V3_AUX         R5639 -1          A18X+130097Y+084667X0280Y0320R270 S2      
327P3V3_AUX         R5640 -1          A18X+129918Y+086399X0280Y0320R270 S2      
327P3V3_AUX         R4903 -2          A18X+128903Y+086378X0198Y0197R090 S2      
327P3V3_AUX         R5641 -1          A18X+128760Y+089742X0280Y0320R270 S2      
327P3V3_AUX         C2109 -2   M      A01X+117460Y+077443X0198Y0197R180 S1      
327P3V3_AUX         U63   -15         A01X+117128Y+078629X0140Y0630R180 S1      
317P3V3_AUX         VIA   -    MD0100PA00X+117460Y+077174X0200Y         S0      
327P3V3_AUX         C2096 -2   M      A01X+071712Y+077996X0198Y0197R180 S1      
327P3V3_AUX         U50   -15         A01X+070919Y+077494X0140Y0630R270 S1      
317P3V3_AUX         VIA   -    MD0100PA00X+071743Y+078250X0200Y    R090 S0      
327P3V3_AUX         R6437 -2          A01X+162673Y+076272X0198Y0197R180 S1      
317P3V3_AUX         VIA   -    MD0100PA00X+162400Y+076090X0200Y         S0      
327P3V3_AUX         C3598 -1   M      A01X+147150Y+075692X0198Y0197R090 S1      
327P3V3_AUX         U344  -24         A01X+146502Y+075647X0240Y0540R270 S1      
317P3V3_AUX         VIA   -    MD0100PA00X+147442Y+075692X0200Y         S0      
327P3V3_AUX         R4668 -1          A01X+142942Y+076650X0198Y0197     S1      
317P3V3_AUX         VIA   -    MD0100PA00X+142700Y+076650X0200Y    R180 S0      
327P3V3_AUX         R4639 -2          A01X+141242Y+075300X0198Y0197R180 S1      
317P3V3_AUX         VIA   -    MD0100PA00X+141000Y+075300X0200Y    R180 S0      
327P3V3_AUX         R4640 -2          A01X+141242Y+075700X0198Y0197R180 S1      
317P3V3_AUX         VIA   -    MD0100PA00X+141000Y+075700X0200Y    R180 S0      
327P3V3_AUX         R4247 -1          A01X+134237Y+075768X0198Y0197R180 S1      
317P3V3_AUX         VIA   -    MD0100PA00X+134477Y+075768X0200Y    R180 S0      
327P3V3_AUX         R4248 -1   M      A01X+134237Y+076168X0198Y0197R180 S1      
327P3V3_AUX         R4240 -1          A01X+134237Y+076568X0198Y0197R180 S1      
317P3V3_AUX         VIA   -    MD0100PA00X+134477Y+076168X0200Y    R180 S0      
327P3V3_AUX         R4241 -1          A01X+134237Y+075368X0198Y0197R180 S1      
317P3V3_AUX         VIA   -    MD0100PA00X+134477Y+075368X0200Y    R180 S0      
327P3V3_AUX         R5066 -1          A01X+100399Y+076840X0198Y0197R090 S1      
327P3V3_AUX         R5283 -1          A18X+099303Y+076878X0198Y0197     S2      
317P3V3_AUX         VIA   -    MD0100PA00X+100399Y+076590X0200Y    R180 S0      
317P3V3_AUX         VIA   -    MD0100PA00X+052055Y+076198X0200Y         S0      
327P3V3_AUX         U441  -5          A01X+051719Y+076926X0140Y0440R180 S1      
327P3V3_AUX         C4448 -2   M      A01X+051741Y+076198X0198Y0197R090 S1      
317P3V3_AUX         VIA   -    MD0100PA00X+042925Y+075985X0200Y         S0      
327P3V3_AUX         U435  -39         A01X+042582Y+075985X0110Y0340R090 S1      
317P3V3_AUX         VIA   -    MD0100PA00X+037980Y+076920X0200Y         S0      
317P3V3_AUX         VIA   -    MD0100PA00X+037630Y+076730X0200Y         S0      
327P3V3_AUX         C4444 -1          A01X+037980Y+077202X0198Y0197R090 S1      
327P3V3_AUX         U435  -3          A01X+039078Y+077363X0110Y0340R270 S1      
327P3V3_AUX         C4443 -1          A01X+037480Y+077070X0280Y0320     S1      
317P3V3_AUX         VIA   -    MD0100PA00X+037350Y+076730X0200Y         S0      
327P3V3_AUX         R6425 -2          A01X+162743Y+074432X0198Y0197R180 S1      
317P3V3_AUX         VIA   -    MD0100PA00X+162834Y+074729X0200Y         S0      
327P3V3_AUX         R4641 -2          A01X+149308Y+075050X0198Y0197     S1      
317P3V3_AUX         VIA   -    MD0100PA00X+149550Y+075050X0200Y         S0      
327P3V3_AUX         R4603 -1          A01X+148242Y+073550X0198Y0197     S1      
317P3V3_AUX         VIA   -    MD0100PA00X+147966Y+073550X0200Y         S0      
327P3V3_AUX         R4609 -1          A01X+148242Y+074350X0198Y0197     S1      
317P3V3_AUX         VIA   -    MD0100PA00X+147976Y+074350X0200Y         S0      
327P3V3_AUX         R4606 -1          A01X+141242Y+074100X0198Y0197     S1      
317P3V3_AUX         VIA   -    MD0100PA00X+141000Y+074100X0200Y    R180 S0      
327P3V3_AUX         R4600 -1          A01X+141242Y+074500X0198Y0197     S1      
317P3V3_AUX         VIA   -    MD0100PA00X+141000Y+074500X0200Y    R180 S0      
327P3V3_AUX         R4243 -1          A01X+134237Y+074968X0198Y0197R180 S1      
317P3V3_AUX         VIA   -    MD0100PA00X+134477Y+074968X0200Y    R180 S0      
327P3V3_AUX         R4242 -1          A01X+134237Y+074568X0198Y0197R180 S1      
317P3V3_AUX         VIA   -    MD0100PA00X+134477Y+074568X0200Y    R180 S0      
327P3V3_AUX         R4239 -1          A01X+134237Y+074168X0198Y0197R180 S1      
317P3V3_AUX         VIA   -    MD0100PA00X+134477Y+074168X0200Y    R180 S0      
327P3V3_AUX         R4237 -1          A01X+134237Y+073768X0198Y0197R180 S1      
317P3V3_AUX         VIA   -    MD0100PA00X+134477Y+073768X0200Y    R180 S0      
327P3V3_AUX         C2629 -2   M      A01X+088404Y+075031X0198Y0197R090 S1      
327P3V3_AUX         U305  -8          A01X+088003Y+076133X0140Y0520R180 S1      
317P3V3_AUX         VIA   -    MD0100PA00X+088116Y+074915X0200Y    R270 S0      
327P3V3_AUX         R5301 -2          A01X+085448Y+074430X0198Y0197R090 S1      
317P3V3_AUX         VIA   -    MD0100PA00X+085448Y+074670X0200Y         S0      
327P3V3_AUX         R5303 -2   M      A01X+083848Y+074430X0198Y0197R090 S1      
327P3V3_AUX         R5302 -2          A01X+084248Y+074430X0198Y0197R090 S1      
317P3V3_AUX         VIA   -    MD0100PA00X+083848Y+074670X0200Y         S0      
327P3V3_AUX         R5304 -2          A01X+082648Y+074430X0198Y0197R090 S1      
317P3V3_AUX         VIA   -    MD0100PA00X+082648Y+074713X0200Y    R090 S0      
317P3V3_AUX         VIA   -    MD0100PA00X+056743Y+075014X0200Y         S0      
327P3V3_AUX         U440  -5          A01X+056183Y+074716X0140Y0440R270 S1      
327P3V3_AUX         C4449 -2   M      A01X+056743Y+074708X0198Y0197R180 S1      
317P3V3_AUX         VIA   -    MD0100PA00X+040620Y+074130X0200Y         S0      
327P3V3_AUX         U435  -24         A01X+040732Y+074528X0110Y0340     S1      
327P3V3_AUX         R6445 -2          A01X+163843Y+072812X0198Y0197R180 S1      
317P3V3_AUX         VIA   -    MD0100PA00X+163528Y+072812X0200Y         S0      
327P3V3_AUX         R4607 -1          A01X+141242Y+072500X0198Y0197     S1      
317P3V3_AUX         VIA   -    MD0100PA00X+141000Y+072500X0200Y    R180 S0      
327P3V3_AUX         R4601 -1          A01X+141242Y+072900X0198Y0197     S1      
317P3V3_AUX         VIA   -    MD0100PA00X+141000Y+072900X0200Y    R180 S0      
327P3V3_AUX         R4747 -2          A01X+140208Y+072200X0198Y0197     S1      
317P3V3_AUX         VIA   -    MD0100PA00X+140450Y+072200X0200Y         S0      
327P3V3_AUX         C3601 -1   M      A01X+138050Y+072842X0198Y0197R090 S1      
327P3V3_AUX         U347  -24         A01X+137402Y+072797X0240Y0540R270 S1      
317P3V3_AUX         VIA   -    MD0100PA00X+138342Y+072842X0200Y         S0      
327P3V3_AUX         R4745 -2          A01X+132142Y+072850X0198Y0197R180 S1      
317P3V3_AUX         VIA   -    MD0100PA00X+131900Y+072850X0200Y    R180 S0      
327P3V3_AUX         R4746 -2          A01X+132142Y+072450X0198Y0197R180 S1      
317P3V3_AUX         VIA   -    MD0100PA00X+131900Y+072450X0200Y    R180 S0      
317P3V3_AUX         VIA   -    MD0100PA00X+097371Y+072206X0200Y    R090 S0      
327P3V3_AUX         R5504 -2          A01X+097371Y+071966X0198Y0197R090 S1      
327P3V3_AUX         C3645 -2   M      A01X+093853Y+072745X0198Y0197R270 S1      
327P3V3_AUX         U358  -4          A01X+093853Y+071990X0220Y0560     S1      
317P3V3_AUX         VIA   -    MD0100PA00X+093603Y+072745X0200Y    R090 S0      
327P3V3_AUX         R5493 -2          A01X+091084Y+071897X0198Y0197     S1      
317P3V3_AUX         VIA   -    MD0100PA00X+091084Y+072157X0200Y         S0      
327P3V3_AUX         C2185 -1   M      A01X+088369Y+072718X0198Y0197     S1      
327P3V3_AUX         U362  -5          A01X+087773Y+072718X0400Y0150     S1      
317P3V3_AUX         VIA   -    MD0100PA00X+088369Y+072978X0200Y         S0      
327P3V3_AUX         R6431 -2          A01X+163103Y+071142X0198Y0197R180 S1      
317P3V3_AUX         VIA   -    MD0100PA00X+162820Y+071142X0200Y         S0      
327P3V3_AUX         R4728 -1          A01X+140258Y+070300X0198Y0197R180 S1      
317P3V3_AUX         VIA   -    MD0100PA00X+140500Y+070300X0200Y         S0      
327P3V3_AUX         R4734 -1          A01X+140258Y+070700X0198Y0197R180 S1      
317P3V3_AUX         VIA   -    MD0100PA00X+140500Y+070700X0200Y         S0      
327P3V3_AUX         R4704 -2          A01X+141242Y+071300X0198Y0197R180 S1      
317P3V3_AUX         VIA   -    MD0100PA00X+141000Y+071300X0200Y    R180 S0      
327P3V3_AUX         R4701 -2          A01X+141242Y+070900X0198Y0197R180 S1      
317P3V3_AUX         VIA   -    MD0100PA00X+141000Y+070900X0200Y    R180 S0      
327P3V3_AUX         R4724 -1          A01X+132142Y+071650X0198Y0197     S1      
317P3V3_AUX         VIA   -    MD0100PA00X+131900Y+071650X0200Y    R180 S0      
327P3V3_AUX         R4730 -1          A01X+132142Y+071250X0198Y0197     S1      
317P3V3_AUX         VIA   -    MD0100PA00X+131900Y+071250X0200Y    R180 S0      
327P3V3_AUX         R254  -1          A01X+111810Y+071013X0198Y0197R180 S1      
317P3V3_AUX         VIA   -    MD0100PA00X+111810Y+070759X0200Y         S0      
327P3V3_AUX         C2147 -1   M      A01X+096150Y+070441X0198Y0197R270 S1      
327P3V3_AUX         U325  -5          A01X+096150Y+071116X0220Y0530R180 S1      
317P3V3_AUX         VIA   -    MD0100PA00X+096577Y+070691X0200Y         S0      
327P3V3_AUX         R5492 -1          A01X+092106Y+071292X0198Y0197R270 S1      
317P3V3_AUX         VIA   -    MD0100PA00X+092106Y+071539X0200Y         S0      
327P3V3_AUX         R5491 -1          A01X+088684Y+071857X0198Y0197R180 S1      
317P3V3_AUX         VIA   -    MD0100PA00X+088684Y+071597X0200Y    R180 S0      
327P3V3_AUX         C3625 -1   M      A01X+084828Y+071659X0198Y0197R270 S1      
327P3V3_AUX         U351  -5          A01X+084828Y+072718X0140Y0440R180 S1      
317P3V3_AUX         VIA   -    MD0100PA00X+084578Y+071659X0200Y         S0      
327P3V3_AUX         U52   -5          A01X+072973Y+073620X0240Y0420R090 S1      
327P3V3_AUX         C2093 -2   M      A01X+072381Y+073898X0198Y0197R270 S1      
317P3V3_AUX         VIA   -    MD0100PA00X+072116Y+073898X0200Y         S0      
327P3V3_AUX         R5418 -2          A01X+085228Y+070649X0198Y0197R270 S1      
327P3V3_AUX         R5419 -2          A01X+084328Y+070649X0198Y0197R270 S1      
327P3V3_AUX         R5420 -2          A01X+083929Y+070647X0198Y0197R270 S1      
327P3V3_AUX         R5421 -2          A01X+082728Y+070649X0198Y0197R270 S1      
317P3V3_AUX         VIA   -    MD0100PA00X+084578Y+070549X0200Y         S0      
317P3V3_AUX         VIA   -    MD0100PA00X+082978Y+070549X0200Y         S0      
327P3V3_AUX         C3626 -1   M      A01X+083228Y+071659X0198Y0197R270 S1      
327P3V3_AUX         U352  -5          A01X+083228Y+072718X0140Y0440R180 S1      
317P3V3_AUX         VIA   -    MD0100PA00X+082978Y+071659X0200Y         S0      
327P3V3_AUX         R152  -1          A01X+066102Y+071013X0198Y0197R180 S1      
317P3V3_AUX         VIA   -    MD0100PA00X+066102Y+070759X0200Y         S0      
327P3V3_AUX         R4669 -1          A01X+141242Y+069700X0198Y0197     S1      
317P3V3_AUX         VIA   -    MD0100PA00X+141000Y+069700X0200Y    R180 S0      
327P3V3_AUX         R4663 -1          A01X+141242Y+070100X0198Y0197     S1      
317P3V3_AUX         VIA   -    MD0100PA00X+141000Y+070100X0200Y    R180 S0      
327P3V3_AUX         R4725 -1          A01X+132142Y+070050X0198Y0197     S1      
317P3V3_AUX         VIA   -    MD0100PA00X+131900Y+070050X0200Y    R180 S0      
327P3V3_AUX         R4731 -1          A01X+132142Y+069650X0198Y0197     S1      
317P3V3_AUX         VIA   -    MD0100PA00X+131900Y+069650X0200Y    R180 S0      
327P3V3_AUX         R5479 -1          A01X+094756Y+070205X0198Y0197R090 S1      
317P3V3_AUX         VIA   -    MD0100PA00X+094756Y+069955X0200Y    R090 S0      
327P3V3_AUX         C3646 -2   M      A01X+090689Y+069977X0198Y0197R180 S1      
327P3V3_AUX         U359  -6          A01X+089575Y+069668X0140Y0580R270 S1      
317P3V3_AUX         VIA   -    MD0100PA00X+090689Y+070228X0200Y         S0      
317P3V3_AUX         VIA   -    MD0100PA00X+091246Y+068777X0200Y    R270 S0      
327P3V3_AUX         R3145 -1          A01X+087869Y+069497X0198Y0197     S1      
317P3V3_AUX         VIA   -    MD0100PA00X+087629Y+069497X0200Y         S0      
327P3V3_AUX         C3649 -2   M      A01X+086892Y+069839X0198Y0197R180 S1      
327P3V3_AUX         U360  -5          A01X+086948Y+069271X0220Y0530R270 S1      
317P3V3_AUX         VIA   -    MD0100PA00X+086892Y+070089X0200Y         S0      
327P3V3_AUX         R5781 -1          A01X+086069Y+070117X0198Y0197     S1      
317P3V3_AUX         VIA   -    MD0100PA00X+085819Y+070117X0200Y         S0      
327P3V3_AUX         R5913 -2          A01X+084968Y+069219X0198Y0197R090 S1      
317P3V3_AUX         VIA   -    MD0100PA00X+084968Y+069479X0200Y         S0      
317P3V3_AUX         VIA   -    MD0100PA00X+071320Y+069968X0200Y         S0      
327P3V3_AUX         U439  -5          A01X+070766Y+069965X0140Y0440R270 S1      
327P3V3_AUX         C4450 -2   M      A01X+071320Y+069672X0198Y0197R180 S1      
327P3V3_AUX         R4766 -2          A01X+140208Y+067500X0198Y0197     S1      
317P3V3_AUX         VIA   -    MD0100PA00X+140450Y+067500X0200Y         S0      
327P3V3_AUX         R4670 -1          A01X+141242Y+068100X0198Y0197     S1      
317P3V3_AUX         VIA   -    MD0100PA00X+141000Y+068100X0200Y    R180 S0      
327P3V3_AUX         R4664 -1          A01X+141242Y+068500X0198Y0197     S1      
317P3V3_AUX         VIA   -    MD0100PA00X+141000Y+068500X0200Y    R180 S0      
327P3V3_AUX         C3602 -1   M      A01X+138050Y+068142X0198Y0197R090 S1      
327P3V3_AUX         U348  -24         A01X+137402Y+068097X0240Y0540R270 S1      
317P3V3_AUX         VIA   -    MD0100PA00X+138342Y+068142X0200Y         S0      
327P3V3_AUX         R4764 -2          A01X+132142Y+067750X0198Y0197R180 S1      
317P3V3_AUX         VIA   -    MD0100PA00X+131900Y+067750X0200Y    R180 S0      
327P3V3_AUX         R4765 -2          A01X+132142Y+068150X0198Y0197R180 S1      
317P3V3_AUX         VIA   -    MD0100PA00X+131900Y+068150X0200Y    R180 S0      
327P3V3_AUX         U327  -5          A01X+093241Y+068724X0220Y0530R180 S1      
327P3V3_AUX         C2808 -1   M      A01X+093241Y+068094X0198Y0197R270 S1      
317P3V3_AUX         VIA   -    MD0100PA00X+093528Y+068094X0200Y         S0      
327P3V3_AUX         R4702 -2          A01X+149308Y+070650X0198Y0197     S1      
327P3V3_AUX         C619  -1   M      A01X+157214Y+066040X0198Y0197     S1      
327P3V3_AUX         U40   -5          A01X+156677Y+065828X0160Y0360R270 S1      
327P3V3_AUX         C948  -1   M      A01X+157308Y+066628X0198Y0197R180 S1      
327P3V3_AUX         U41   -5          A01X+157261Y+067236X0220Y0530R180 S1      
317P3V3_AUX         VIA   -    MD0100PA00X+157214Y+066298X0200Y         S0      
327P3V3_AUX         R356  -1          A01X+157519Y+071013X0198Y0197R180 S1      
317P3V3_AUX         VIA   -    MD0100PA00X+157519Y+070759X0200Y         S0      
327P3V3_AUX         C3599 -1   M      A01X+147150Y+071292X0198Y0197R090 S1      
327P3V3_AUX         U346  -24         A01X+146502Y+071247X0240Y0540R270 S1      
317P3V3_AUX         VIA   -    MD0100PA00X+147442Y+071292X0200Y         S0      
327P3V3_AUX         R4666 -1          A01X+148192Y+068163X0198Y0197     S1      
317P3V3_AUX         VIA   -    MD0100PA00X+147760Y+068300X0200Y         S0      
327P3V3_AUX         R4672 -1          A01X+148192Y+069363X0198Y0197     S1      
317P3V3_AUX         VIA   -    MD0100PA00X+147930Y+069363X0200Y         S0      
327P3V3_AUX         R4735 -1          A01X+140258Y+066000X0198Y0197R180 S1      
317P3V3_AUX         VIA   -    MD0100PA00X+140500Y+066000X0200Y         S0      
327P3V3_AUX         R4732 -1          A01X+132142Y+066550X0198Y0197     S1      
317P3V3_AUX         VIA   -    MD0100PA00X+131900Y+066550X0200Y    R180 S0      
327P3V3_AUX         R4726 -1          A01X+132142Y+066950X0198Y0197     S1      
317P3V3_AUX         VIA   -    MD0100PA00X+131900Y+066950X0200Y    R180 S0      
327P3V3_AUX         C933  -1   M      A01X+111505Y+066040X0198Y0197     S1      
327P3V3_AUX         U30   -5          A01X+110968Y+065828X0160Y0360R270 S1      
327P3V3_AUX         C917  -1   M      A01X+111599Y+066628X0198Y0197R180 S1      
327P3V3_AUX         U31   -5          A01X+111552Y+067236X0220Y0530R180 S1      
317P3V3_AUX         VIA   -    MD0100PA00X+111505Y+066298X0200Y         S0      
327P3V3_AUX         U21   -5          A01X+065844Y+067236X0220Y0530R180 S1      
327P3V3_AUX         C886  -1   M      A01X+065890Y+066628X0198Y0197R180 S1      
317P3V3_AUX         VIA   -    MD0100PA00X+066209Y+066628X0200Y         S0      
327P3V3_AUX         C415  -1   M      A01X+065797Y+066040X0198Y0197     S1      
327P3V3_AUX         U20   -5          A01X+065260Y+065828X0160Y0360R270 S1      
317P3V3_AUX         VIA   -    MD0100PA00X+065797Y+066298X0200Y         S0      
317P3V3_AUX         VIA   -    MD0100PA00X+049446Y+065777X0200Y         S0      
327P3V3_AUX         U438  -5          A01X+049132Y+066333X0140Y0440R180 S1      
327P3V3_AUX         C4451 -2   M      A01X+049137Y+065777X0198Y0197R090 S1      
327P3V3_AUX         R4729 -1          A01X+140258Y+065200X0198Y0197R180 S1      
317P3V3_AUX         VIA   -    MD0100PA00X+140523Y+065203X0200Y         S0      
327P3V3_AUX         R4733 -1          A01X+132142Y+064950X0198Y0197     S1      
317P3V3_AUX         VIA   -    MD0100PA00X+131900Y+064950X0200Y    R180 S0      
327P3V3_AUX         R4727 -1          A01X+132142Y+065350X0198Y0197     S1      
317P3V3_AUX         VIA   -    MD0100PA00X+131900Y+065350X0200Y    R180 S0      
317P3V3_AUX         VIA   -    MD0100PA00X+169238Y+062291X0200Y    R180 S0      
327P3V3_AUX         R365  -2          A01X+168992Y+062291X0198Y0197     S1      
327P3V3_AUX         PR7052-2          A01X+140138Y+062931X0198Y0197R180 S1      
317P3V3_AUX         VIA   -    MD0100PA00X+139895Y+062931X0200Y         S0      
327P3V3_AUX         R4809 -2          A01X+138866Y+062369X0198Y0197     S1      
317P3V3_AUX         VIA   -    MD0100PA00X+139159Y+062369X0200Y         S0      
327P3V3_AUX         C3604 -1   M      A01X+138050Y+063692X0198Y0197R090 S1      
327P3V3_AUX         U349  -24         A01X+137402Y+063647X0240Y0540R270 S1      
317P3V3_AUX         VIA   -    MD0100PA00X+138342Y+063692X0200Y         S0      
327P3V3_AUX         R4808 -2          A01X+132142Y+063700X0198Y0197R180 S1      
317P3V3_AUX         VIA   -    MD0100PA00X+131900Y+063700X0200Y    R180 S0      
327P3V3_AUX         R4787 -1          A01X+132142Y+062500X0198Y0197     S1      
317P3V3_AUX         VIA   -    MD0100PA00X+131900Y+062500X0200Y    R180 S0      
327P3V3_AUX         R4811 -2          A01X+132142Y+063300X0198Y0197R180 S1      
317P3V3_AUX         VIA   -    MD0100PA00X+131900Y+063300X0200Y    R180 S0      
327P3V3_AUX         R263  -2          A01X+123283Y+062291X0198Y0197     S1      
317P3V3_AUX         VIA   -    MD0100PA00X+123529Y+062291X0200Y    R180 S0      
327P3V3_AUX         PR7028-2          A01X+094429Y+062931X0198Y0197R180 S1      
317P3V3_AUX         VIA   -    MD0100PA00X+094186Y+062931X0200Y         S0      
327P3V3_AUX         R161  -2          A01X+077575Y+062291X0198Y0197     S1      
317P3V3_AUX         VIA   -    MD0100PA00X+077820Y+062291X0200Y    R180 S0      
327P3V3_AUX         PR6893-2          A01X+048720Y+062931X0198Y0197R180 S1      
317P3V3_AUX         VIA   -    MD0100PA00X+048477Y+062931X0200Y         S0      
327P3V3_AUX         R59   -2          A01X+031866Y+062291X0198Y0197     S1      
317P3V3_AUX         VIA   -    MD0100PA00X+032112Y+062291X0200Y    R180 S0      
327P3V3_AUX         R50   -1          A18X+022126Y+063258X0198Y0197R270 S2      
327P3V3_AUX         C858  -1          A18X+021930Y+062340X0198Y0197     S2      
327P3V3_AUX         U11   -5          A18X+022780Y+062354X0220Y0530R090 S2      
317P3V3_AUX         VIA   -    MD0100PA00X+022026Y+062975X0200Y         S0      
327P3V3_AUX         PR6870-2          A01X+003012Y+062931X0198Y0197R180 S1      
317P3V3_AUX         VIA   -    MD0100PA00X+002769Y+062931X0200Y         S0      
327P3V3_AUX         R747  -2          A01X+145894Y+060280X0198Y0197R090 S1      
317P3V3_AUX         VIA   -    MD0100PA00X+145894Y+060544X0200Y    R090 S0      
327P3V3_AUX         R749  -2          A01X+145094Y+060280X0198Y0197R090 S1      
317P3V3_AUX         VIA   -    MD0100PA00X+145094Y+060544X0200Y    R090 S0      
327P3V3_AUX         R957  -1          A01X+140138Y+062131X0198Y0197     S1      
317P3V3_AUX         VIA   -    MD0100PA00X+139895Y+062131X0200Y         S0      
327P3V3_AUX         R4797 -1   M      A18X+138286Y+061550X0198Y0197R180 S2      
327P3V3_AUX         R4791 -1          A18X+138286Y+061150X0198Y0197R180 S2      
317P3V3_AUX         VIA   -    MD0100PA00X+138361Y+061843X0200Y         S0      
327P3V3_AUX         R4788 -1          A01X+132142Y+060900X0198Y0197     S1      
317P3V3_AUX         VIA   -    MD0100PA00X+131900Y+060900X0200Y    R180 S0      
327P3V3_AUX         R4793 -1          A01X+132142Y+062100X0198Y0197     S1      
317P3V3_AUX         VIA   -    MD0100PA00X+131900Y+062100X0200Y    R180 S0      
327P3V3_AUX         R725  -2          A01X+100186Y+060280X0198Y0197R090 S1      
317P3V3_AUX         VIA   -    MD0100PA00X+100186Y+060544X0200Y    R090 S0      
327P3V3_AUX         R726  -2          A01X+099386Y+060280X0198Y0197R090 S1      
317P3V3_AUX         VIA   -    MD0100PA00X+099386Y+060544X0200Y    R090 S0      
327P3V3_AUX         R951  -1          A01X+094429Y+062131X0198Y0197     S1      
317P3V3_AUX         VIA   -    MD0100PA00X+094186Y+062131X0200Y         S0      
327P3V3_AUX         R705  -2          A01X+054477Y+060280X0198Y0197R090 S1      
317P3V3_AUX         VIA   -    MD0100PA00X+054477Y+060544X0200Y    R090 S0      
327P3V3_AUX         R703  -2          A01X+053677Y+060280X0198Y0197R090 S1      
317P3V3_AUX         VIA   -    MD0100PA00X+053677Y+060544X0200Y    R090 S0      
327P3V3_AUX         R945  -1          A01X+048720Y+062131X0198Y0197     S1      
317P3V3_AUX         VIA   -    MD0100PA00X+048477Y+062131X0200Y         S0      
327P3V3_AUX         R681  -2          A01X+008768Y+060280X0198Y0197R090 S1      
317P3V3_AUX         VIA   -    MD0100PA00X+008768Y+060544X0200Y    R090 S0      
327P3V3_AUX         R683  -2          A01X+007968Y+060280X0198Y0197R090 S1      
317P3V3_AUX         VIA   -    MD0100PA00X+007968Y+060544X0200Y    R090 S0      
327P3V3_AUX         R902  -1          A01X+003012Y+062131X0198Y0197     S1      
317P3V3_AUX         VIA   -    MD0100PA00X+002769Y+062131X0200Y         S0      
327P3V3_AUX         R757  -1          A01X+143894Y+059965X0198Y0197R090 S1      
317P3V3_AUX         VIA   -    MD0100PA00X+143894Y+059723X0200Y    R090 S0      
327P3V3_AUX         C3603 -1   M      A01X+138050Y+059042X0198Y0197R090 S1      
327P3V3_AUX         U350  -24         A01X+137402Y+058997X0240Y0540R270 S1      
317P3V3_AUX         VIA   -    MD0100PA00X+138342Y+059042X0200Y         S0      
327P3V3_AUX         R4828 -2          A01X+132142Y+059050X0198Y0197R180 S1      
317P3V3_AUX         VIA   -    MD0100PA00X+131900Y+059050X0200Y    R180 S0      
327P3V3_AUX         R4794 -1          A01X+132142Y+060500X0198Y0197     S1      
317P3V3_AUX         VIA   -    MD0100PA00X+131900Y+060500X0200Y    R180 S0      
327P3V3_AUX         R724  -1          A01X+098186Y+059965X0198Y0197R090 S1      
317P3V3_AUX         VIA   -    MD0100PA00X+098186Y+059723X0200Y    R090 S0      
327P3V3_AUX         R702  -1          A01X+052477Y+059965X0198Y0197R090 S1      
317P3V3_AUX         VIA   -    MD0100PA00X+052477Y+059723X0200Y    R090 S0      
327P3V3_AUX         C857  -1   M      A18X+024359Y+060266X0198Y0197R090 S2      
327P3V3_AUX         U10   -5          A18X+023669Y+060266X0160Y0360R270 S2      
317P3V3_AUX         VIA   -    MD0100PA00X+024754Y+060269X0200Y         S0      
327P3V3_AUX         R680  -1          A01X+006768Y+059965X0198Y0197R090 S1      
317P3V3_AUX         VIA   -    MD0100PA00X+006768Y+059723X0200Y    R090 S0      
327P3V3_AUX         C946  -1   M      A01X+143567Y+057891X0198Y0197R270 S1      
327P3V3_AUX         U85   -9          A01X+144181Y+058234X0090Y0240R180 S1      
317P3V3_AUX         VIA   -    MD0100PA00X+143567Y+058275X0200Y    R090 S0      
327P3V3_AUX         R4829 -2          A01X+138866Y+058132X0198Y0197     S1      
317P3V3_AUX         VIA   -    MD0100PA00X+139109Y+058132X0200Y         S0      
327P3V3_AUX         R4789 -1          A01X+132142Y+057850X0198Y0197     S1      
317P3V3_AUX         VIA   -    MD0100PA00X+131900Y+057850X0200Y    R180 S0      
327P3V3_AUX         R4795 -1          A01X+132142Y+057450X0198Y0197     S1      
317P3V3_AUX         VIA   -    MD0100PA00X+131900Y+057450X0200Y    R180 S0      
327P3V3_AUX         R4827 -2          A01X+132142Y+058650X0198Y0197R180 S1      
317P3V3_AUX         VIA   -    MD0100PA00X+131900Y+058650X0200Y    R180 S0      
317P3V3_AUX         VIA   -    MD0100PA00X+097858Y+058275X0200Y    R090 S0      
327P3V3_AUX         C916  -1   M      A01X+097858Y+057891X0198Y0197R270 S1      
327P3V3_AUX         U83   -9          A01X+098472Y+058234X0090Y0240R180 S1      
327P3V3_AUX         C888  -1   M      A01X+052149Y+057891X0198Y0197R270 S1      
327P3V3_AUX         U81   -9          A01X+052763Y+058234X0090Y0240R180 S1      
317P3V3_AUX         VIA   -    MD0100PA00X+052149Y+058275X0200Y    R090 S0      
327P3V3_AUX         C409  -1   M      A01X+006441Y+057891X0198Y0197R270 S1      
327P3V3_AUX         U79   -9          A01X+007055Y+058234X0090Y0240R180 S1      
317P3V3_AUX         VIA   -    MD0100PA00X+006441Y+058275X0200Y    R090 S0      
327P3V3_AUX         R4798 -1   M      A18X+138286Y+056900X0198Y0197R180 S2      
327P3V3_AUX         R4792 -1          A18X+138286Y+056500X0198Y0197R180 S2      
317P3V3_AUX         VIA   -    MD0100PA00X+138361Y+057193X0200Y         S0      
327P3V3_AUX         R4796 -1          A01X+132142Y+055850X0198Y0197     S1      
317P3V3_AUX         VIA   -    MD0100PA00X+131900Y+055850X0200Y    R180 S0      
327P3V3_AUX         R4790 -1          A01X+132142Y+056250X0198Y0197     S1      
317P3V3_AUX         VIA   -    MD0100PA00X+131900Y+056250X0200Y    R180 S0      
327P3V3_AUX         R401  -1          A01X+169454Y+055329X0198Y0197R270 S1      
317P3V3_AUX         VIA   -    MD0100PA00X+168924Y+055014X0200Y    R180 S0      
327P3V3_AUX         R362  -2          A01X+161957Y+054271X0198Y0197R180 S1      
317P3V3_AUX         VIA   -    MD0100PA00X+161662Y+054271X0200Y    R180 S0      
327P3V3_AUX         C947  -1   M      A18X+159176Y+054708X0198Y0197R090 S2      
327P3V3_AUX         U38   -5          A18X+159081Y+055189X0240Y0240R180 S2      
317P3V3_AUX         VIA   -    MD0100PA00X+159526Y+054708X0200Y         S0      
327P3V3_AUX         R312  -2          A01X+159284Y+054980X0198Y0197     S1      
317P3V3_AUX         VIA   -    MD0100PA00X+159546Y+054980X0200Y         S0      
327P3V3_AUX         R339  -2   M      A01X+151537Y+055456X0198Y0197R180 S1      
327P3V3_AUX         R337  -2   M      A01X+151537Y+055856X0198Y0197R180 S1      
327P3V3_AUX         R335  -2          A01X+151537Y+056256X0198Y0197R180 S1      
317P3V3_AUX         VIA   -    MD0100PA00X+151328Y+055247X0200Y         S0      
327P3V3_AUX         R858  -1          A01X+139966Y+054873X0198Y0197     S1      
317P3V3_AUX         VIA   -    MD0100PA00X+139708Y+054873X0200Y    R180 S0      
327P3V3_AUX         R299  -1          A01X+123746Y+055329X0198Y0197R270 S1      
317P3V3_AUX         VIA   -    MD0100PA00X+123215Y+055014X0200Y    R180 S0      
327P3V3_AUX         R261  -2          A01X+116248Y+054271X0198Y0197R180 S1      
317P3V3_AUX         VIA   -    MD0100PA00X+115954Y+054271X0200Y    R180 S0      
317P3V3_AUX         VIA   -    MD0100PA00X+113817Y+054708X0200Y         S0      
327P3V3_AUX         U28   -5          A18X+113372Y+055189X0240Y0240R180 S2      
327P3V3_AUX         C918  -1   M      A18X+113467Y+054708X0198Y0197R090 S2      
327P3V3_AUX         R211  -2          A01X+113575Y+054980X0198Y0197     S1      
317P3V3_AUX         VIA   -    MD0100PA00X+113837Y+054980X0200Y         S0      
327P3V3_AUX         R237  -2   M      A01X+105829Y+055456X0198Y0197R180 S1      
327P3V3_AUX         R235  -2   M      A01X+105829Y+055856X0198Y0197R180 S1      
327P3V3_AUX         R233  -2          A01X+105829Y+056256X0198Y0197R180 S1      
317P3V3_AUX         VIA   -    MD0100PA00X+105588Y+055456X0200Y         S0      
327P3V3_AUX         R854  -1          A01X+094257Y+054873X0198Y0197     S1      
317P3V3_AUX         VIA   -    MD0100PA00X+093999Y+054873X0200Y    R180 S0      
327P3V3_AUX         R197  -1          A01X+078037Y+055329X0198Y0197R270 S1      
317P3V3_AUX         VIA   -    MD0100PA00X+077771Y+055329X0200Y    R180 S0      
327P3V3_AUX         R159  -2          A01X+070540Y+054271X0198Y0197R180 S1      
317P3V3_AUX         VIA   -    MD0100PA00X+070245Y+054271X0200Y    R180 S0      
327P3V3_AUX         R109  -2          A01X+067866Y+054980X0198Y0197     S1      
317P3V3_AUX         VIA   -    MD0100PA00X+068129Y+054980X0200Y         S0      
327P3V3_AUX         U18   -5          A18X+067663Y+055189X0240Y0240R180 S2      
327P3V3_AUX         C901  -1   M      A18X+067759Y+054708X0198Y0197R090 S2      
317P3V3_AUX         VIA   -    MD0100PA00X+068109Y+054708X0200Y         S0      
327P3V3_AUX         R135  -2   M      A01X+060120Y+055456X0198Y0197R180 S1      
327P3V3_AUX         R133  -2   M      A01X+060120Y+055856X0198Y0197R180 S1      
327P3V3_AUX         R131  -2          A01X+060120Y+056256X0198Y0197R180 S1      
317P3V3_AUX         VIA   -    MD0100PA00X+059911Y+055247X0200Y         S0      
327P3V3_AUX         R857  -1          A01X+048548Y+054873X0198Y0197     S1      
317P3V3_AUX         VIA   -    MD0100PA00X+048290Y+054873X0200Y    R180 S0      
327P3V3_AUX         R95   -1          A01X+032328Y+055329X0198Y0197R270 S1      
317P3V3_AUX         VIA   -    MD0100PA00X+032078Y+055329X0200Y    R180 S0      
327P3V3_AUX         R57   -2          A01X+024831Y+054271X0198Y0197R180 S1      
317P3V3_AUX         VIA   -    MD0100PA00X+024536Y+054271X0200Y    R180 S0      
327P3V3_AUX         R7    -2          A01X+022158Y+054980X0198Y0197     S1      
317P3V3_AUX         VIA   -    MD0100PA00X+022420Y+054980X0200Y         S0      
327P3V3_AUX         C856  -1   M      A18X+022050Y+054708X0198Y0197R090 S2      
327P3V3_AUX         U8    -5          A18X+021955Y+055189X0240Y0240R180 S2      
317P3V3_AUX         VIA   -    MD0100PA00X+022400Y+054708X0200Y         S0      
327P3V3_AUX         R33   -2   M      A01X+014411Y+055456X0198Y0197R180 S1      
327P3V3_AUX         R31   -2   M      A01X+014411Y+055856X0198Y0197R180 S1      
327P3V3_AUX         R29   -2          A01X+014411Y+056256X0198Y0197R180 S1      
317P3V3_AUX         VIA   -    MD0100PA00X+014202Y+055247X0200Y         S0      
327P3V3_AUX         R853  -1          A01X+002840Y+054873X0198Y0197     S1      
317P3V3_AUX         VIA   -    MD0100PA00X+002582Y+054873X0200Y    R180 S0      
327P3V3_AUX         R363  -2          A01X+168992Y+054191X0198Y0197     S1      
317P3V3_AUX         VIA   -    MD0100PA00X+168992Y+053932X0200Y    R180 S0      
327P3V3_AUX         R260  -2          A01X+123283Y+054191X0198Y0197     S1      
317P3V3_AUX         VIA   -    MD0100PA00X+123283Y+053932X0200Y    R180 S0      
327P3V3_AUX         R158  -2          A01X+077575Y+054191X0198Y0197     S1      
317P3V3_AUX         VIA   -    MD0100PA00X+077575Y+053932X0200Y    R180 S0      
327P3V3_AUX         R56   -2          A01X+031866Y+054191X0198Y0197     S1      
317P3V3_AUX         VIA   -    MD0100PA00X+031866Y+053932X0200Y    R180 S0      
327P3V3_AUX         R2774 -1          A01X+046598Y+051661X0198Y0197R180 S1      
317P3V3_AUX         VIA   -    MD0100PA00X+046856Y+051661X0200Y         S0      
317P3V3_AUX         VIA   -    M      A01X+046885Y+054559X0200Y         S2      
017P3V3_AUX         VIA   -    M      A18X+046885Y+054559X0260Y         S2      
017P3V3_AUX               -    MD0100PA00X+046885Y+054559                       
317P3V3_AUX         VIA   -    MD0100PA00X+044594Y+050645X0200Y    R180 S0      
317P3V3_AUX         VIA   -    MD0100PA00X+044844Y+050645X0200Y    R180 S0      
317P3V3_AUX         VIA   -    MD0100PA00X+045094Y+050645X0200Y    R180 S0      
317P3V3_AUX         VIA   -    MD0100PA00X+044852Y+051970X0200Y    R180 S0      
317P3V3_AUX         VIA   -    MD0100PA00X+044602Y+051970X0200Y    R180 S0      
317P3V3_AUX         VIA   -    MD0100PA00X+044852Y+051151X0200Y    R180 S0      
317P3V3_AUX         VIA   -    MD0100PA00X+044602Y+051151X0200Y    R180 S0      
317P3V3_AUX         VIA   -    MD0100PA00X+045501Y+054971X0200Y         S0      
317P3V3_AUX         VIA   -    MD0100PA00X+045501Y+054691X0200Y         S0      
317P3V3_AUX         VIA   -    MD0100PA00X+045501Y+054431X0200Y         S0      
317P3V3_AUX         VIA   -    MD0100PA00X+045501Y+055231X0200Y         S0      
317P3V3_AUX         VIA   -    MD0100PA00X+045501Y+055491X0200Y         S0      
317P3V3_AUX         VIA   -    MD0100PA00X+044300Y+055249X0200Y         S0      
317P3V3_AUX         VIA   -    MD0100PA00X+045240Y+055499X0200Y         S0      
317P3V3_AUX         VIA   -    MD0100PA00X+045240Y+055239X0200Y         S0      
317P3V3_AUX         VIA   -    MD0100PA00X+044300Y+055509X0200Y         S0      
317P3V3_AUX         VIA   -    MD0100PA00X+045240Y+054439X0200Y         S0      
317P3V3_AUX         VIA   -    MD0100PA00X+045240Y+054699X0200Y         S0      
317P3V3_AUX         VIA   -    MD0100PA00X+044300Y+054989X0200Y         S0      
317P3V3_AUX         VIA   -    MD0100PA00X+045240Y+054979X0200Y         S0      
317P3V3_AUX         VIA   -    MD0100PA00X+043138Y+054999X0200Y         S0      
317P3V3_AUX         VIA   -    MD0100PA00X+043138Y+054699X0200Y         S0      
317P3V3_AUX         VIA   -    MD0100PA00X+043138Y+054439X0200Y         S0      
317P3V3_AUX         VIA   -    MD0100PA00X+043138Y+055519X0200Y         S0      
317P3V3_AUX         VIA   -    MD0100PA00X+043138Y+055259X0200Y         S0      
317P3V3_AUX         VIA   -    MD0100PA00X+042874Y+055259X0200Y         S0      
317P3V3_AUX         VIA   -    MD0100PA00X+042874Y+055519X0200Y         S0      
317P3V3_AUX         VIA   -    MD0100PA00X+042874Y+054439X0200Y         S0      
317P3V3_AUX         VIA   -    MD0100PA00X+042874Y+054699X0200Y         S0      
317P3V3_AUX         VIA   -    MD0100PA00X+044280Y+054439X0200Y         S0      
317P3V3_AUX         VIA   -    MD0100PA00X+044280Y+054699X0200Y         S0      
317P3V3_AUX         VIA   -    MD0100PA00X+042874Y+054999X0200Y         S0      
317P3V3_AUX         VIA   -    MD0100PA00X+041934Y+055519X0200Y         S0      
317P3V3_AUX         VIA   -    MD0100PA00X+041934Y+055259X0200Y         S0      
317P3V3_AUX         VIA   -    MD0100PA00X+041914Y+054479X0200Y         S0      
317P3V3_AUX         VIA   -    MD0100PA00X+041914Y+054739X0200Y         S0      
317P3V3_AUX         VIA   -    MD0100PA00X+041934Y+054999X0200Y         S0      
327P3V3_AUX         PC33  -1          A18X+042375Y+054508X0400Y0500R270 S2      
327P3V3_AUX         PC34  -1          A18X+043580Y+054509X0400Y0500R270 S2      
327P3V3_AUX         PC35  -1          A18X+044761Y+054508X0400Y0500R270 S2      
327P3V3_AUX         PC32  -1          A18X+045910Y+054499X0400Y0500R270 S2      
327P3V3_AUX         PC299 -2          A01X+044709Y+051554X0400Y0500R180 S1      
327P3V3_AUX         PC298 -1          A01X+044602Y+050900X0198Y0197R180 S1      
327P3V3_AUX         PC37  -1          A01X+042404Y+054975X0630Y1190     S1      
327P3V3_AUX         PC38  -1          A01X+044770Y+054975X0630Y1190     S1      
327P3V3_AUX         PC36  -1   M      A01X+046884Y+054317X0198Y0197R270 S1      
327P3V3_AUX         PJ3   -2          A01X+045429Y+062589X0180Y0200R090 S1      
327P3V3_AUX         PL4   -2          A01X+043600Y+056606X1300Y1692R270 S1      
317P3V3_AUX         VIA   -    MD0100PA00X+142638Y+047612X0200Y    R180 S0      
317P3V3_AUX         VIA   -    MD0100PA00X+142500Y+048514X0200Y         S0      
317P3V3_AUX         VIA   -    MD0100PA00X+142750Y+048514X0200Y         S0      
317P3V3_AUX         VIA   -    MD0100PA00X+142808Y+048242X0200Y    R180 S0      
317P3V3_AUX         VIA   -    MD0100PA00X+142638Y+047862X0200Y    R180 S0      
317P3V3_AUX         VIA   -    MD0100PA00X+141965Y+048513X0200Y    R180 S0      
317P3V3_AUX         VIA   -    MD0100PA00X+142250Y+048514X0200Y         S0      
327P3V3_AUX         PC475 -2          A01X+143046Y+047799X0400Y0500     S1      
327P3V3_AUX         PC462 -1          A01X+143149Y+048339X0198Y0197     S1      
317P3V3_AUX         VIA   -    MD0100PA00X+096791Y+048514X0200Y         S0      
317P3V3_AUX         VIA   -    MD0100PA00X+097041Y+048514X0200Y         S0      
317P3V3_AUX         VIA   -    MD0100PA00X+097100Y+048242X0200Y    R180 S0      
317P3V3_AUX         VIA   -    MD0100PA00X+096930Y+047582X0200Y    R180 S0      
317P3V3_AUX         VIA   -    MD0100PA00X+096930Y+047862X0200Y    R180 S0      
317P3V3_AUX         VIA   -    MD0100PA00X+096541Y+048514X0200Y         S0      
317P3V3_AUX         VIA   -    MD0100PA00X+096256Y+048513X0200Y    R180 S0      
327P3V3_AUX         PC449 -2          A01X+097338Y+047799X0400Y0500     S1      
327P3V3_AUX         PC474 -1          A01X+097440Y+048339X0198Y0197     S1      
317P3V3_AUX         VIA   -    MD0100PA00X+092100Y+047795X0200Y    R270 S0      
327P3V3_AUX         R947  -1          A01X+092100Y+047552X0198Y0197R270 S1      
317P3V3_AUX         VIA   -    MD0100PA00X+092900Y+047795X0200Y    R270 S0      
327P3V3_AUX         PR6896-2          A01X+092900Y+047552X0198Y0197R090 S1      
317P3V3_AUX         VIA   -    MD0100PA00X+086147Y+048330X0200Y    R270 S0      
327P3V3_AUX         R5957 -1          A01X+086388Y+048330X0198Y0197     S1      
317P3V3_AUX         VIA   -    MD0100PA00X+083422Y+048414X0200Y         S0      
317P3V3_AUX         VIA   -    MD0100PA00X+083392Y+048058X0200Y    R180 S0      
317P3V3_AUX         VIA   -    MD0100PA00X+083106Y+048404X0200Y         S0      
317P3V3_AUX         VIA   -    MD0100PA00X+083142Y+048058X0200Y    R180 S0      
317P3V3_AUX         VIA   -    MD0100PA00X+082892Y+048058X0200Y    R180 S0      
327P3V3_AUX         PC448 -1          A01X+082856Y+048382X0198Y0197R180 S1      
317P3V3_AUX         VIA   -    MD0100PA00X+083329Y+048784X0200Y         S0      
317P3V3_AUX         VIA   -    MD0100PA00X+083329Y+049064X0200Y         S0      
327P3V3_AUX         PC485 -2          A01X+082959Y+048922X0400Y0500R180 S1      
317P3V3_AUX         VIA   -    MD0100PA00X+005512Y+047582X0200Y    R180 S0      
317P3V3_AUX         VIA   -    MD0100PA00X+005682Y+048242X0200Y    R180 S0      
317P3V3_AUX         VIA   -    MD0100PA00X+005624Y+048514X0200Y         S0      
317P3V3_AUX         VIA   -    MD0100PA00X+005374Y+048514X0200Y         S0      
317P3V3_AUX         VIA   -    MD0100PA00X+005512Y+047862X0200Y    R180 S0      
317P3V3_AUX         VIA   -    MD0100PA00X+005124Y+048514X0200Y         S0      
317P3V3_AUX         VIA   -    MD0100PA00X+004839Y+048513X0200Y    R180 S0      
327P3V3_AUX         PC451 -2          A01X+005920Y+047799X0400Y0500     S1      
327P3V3_AUX         PC450 -1          A01X+006023Y+048339X0198Y0197     S1      
317P3V3_AUX         VIA   -    MD0100PA00X+179693Y+046161X0200Y    R270 S0      
327P3V3_AUX         R959  -1          A01X+179693Y+045918X0198Y0197R270 S1      
317P3V3_AUX         VIA   -    MD0100PA00X+180493Y+046161X0200Y    R270 S0      
327P3V3_AUX         PR7058-2          A01X+180493Y+045918X0198Y0197R090 S1      
317P3V3_AUX         VIA   -    MD0100PA00X+176859Y+046756X0200Y    R270 S0      
317P3V3_AUX         VIA   -    MD0100PA00X+174809Y+048558X0200Y    R180 S0      
317P3V3_AUX         VIA   -    MD0100PA00X+174559Y+048558X0200Y    R180 S0      
317P3V3_AUX         VIA   -    MD0100PA00X+174309Y+048558X0200Y    R180 S0      
317P3V3_AUX         VIA   -    MD0100PA00X+174481Y+047000X0200Y    R180 S0      
317P3V3_AUX         VIA   -    MD0100PA00X+174731Y+047000X0200Y    R180 S0      
317P3V3_AUX         VIA   -    MD0100PA00X+174523Y+048904X0200Y         S0      
317P3V3_AUX         VIA   -    MD0100PA00X+174747Y+049564X0200Y         S0      
317P3V3_AUX         VIA   -    MD0100PA00X+174747Y+049284X0200Y         S0      
327P3V3_AUX         PC472 -1          A01X+174274Y+048882X0198Y0197R180 S1      
327P3V3_AUX         PC473 -2          A01X+174376Y+049422X0400Y0500R180 S1      
317P3V3_AUX         VIA   -    MD0100PA00X+164713Y+046348X0200Y         S0      
327P3V3_AUX         U43   -5          A18X+164685Y+045871X0240Y0240R270 S2      
327P3V3_AUX         C961  -1   M      A18X+164450Y+046348X0198Y0197     S2      
317P3V3_AUX         VIA   -    MD0100PA00X+159144Y+046533X0200Y         S0      
327P3V3_AUX         R311  -2          A01X+159264Y+046280X0198Y0197     S1      
317P3V3_AUX         VIA   -    MD0100PA00X+151878Y+046360X0200Y         S0      
327P3V3_AUX         R313  -2          A01X+152228Y+046360X0198Y0197R180 S1      
317P3V3_AUX         VIA   -    MD0100PA00X+141490Y+046990X0200Y    R180 S0      
327P3V3_AUX         R6044 -1          A01X+141490Y+046749X0198Y0197R270 S1      
317P3V3_AUX         VIA   -    MD0100PA00X+133985Y+046161X0200Y    R270 S0      
327P3V3_AUX         R953  -1          A01X+133985Y+045918X0198Y0197R270 S1      
317P3V3_AUX         VIA   -    MD0100PA00X+134785Y+046161X0200Y    R270 S0      
327P3V3_AUX         PR7035-2          A01X+134785Y+045918X0198Y0197R090 S1      
317P3V3_AUX         VIA   -    MD0100PA00X+131149Y+047156X0200Y    R270 S0      
327P3V3_AUX         R6033 -1          A01X+131390Y+047156X0198Y0197     S1      
317P3V3_AUX         VIA   -    MD0100PA00X+128850Y+048558X0200Y    R180 S0      
317P3V3_AUX         VIA   -    MD0100PA00X+129100Y+048558X0200Y    R180 S0      
317P3V3_AUX         VIA   -    MD0100PA00X+128600Y+048558X0200Y    R180 S0      
317P3V3_AUX         VIA   -    MD0100PA00X+129022Y+047000X0200Y    R180 S0      
317P3V3_AUX         VIA   -    MD0100PA00X+128772Y+047000X0200Y    R180 S0      
317P3V3_AUX         VIA   -    MD0100PA00X+128814Y+048904X0200Y         S0      
317P3V3_AUX         VIA   -    MD0100PA00X+129038Y+049284X0200Y         S0      
317P3V3_AUX         VIA   -    MD0100PA00X+129038Y+049564X0200Y         S0      
327P3V3_AUX         PC486 -1          A01X+128565Y+048882X0198Y0197R180 S1      
327P3V3_AUX         PC487 -2          A01X+128667Y+049422X0400Y0500R180 S1      
317P3V3_AUX         VIA   -    MD0100PA00X+119005Y+046348X0200Y         S0      
327P3V3_AUX         C421  -1   M      A18X+118742Y+046348X0198Y0197     S2      
327P3V3_AUX         U33   -5          A18X+118976Y+045871X0240Y0240R270 S2      
317P3V3_AUX         VIA   -    MD0100PA00X+113463Y+046555X0200Y         S0      
327P3V3_AUX         R210  -2          A01X+113555Y+046280X0198Y0197     S1      
317P3V3_AUX         VIA   -    MD0100PA00X+106169Y+046360X0200Y         S0      
327P3V3_AUX         R209  -2          A01X+106520Y+046360X0198Y0197R180 S1      
317P3V3_AUX         VIA   -    MD0100PA00X+095982Y+047290X0200Y    R180 S0      
327P3V3_AUX         R6032 -1          A01X+095982Y+047049X0198Y0197R270 S1      
317P3V3_AUX         VIA   -    MD0100PA00X+073296Y+046348X0200Y         S0      
327P3V3_AUX         U23   -5          A18X+073267Y+045871X0240Y0240R270 S2      
327P3V3_AUX         C887  -1   M      A18X+073033Y+046348X0198Y0197     S2      
317P3V3_AUX         VIA   -    MD0100PA00X+067524Y+046561X0200Y         S0      
327P3V3_AUX         R107  -2          A01X+067846Y+046280X0198Y0197     S1      
317P3V3_AUX         VIA   -    MD0100PA00X+060461Y+046360X0200Y         S0      
327P3V3_AUX         R108  -2          A01X+060811Y+046360X0198Y0197R180 S1      
317P3V3_AUX         VIA   -    MD0100PA00X+051082Y+048514X0200Y         S0      
317P3V3_AUX         VIA   -    MD0100PA00X+051332Y+048514X0200Y         S0      
317P3V3_AUX         VIA   -    MD0100PA00X+051391Y+048242X0200Y    R180 S0      
317P3V3_AUX         VIA   -    M      A01X+051221Y+047582X0200Y    R180 S2      
017P3V3_AUX         VIA   -    M      A18X+051221Y+047582X0260Y    R180 S2      
017P3V3_AUX               -    MD0100PA00X+051221Y+047582                       
317P3V3_AUX         VIA   -    MD0100PA00X+051221Y+047862X0200Y    R180 S0      
317P3V3_AUX         VIA   -    MD0100PA00X+050832Y+048514X0200Y         S0      
317P3V3_AUX         VIA   -    MD0100PA00X+050548Y+048513X0200Y    R180 S0      
327P3V3_AUX         PC463 -2          A01X+051629Y+047799X0400Y0500     S1      
327P3V3_AUX         PC484 -1          A01X+051731Y+048339X0198Y0197     S1      
317P3V3_AUX         VIA   -    MD0100PA00X+050073Y+046990X0200Y    R180 S0      
327P3V3_AUX         R5956 -1          A01X+050073Y+046749X0198Y0197R270 S1      
317P3V3_AUX         VIA   -    MD0100PA00X+046213Y+046044X0200Y    R090 S0      
317P3V3_AUX         VIA   -    MD0100PA00X+046513Y+046044X0200Y    R090 S0      
317P3V3_AUX         VIA   -    MD0100PA00X+046785Y+046457X0200Y    R090 S0      
317P3V3_AUX         VIA   -    MD0100PA00X+046485Y+046457X0200Y    R090 S0      
327P3V3_AUX         PC593 -1          A01X+046782Y+046186X0198Y0197     S1      
327P3V3_AUX         PU70  -1_2        A01X+046682Y+046904X0295Y0354R180 S1      
317P3V3_AUX         VIA   -    MD0100PA00X+043367Y+046161X0200Y    R270 S0      
327P3V3_AUX         PR6873-2          A01X+043367Y+045918X0198Y0197R090 S1      
317P3V3_AUX         VIA   -    MD0100PA00X+042567Y+046161X0200Y    R270 S0      
327P3V3_AUX         R904  -1          A01X+042567Y+045918X0198Y0197R270 S1      
317P3V3_AUX         VIA   -    MD0100PA00X+039732Y+047156X0200Y    R270 S0      
327P3V3_AUX         R5857 -1          A01X+039973Y+047156X0198Y0197     S1      
317P3V3_AUX         VIA   -    MD0100PA00X+037683Y+048558X0200Y    R180 S0      
317P3V3_AUX         VIA   -    MD0100PA00X+037433Y+048558X0200Y    R180 S0      
317P3V3_AUX         VIA   -    MD0100PA00X+037183Y+048558X0200Y    R180 S0      
317P3V3_AUX         VIA   -    MD0100PA00X+037605Y+047000X0200Y    R180 S0      
317P3V3_AUX         VIA   -    MD0100PA00X+037355Y+047000X0200Y    R180 S0      
317P3V3_AUX         VIA   -    MD0100PA00X+037397Y+048904X0200Y         S0      
317P3V3_AUX         VIA   -    MD0100PA00X+037621Y+049564X0200Y         S0      
317P3V3_AUX         VIA   -    MD0100PA00X+037621Y+049284X0200Y         S0      
327P3V3_AUX         PC460 -1          A01X+037148Y+048882X0198Y0197R180 S1      
327P3V3_AUX         PC461 -2          A01X+037250Y+049422X0400Y0500R180 S1      
317P3V3_AUX         VIA   -    MD0100PA00X+027587Y+046348X0200Y         S0      
327P3V3_AUX         U13   -5          A18X+027559Y+045871X0240Y0240R270 S2      
327P3V3_AUX         C418  -1   M      A18X+027324Y+046348X0198Y0197     S2      
317P3V3_AUX         VIA   -    MD0100PA00X+022035Y+046562X0200Y         S0      
327P3V3_AUX         R6    -2          A01X+022138Y+046280X0198Y0197     S1      
317P3V3_AUX         VIA   -    MD0100PA00X+014752Y+046360X0200Y         S0      
327P3V3_AUX         R5    -2          A01X+015102Y+046360X0198Y0197R180 S1      
317P3V3_AUX         VIA   -    MD0100PA00X+004564Y+047290X0200Y    R180 S0      
327P3V3_AUX         R5856 -1          A01X+004564Y+047049X0198Y0197R270 S1      
327P3V3_AUX         PU122 -1_2        A01X+173199Y+045457X0295Y0354R180 S1      
327P3V3_AUX         PC908 -1          A01X+173300Y+044736X0198Y0197     S1      
317P3V3_AUX         VIA   -    MD0100PA00X+173040Y+044721X0200Y    R090 S0      
317P3V3_AUX         VIA   -    MD0100PA00X+172740Y+044721X0200Y    R090 S0      
317P3V3_AUX         VIA   -    MD0100PA00X+173001Y+045009X0200Y    R090 S0      
317P3V3_AUX         VIA   -    MD0100PA00X+173301Y+045009X0200Y    R090 S0      
317P3V3_AUX         VIA   -    MD0100PA00X+162160Y+045639X0200Y         S0      
327P3V3_AUX         R364  -2          A01X+162038Y+045886X0198Y0197R180 S1      
317P3V3_AUX         VIA   -    MD0100PA00X+152196Y+045368X0200Y         S0      
327P3V3_AUX         R350  -1          A01X+151766Y+045222X0198Y0197R090 S1      
327P3V3_AUX         PC909 -1          A01X+142420Y+045191X0198Y0197R270 S1      
327P3V3_AUX         PU121 -1_2        A01X+143094Y+045249X0295Y0354R090 S1      
317P3V3_AUX         VIA   -    MD0100PA00X+142593Y+045934X0200Y         S0      
317P3V3_AUX         VIA   -    MD0100PA00X+142343Y+045934X0200Y         S0      
317P3V3_AUX         VIA   -    MD0100PA00X+142593Y+045434X0200Y         S0      
317P3V3_AUX         VIA   -    MD0100PA00X+142343Y+045434X0200Y         S0      
317P3V3_AUX         VIA   -    MD0100PA00X+142593Y+045684X0200Y         S0      
317P3V3_AUX         VIA   -    MD0100PA00X+142343Y+045684X0200Y         S0      
327P3V3_AUX         PU120 -1_2        A01X+127490Y+045457X0295Y0354R180 S1      
327P3V3_AUX         PC898 -1          A01X+127592Y+044736X0198Y0197     S1      
317P3V3_AUX         VIA   -    MD0100PA00X+127040Y+044708X0200Y    R090 S0      
317P3V3_AUX         VIA   -    MD0100PA00X+127340Y+044708X0200Y    R090 S0      
317P3V3_AUX         VIA   -    MD0100PA00X+127593Y+045009X0200Y    R090 S0      
317P3V3_AUX         VIA   -    MD0100PA00X+127293Y+045009X0200Y    R090 S0      
317P3V3_AUX         VIA   -    MD0100PA00X+116840Y+045631X0200Y         S0      
327P3V3_AUX         R262  -2          A01X+116330Y+045886X0198Y0197R180 S1      
317P3V3_AUX         VIA   -    MD0100PA00X+106488Y+045368X0200Y         S0      
327P3V3_AUX         R248  -1          A01X+106057Y+045222X0198Y0197R090 S1      
327P3V3_AUX         PC899 -1          A01X+096911Y+045491X0198Y0197R270 S1      
327P3V3_AUX         PU119 -1_2        A01X+097585Y+045549X0295Y0354R090 S1      
317P3V3_AUX         VIA   -    MD0100PA00X+096834Y+045984X0200Y         S0      
317P3V3_AUX         VIA   -    MD0100PA00X+096834Y+046234X0200Y         S0      
317P3V3_AUX         VIA   -    MD0100PA00X+097084Y+046234X0200Y         S0      
317P3V3_AUX         VIA   -    MD0100PA00X+097084Y+045984X0200Y         S0      
317P3V3_AUX         VIA   -    MD0100PA00X+096834Y+045734X0200Y         S0      
317P3V3_AUX         VIA   -    MD0100PA00X+097084Y+045734X0200Y         S0      
317P3V3_AUX         VIA   -    MD0100PA00X+079417Y+045051X0200Y    R180 S0      
327P3V3_AUX         R186  -2   M      A01X+079170Y+045051X0198Y0197     S1      
327P3V3_AUX         R182  -2          A01X+079170Y+044251X0198Y0197     S1      
327P3V3_AUX         R184  -2   M      A01X+079170Y+044651X0198Y0197     S1      
317P3V3_AUX         VIA   -    MD0100PA00X+071064Y+045634X0200Y         S0      
327P3V3_AUX         R160  -2          A01X+070621Y+045886X0198Y0197R180 S1      
317P3V3_AUX         VIA   -    MD0100PA00X+060779Y+045368X0200Y         S0      
327P3V3_AUX         R146  -1          A01X+060349Y+045222X0198Y0197R090 S1      
327P3V3_AUX         PU101 -1_2        A01X+051676Y+045249X0295Y0354R090 S1      
327P3V3_AUX         PC788 -1          A01X+051002Y+045191X0198Y0197R270 S1      
317P3V3_AUX         VIA   -    MD0100PA00X+051175Y+045934X0200Y         S0      
317P3V3_AUX         VIA   -    MD0100PA00X+050925Y+045934X0200Y         S0      
317P3V3_AUX         VIA   -    MD0100PA00X+050925Y+045434X0200Y         S0      
317P3V3_AUX         VIA   -    MD0100PA00X+050925Y+045684X0200Y         S0      
317P3V3_AUX         VIA   -    MD0100PA00X+051175Y+045684X0200Y         S0      
317P3V3_AUX         VIA   -    MD0100PA00X+051175Y+045434X0200Y         S0      
327P3V3_AUX         PU79  -1_2        A01X+036073Y+045457X0295Y0354R180 S1      
327P3V3_AUX         PC659 -1          A01X+036174Y+044736X0198Y0197     S1      
317P3V3_AUX         VIA   -    MD0100PA00X+035924Y+044700X0200Y    R090 S0      
317P3V3_AUX         VIA   -    MD0100PA00X+035624Y+044700X0200Y    R090 S0      
317P3V3_AUX         VIA   -    MD0100PA00X+035875Y+045009X0200Y    R090 S0      
317P3V3_AUX         VIA   -    MD0100PA00X+036175Y+045009X0200Y    R090 S0      
317P3V3_AUX         VIA   -    MD0100PA00X+025034Y+045639X0200Y         S0      
327P3V3_AUX         R58   -2          A01X+024912Y+045886X0198Y0197R180 S1      
317P3V3_AUX         VIA   -    MD0100PA00X+015070Y+045368X0200Y         S0      
327P3V3_AUX         R44   -1          A01X+014640Y+045222X0198Y0197R090 S1      
327P3V3_AUX         PC658 -1          A01X+005494Y+045491X0198Y0197R270 S1      
327P3V3_AUX         PU80  -1_2        A01X+006168Y+045549X0295Y0354R090 S1      
317P3V3_AUX         VIA   -    MD0100PA00X+005667Y+046234X0200Y         S0      
317P3V3_AUX         VIA   -    MD0100PA00X+005417Y+046234X0200Y         S0      
317P3V3_AUX         VIA   -    MD0100PA00X+005417Y+045984X0200Y         S0      
317P3V3_AUX         VIA   -    MD0100PA00X+005667Y+045984X0200Y         S0      
317P3V3_AUX         VIA   -    MD0100PA00X+005667Y+045734X0200Y         S0      
317P3V3_AUX         VIA   -    MD0100PA00X+005417Y+045734X0200Y         S0      
317P3V3_AUX         VIA   -    MD0100PA00X+081346Y+044147X0200Y    R090 S0      
317P3V3_AUX         VIA   -    MD0100PA00X+081618Y+044144X0200Y    R090 S0      
317P3V3_AUX         VIA   -    MD0100PA00X+081584Y+044409X0200Y    R090 S0      
317P3V3_AUX         VIA   -    M      A01X+081884Y+044409X0200Y    R090 S2      
017P3V3_AUX         VIA   -    M      A18X+081884Y+044409X0260Y    R090 S2      
017P3V3_AUX               -    MD0100PA00X+081884Y+044409                       
327P3V3_AUX         PC789 -1          A01X+081881Y+044139X0198Y0197     S1      
327P3V3_AUX         PU102 -1_2        A01X+081781Y+044857X0295Y0354R180 S1      
317P3V3_AUX         VIA   -    MD0100PA00X+162864Y+042209X0200Y         S0      
327P3V3_AUX         R390  -2          A18X+161219Y+043503X0198Y0197     S2      
327P3V3_AUX         R388  -2   M      A18X+161219Y+043103X0198Y0197     S2      
327P3V3_AUX         R386  -2   M      A18X+161219Y+042703X0198Y0197     S2      
317P3V3_AUX         VIA   -    MD0100PA00X+117144Y+042209X0200Y         S0      
327P3V3_AUX         R288  -2          A18X+115511Y+043503X0198Y0197     S2      
327P3V3_AUX         R286  -2   M      A18X+115511Y+043103X0198Y0197     S2      
327P3V3_AUX         R284  -2   M      A18X+115511Y+042703X0198Y0197     S2      
317P3V3_AUX         VIA   -    MD0100PA00X+049098Y+041234X0200Y         S0      
327P3V3_AUX         R5827 -1          A01X+048848Y+041234X0198Y0197R090 S1      
317P3V3_AUX         VIA   -    MD0100PA00X+025648Y+042209X0200Y         S0      
327P3V3_AUX         R84   -2          A18X+024093Y+043503X0198Y0197     S2      
327P3V3_AUX         R82   -2   M      A18X+024093Y+043103X0198Y0197     S2      
327P3V3_AUX         R80   -2   M      A18X+024093Y+042703X0198Y0197     S2      
317P3V3_AUX         VIA   -    MD0100PA00X+173985Y+040107X0200Y    R270 S0      
327P3V3_AUX         C616  -1   M      A01X+173985Y+040347X0198Y0197R090 S1      
327P3V3_AUX         U86   -9          A01X+173371Y+040004X0090Y0240     S1      
317P3V3_AUX         VIA   -    MD0100PA00X+128276Y+040107X0200Y    R270 S0      
327P3V3_AUX         C622  -1   M      A01X+128276Y+040347X0198Y0197R090 S1      
327P3V3_AUX         U84   -9          A01X+127662Y+040004X0090Y0240     S1      
317P3V3_AUX         VIA   -    MD0100PA00X+086934Y+040763X0200Y    R270 S0      
327P3V3_AUX         U82   -9          A01X+086320Y+040804X0090Y0240     S1      
327P3V3_AUX         C903  -1   M      A01X+086934Y+041147X0198Y0197R090 S1      
317P3V3_AUX         VIA   -    MD0100PA00X+053199Y+039755X0200Y         S0      
327P3V3_AUX         U124  -24         A01X+052387Y+038480X0120Y0630R270 S1      
327P3V3_AUX         C2709 -1   M      A01X+053199Y+039431X0198Y0197     S1      
317P3V3_AUX         VIA   -    MD0100PA00X+036859Y+040107X0200Y    R270 S0      
327P3V3_AUX         C871  -1   M      A01X+036859Y+040347X0198Y0197R090 S1      
327P3V3_AUX         U80   -9          A01X+036245Y+040004X0090Y0240     S1      
317P3V3_AUX         VIA   -    MD0100PA00X+173375Y+038512X0200Y    R270 S0      
327P3V3_AUX         R746  -1          A01X+173375Y+038272X0198Y0197R270 S1      
317P3V3_AUX         VIA   -    MD0100PA00X+171523Y+038797X0200Y    R270 S0      
327P3V3_AUX         R759  -2          A01X+171375Y+037957X0198Y0197R270 S1      
317P3V3_AUX         VIA   -    MD0100PA00X+151932Y+038260X0200Y         S0      
327P3V3_AUX         R314  -2          A01X+152228Y+038260X0198Y0197R180 S1      
317P3V3_AUX         VIA   -    MD0100PA00X+127666Y+038512X0200Y    R270 S0      
327P3V3_AUX         R735  -1          A01X+127666Y+038272X0198Y0197R270 S1      
317P3V3_AUX         VIA   -    MD0100PA00X+106223Y+038260X0200Y         S0      
327P3V3_AUX         R212  -2          A01X+106520Y+038260X0198Y0197R180 S1      
317P3V3_AUX         VIA   -    MD0100PA00X+093107Y+038699X0200Y    R090 S0      
327P3V3_AUX         R1009 -1          A01X+093107Y+038448X0198Y0197R270 S1      
317P3V3_AUX         VIA   -    MD0100PA00X+091507Y+038699X0200Y    R090 S0      
327P3V3_AUX         R1018 -1          A01X+091507Y+038448X0198Y0197R270 S1      
317P3V3_AUX         VIA   -    MD0100PA00X+091107Y+038699X0200Y    R090 S0      
327P3V3_AUX         R1016 -1          A01X+091107Y+038448X0198Y0197R270 S1      
317P3V3_AUX         VIA   -    MD0100PA00X+087674Y+038312X0200Y    R270 S0      
327P3V3_AUX         R859  -1          A01X+087674Y+038570X0198Y0197R090 S1      
327P3V3_AUX         R110  -2          A01X+060811Y+038260X0198Y0197R180 S1      
317P3V3_AUX         VIA   -    MD0100PA00X+060515Y+038260X0200Y         S0      
317P3V3_AUX         VIA   -    MD0100PA00X+055154Y+038172X0200Y         S0      
327P3V3_AUX         R1559 -1          A01X+054876Y+038172X0198Y0197R180 S1      
317P3V3_AUX         VIA   -    MD0100PA00X+047291Y+037809X0200Y         S0      
327P3V3_AUX         R1552 -1          A01X+047534Y+037809X0198Y0197     S1      
317P3V3_AUX         VIA   -    MD0100PA00X+047291Y+038259X0200Y         S0      
327P3V3_AUX         R1551 -1          A01X+047534Y+038259X0198Y0197     S1      
317P3V3_AUX         VIA   -    MD0100PA00X+047291Y+039159X0200Y         S0      
327P3V3_AUX         R1557 -1          A01X+047534Y+039159X0198Y0197     S1      
317P3V3_AUX         VIA   -    MD0100PA00X+047291Y+038709X0200Y         S0      
327P3V3_AUX         R1558 -1          A01X+047534Y+038709X0198Y0197     S1      
317P3V3_AUX         VIA   -    MD0100PA00X+036249Y+038512X0200Y    R270 S0      
327P3V3_AUX         R691  -1          A01X+036249Y+038272X0198Y0197R270 S1      
317P3V3_AUX         VIA   -    MD0100PA00X+014806Y+038260X0200Y         S0      
327P3V3_AUX         R8    -2          A01X+015102Y+038260X0198Y0197R180 S1      
317P3V3_AUX         VIA   -    MD0100PA00X+174850Y+037106X0200Y         S0      
327P3V3_AUX         R860  -1          A01X+174850Y+037368X0198Y0197R090 S1      
317P3V3_AUX         VIA   -    MD0100PA00X+172175Y+037717X0200Y    R270 S0      
327P3V3_AUX         R760  -2          A01X+172175Y+037957X0198Y0197R270 S1      
317P3V3_AUX         VIA   -    MD0100PA00X+143461Y+036258X0200Y         S0      
327P3V3_AUX         U125  -24         A01X+142641Y+035459X0120Y0630R270 S1      
327P3V3_AUX         C2710 -1   M      A01X+143461Y+035967X0198Y0197     S1      
317P3V3_AUX         VIA   -    MD0100PA00X+129141Y+037106X0200Y         S0      
327P3V3_AUX         R856  -1          A01X+129141Y+037368X0198Y0197R090 S1      
317P3V3_AUX         VIA   -    MD0100PA00X+126794Y+037177X0200Y    R270 S0      
327P3V3_AUX         R736  -2          A01X+125666Y+037957X0198Y0197R270 S1      
317P3V3_AUX         VIA   -    MD0100PA00X+126466Y+037717X0200Y    R270 S0      
327P3V3_AUX         R737  -2          A01X+126466Y+037957X0198Y0197R270 S1      
317P3V3_AUX         VIA   -    MD0100PA00X+092994Y+037260X0200Y    R090 S0      
327P3V3_AUX         R1006 -1          A18X+092636Y+037174X0198Y0197     S2      
317P3V3_AUX         VIA   -    MD0100PA00X+089659Y+037437X0200Y    R090 S0      
327P3V3_AUX         R5440 -1          A01X+089918Y+037437X0198Y0197     S1      
317P3V3_AUX         VIA   -    MD0100PA00X+086309Y+037450X0200Y         S0      
327P3V3_AUX         R713  -1          A01X+086309Y+037692X0198Y0197R090 S1      
317P3V3_AUX         VIA   -    MD0100PA00X+085859Y+037450X0200Y         S0      
327P3V3_AUX         R715  -2          A01X+085859Y+037692X0198Y0197R270 S1      
317P3V3_AUX         VIA   -    MD0100PA00X+085409Y+037450X0200Y         S0      
327P3V3_AUX         R714  -2          A01X+085409Y+037692X0198Y0197R270 S1      
317P3V3_AUX         VIA   -    MD0100PA00X+055154Y+036372X0200Y         S0      
327P3V3_AUX         R1569 -1          A01X+054876Y+036372X0198Y0197R180 S1      
317P3V3_AUX         VIA   -    MD0100PA00X+055154Y+036822X0200Y         S0      
327P3V3_AUX         R1570 -1          A01X+054876Y+036822X0198Y0197R180 S1      
317P3V3_AUX         VIA   -    MD0100PA00X+055154Y+037272X0200Y         S0      
327P3V3_AUX         R1571 -1          A01X+054876Y+037272X0198Y0197R180 S1      
317P3V3_AUX         VIA   -    MD0100PA00X+055154Y+037722X0200Y         S0      
327P3V3_AUX         R1572 -1          A01X+054876Y+037722X0198Y0197R180 S1      
317P3V3_AUX         VIA   -    MD0100PA00X+047291Y+037359X0200Y         S0      
327P3V3_AUX         R1553 -1          A01X+047534Y+037359X0198Y0197     S1      
317P3V3_AUX         VIA   -    MD0100PA00X+047291Y+036909X0200Y         S0      
327P3V3_AUX         R1554 -1          A01X+047534Y+036909X0198Y0197     S1      
317P3V3_AUX         VIA   -    MD0100PA00X+037724Y+037106X0200Y         S0      
327P3V3_AUX         R855  -1          A01X+037724Y+037368X0198Y0197R090 S1      
317P3V3_AUX         VIA   -    MD0100PA00X+035049Y+037717X0200Y    R270 S0      
327P3V3_AUX         R694  -2          A01X+035049Y+037957X0198Y0197R270 S1      
317P3V3_AUX         VIA   -    MD0100PA00X+035114Y+037233X0200Y    R270 S0      
327P3V3_AUX         R692  -2          A01X+034249Y+037957X0198Y0197R270 S1      
317P3V3_AUX         VIA   -    MD0100PA00X+168859Y+035347X0200Y         S0      
327P3V3_AUX         U45   -5          A01X+168321Y+034744X0160Y0360R270 S1      
327P3V3_AUX         C963  -1   M      A01X+168859Y+035085X0198Y0197     S1      
317P3V3_AUX         VIA   -    MD0100PA00X+156388Y+035236X0200Y         S0      
327P3V3_AUX         R1751 -1          A01X+156145Y+035236X0198Y0197R180 S1      
317P3V3_AUX         VIA   -    MD0100PA00X+153813Y+035455X0200Y         S0      
327P3V3_AUX         U142  -24         A01X+152850Y+035192X0120Y0630R270 S1      
327P3V3_AUX         C2743 -1   M      A01X+153813Y+035205X0198Y0197     S1      
317P3V3_AUX         VIA   -    MD0100PA00X+147755Y+035420X0200Y         S0      
327P3V3_AUX         R1750 -1          A01X+147997Y+035420X0198Y0197     S1      
317P3V3_AUX         VIA   -    MD0100PA00X+147755Y+034970X0200Y         S0      
327P3V3_AUX         R1743 -1          A01X+147997Y+034970X0198Y0197     S1      
317P3V3_AUX         VIA   -    MD0100PA00X+147755Y+035870X0200Y         S0      
327P3V3_AUX         R1749 -1          A01X+147997Y+035870X0198Y0197     S1      
317P3V3_AUX         VIA   -    MD0100PA00X+145906Y+035236X0200Y    R180 S0      
327P3V3_AUX         R1612 -1          A01X+145628Y+035236X0198Y0197R180 S1      
317P3V3_AUX         VIA   -    MD0100PA00X+145906Y+034786X0200Y    R180 S0      
327P3V3_AUX         R1611 -1          A01X+145628Y+034786X0198Y0197R180 S1      
317P3V3_AUX         VIA   -    MD0100PA00X+144906Y+035686X0200Y    R180 S0      
327P3V3_AUX         R1599 -1          A01X+144628Y+035686X0198Y0197R180 S1      
327P3V3_AUX         R1592 -1          A01X+137788Y+034787X0198Y0197     S1      
327P3V3_AUX         R1591 -1          A01X+137788Y+035237X0198Y0197     S1      
327P3V3_AUX         R1593 -1          A01X+137788Y+034337X0198Y0197     S1      
327P3V3_AUX         R1594 -1          A01X+137788Y+033887X0198Y0197     S1      
327P3V3_AUX         R1595 -1          A01X+137788Y+033437X0198Y0197     S1      
327P3V3_AUX         R1596 -1          A01X+137788Y+032987X0198Y0197     S1      
327P3V3_AUX         R1601 -1          A01X+137788Y+032087X0198Y0197     S1      
327P3V3_AUX         R1600 -1          A01X+137788Y+032537X0198Y0197     S1      
317P3V3_AUX         VIA   -    MD0100PA00X+137507Y+036137X0200Y    R180 S0      
317P3V3_AUX         VIA   -    MD0100PA00X+137507Y+035687X0200Y    R180 S0      
327P3V3_AUX         R1598 -1   M      A01X+137788Y+035687X0198Y0197     S1      
327P3V3_AUX         R1597 -1   M      A01X+137788Y+036137X0198Y0197     S1      
317P3V3_AUX         VIA   -    MD0100PA00X+123151Y+035347X0200Y         S0      
327P3V3_AUX         C932  -1   M      A01X+123151Y+035085X0198Y0197     S1      
327P3V3_AUX         U35   -5          A01X+122612Y+034744X0160Y0360R270 S1      
317P3V3_AUX         VIA   -    MD0100PA00X+089659Y+035437X0200Y    R090 S0      
327P3V3_AUX         R1012 -1          A01X+089918Y+035437X0198Y0197     S1      
317P3V3_AUX         VIA   -    MD0100PA00X+089659Y+035837X0200Y    R090 S0      
327P3V3_AUX         R1014 -1          A01X+089918Y+035837X0198Y0197     S1      
317P3V3_AUX         VIA   -    MD0100PA00X+079714Y+035037X0200Y         S0      
327P3V3_AUX         R4261 -1          A01X+080390Y+034637X0198Y0197     S1      
327P3V3_AUX         R4359 -1          A01X+081190Y+035474X0198Y0197     S1      
317P3V3_AUX         VIA   -    MD0100PA00X+077442Y+035347X0200Y         S0      
327P3V3_AUX         C902  -1   M      A01X+077442Y+035085X0198Y0197     S1      
327P3V3_AUX         U25   -5          A01X+076903Y+034744X0160Y0360R270 S1      
317P3V3_AUX         VIA   -    MD0100PA00X+055154Y+034572X0200Y         S0      
327P3V3_AUX         R1562 -1          A01X+054876Y+034572X0198Y0197R180 S1      
317P3V3_AUX         VIA   -    MD0100PA00X+055154Y+035022X0200Y         S0      
327P3V3_AUX         R1563 -1          A01X+054876Y+035022X0198Y0197R180 S1      
317P3V3_AUX         VIA   -    MD0100PA00X+055154Y+035472X0200Y         S0      
327P3V3_AUX         R1564 -1          A01X+054876Y+035472X0198Y0197R180 S1      
317P3V3_AUX         VIA   -    MD0100PA00X+055154Y+035922X0200Y         S0      
327P3V3_AUX         R1565 -1          A01X+054876Y+035922X0198Y0197R180 S1      
317P3V3_AUX         VIA   -    MD0100PA00X+047261Y+035250X0200Y         S0      
327P3V3_AUX         R1560 -1          A01X+047523Y+035250X0198Y0197     S1      
317P3V3_AUX         VIA   -    MD0100PA00X+047291Y+036009X0200Y         S0      
327P3V3_AUX         R1555 -1          A01X+047534Y+036459X0198Y0197     S1      
327P3V3_AUX         R1556 -1   M      A01X+047534Y+036009X0198Y0197     S1      
317P3V3_AUX         VIA   -    MD0100PA00X+047281Y+034800X0200Y         S0      
327P3V3_AUX         R1561 -1          A01X+047523Y+034800X0198Y0197     S1      
317P3V3_AUX         VIA   -    MD0100PA00X+031733Y+035347X0200Y         S0      
327P3V3_AUX         U15   -5          A01X+031195Y+034744X0160Y0360R270 S1      
327P3V3_AUX         C873  -1   M      A01X+031733Y+035085X0198Y0197     S1      
317P3V3_AUX         VIA   -    MD0100PA00X+156388Y+033436X0200Y         S0      
327P3V3_AUX         R1760 -1          A01X+156145Y+033436X0198Y0197R180 S1      
317P3V3_AUX         VIA   -    MD0100PA00X+156388Y+034336X0200Y         S0      
327P3V3_AUX         R1763 -1          A01X+156145Y+034336X0198Y0197R180 S1      
317P3V3_AUX         VIA   -    MD0100PA00X+156388Y+032986X0200Y         S0      
327P3V3_AUX         R1757 -1          A01X+156145Y+032986X0198Y0197R180 S1      
317P3V3_AUX         VIA   -    MD0100PA00X+157478Y+033355X0200Y         S0      
327P3V3_AUX         U421  -8          A01X+158244Y+033546X0240Y0460R270 S1      
327P3V3_AUX         C3994 -2   M      A01X+157478Y+033620X0198Y0197     S1      
317P3V3_AUX         VIA   -    MD0100PA00X+157162Y+034413X0200Y         S0      
327P3V3_AUX         R6265 -2          A01X+157162Y+034160X0198Y0197R180 S1      
317P3V3_AUX         VIA   -    MD0100PA00X+147755Y+033170X0200Y         S0      
327P3V3_AUX         R1747 -1          A01X+147997Y+033170X0198Y0197     S1      
317P3V3_AUX         VIA   -    MD0100PA00X+147755Y+034070X0200Y         S0      
327P3V3_AUX         R1745 -1          A01X+147997Y+034070X0198Y0197     S1      
317P3V3_AUX         VIA   -    MD0100PA00X+147755Y+034520X0200Y         S0      
327P3V3_AUX         R1744 -1          A01X+147997Y+034520X0198Y0197     S1      
317P3V3_AUX         VIA   -    MD0100PA00X+145906Y+033436X0200Y    R180 S0      
327P3V3_AUX         R1605 -1          A01X+145628Y+033436X0198Y0197R180 S1      
317P3V3_AUX         VIA   -    MD0100PA00X+145906Y+034336X0200Y    R180 S0      
327P3V3_AUX         R1610 -1          A01X+145628Y+034336X0198Y0197R180 S1      
317P3V3_AUX         VIA   -    MD0100PA00X+145906Y+033886X0200Y    R180 S0      
327P3V3_AUX         R1606 -1          A01X+145628Y+033886X0198Y0197R180 S1      
317P3V3_AUX         VIA   -    MD0100PA00X+145906Y+032986X0200Y    R180 S0      
327P3V3_AUX         R1604 -1          A01X+145628Y+032986X0198Y0197R180 S1      
317P3V3_AUX         VIA   -    MD0100PA00X+125700Y+033350X0200Y         S0      
327P3V3_AUX         R6258 -2          A01X+125792Y+033600X0198Y0197R180 S1      
317P3V3_AUX         VIA   -    MD0100PA00X+121578Y+033107X0200Y    R270 S0      
327P3V3_AUX         U36   -5          A01X+122480Y+032884X0220Y0530R090 S1      
327P3V3_AUX         C931  -1   M      A01X+121872Y+032887X0198Y0197R090 S1      
317P3V3_AUX         VIA   -    MD0100PA00X+117976Y+033638X0200Y         S0      
327P3V3_AUX         U7    -8          A01X+117171Y+033915X0220Y0680R270 S1      
327P3V3_AUX         C198  -1   M      A01X+117976Y+033910X0198Y0197     S1      
317P3V3_AUX         VIA   -    MD0100PA00X+111500Y+033900X0200Y         S0      
327P3V3_AUX         R484  -2          A01X+111742Y+033900X0198Y0197R180 S1      
317P3V3_AUX         VIA   -    MD0100PA00X+111500Y+033400X0200Y         S0      
327P3V3_AUX         R485  -2          A01X+111742Y+033400X0198Y0197R180 S1      
317P3V3_AUX         VIA   -    M      A01X+088595Y+033337X0200Y         S2      
017P3V3_AUX         VIA   -    M      A18X+088595Y+033337X0260Y         S2      
017P3V3_AUX               -    MD0100PA00X+088595Y+033337                       
327P3V3_AUX         R4260 -1          A01X+088355Y+033734X0198Y0197R180 S1      
327P3V3_AUX         R4353 -1   M      A01X+088355Y+033337X0198Y0197R180 S1      
317P3V3_AUX         VIA   -    MD0100PA00X+088595Y+032937X0200Y         S0      
327P3V3_AUX         R4352 -1          A01X+088355Y+032937X0198Y0197R180 S1      
317P3V3_AUX         VIA   -    MD0100PA00X+086177Y+034301X0200Y         S0      
327P3V3_AUX         U330  -24         A01X+085599Y+033784X0240Y0540R270 S1      
327P3V3_AUX         C2809 -1   M      A01X+086217Y+034045X0198Y0197     S1      
317P3V3_AUX         VIA   -    MD0100PA00X+080003Y+033337X0200Y         S0      
327P3V3_AUX         R4331 -1          A01X+080390Y+032937X0198Y0197     S1      
327P3V3_AUX         R4330 -1   M      A01X+080390Y+033337X0198Y0197     S1      
317P3V3_AUX         VIA   -    MD0100PA00X+080016Y+033737X0200Y         S0      
327P3V3_AUX         R4358 -1          A01X+080390Y+033737X0198Y0197     S1      
327P3V3_AUX         C962  -1   M      A01X+167580Y+032887X0198Y0197R090 S1      
327P3V3_AUX         U46   -5          A01X+168189Y+032884X0220Y0530R090 S1      
317P3V3_AUX         VIA   -    MD0100PA00X+167320Y+032887X0200Y    R270 S0      
317P3V3_AUX         VIA   -    MD0100PA00X+165820Y+031504X0200Y         S0      
327P3V3_AUX         R407  -1          A01X+165820Y+031787X0198Y0197     S1      
317P3V3_AUX         VIA   -    MD0100PA00X+156388Y+031636X0200Y         S0      
327P3V3_AUX         R1754 -1          A01X+156145Y+031636X0198Y0197R180 S1      
317P3V3_AUX         VIA   -    MD0100PA00X+156388Y+032536X0200Y         S0      
327P3V3_AUX         R1756 -1          A01X+156145Y+032536X0198Y0197R180 S1      
317P3V3_AUX         VIA   -    MD0100PA00X+147755Y+032270X0200Y         S0      
327P3V3_AUX         R1752 -1          A01X+147997Y+032270X0198Y0197     S1      
317P3V3_AUX         VIA   -    MD0100PA00X+147755Y+032720X0200Y         S0      
327P3V3_AUX         R1748 -1          A01X+147997Y+032720X0198Y0197     S1      
317P3V3_AUX         VIA   -    MD0100PA00X+145906Y+032536X0200Y    R180 S0      
327P3V3_AUX         R1603 -1          A01X+145628Y+032536X0198Y0197R180 S1      
317P3V3_AUX         VIA   -    MD0100PA00X+145906Y+032086X0200Y    R180 S0      
327P3V3_AUX         R1602 -1          A01X+145628Y+032086X0198Y0197R180 S1      
327P3V3_AUX         R1764 -1          A18X+126066Y+032726X0198Y0197R180 S2      
317P3V3_AUX         VIA   -    MD0100PA00X+126208Y+032408X0200Y         S0      
327P3V3_AUX         U420  -8          A01X+126829Y+032780X0240Y0460R270 S1      
327P3V3_AUX         C3992 -2   M      A01X+126208Y+032700X0198Y0197     S1      
317P3V3_AUX         VIA   -    MD0100PA00X+120111Y+031504X0200Y         S0      
327P3V3_AUX         R305  -1          A01X+120111Y+031787X0198Y0197     S1      
317P3V3_AUX         VIA   -    MD0100PA00X+111500Y+032900X0200Y         S0      
327P3V3_AUX         R486  -2          A01X+111742Y+032900X0198Y0197R180 S1      
317P3V3_AUX         VIA   -    MD0100PA00X+094773Y+031968X0200Y         S0      
327P3V3_AUX         R1002 -2          A01X+094451Y+031674X0198Y0197R180 S1      
317P3V3_AUX         VIA   -    M      A01X+088595Y+032137X0200Y         S2      
017P3V3_AUX         VIA   -    M      A18X+088595Y+032137X0260Y         S2      
017P3V3_AUX               -    MD0100PA00X+088595Y+032137                       
327P3V3_AUX         R4350 -1          A01X+088355Y+032137X0198Y0197R180 S1      
317P3V3_AUX         VIA   -    MD0100PA00X+088599Y+031337X0200Y         S0      
327P3V3_AUX         R4348 -1          A01X+088355Y+031337X0198Y0197R180 S1      
317P3V3_AUX         VIA   -    MD0100PA00X+088595Y+032537X0200Y         S0      
327P3V3_AUX         R4351 -1          A01X+088355Y+032537X0198Y0197R180 S1      
317P3V3_AUX         VIA   -    MD0100PA00X+088599Y+031737X0200Y         S0      
327P3V3_AUX         R4349 -1          A01X+088355Y+031737X0198Y0197R180 S1      
317P3V3_AUX         VIA   -    MD0100PA00X+075903Y+032887X0200Y    R270 S0      
327P3V3_AUX         U26   -5          A01X+076771Y+032884X0220Y0530R090 S1      
327P3V3_AUX         C412  -1   M      A01X+076163Y+032887X0198Y0197R090 S1      
317P3V3_AUX         VIA   -    MD0100PA00X+074105Y+031639X0200Y         S0      
327P3V3_AUX         R203  -1          A01X+074403Y+031787X0198Y0197     S1      
317P3V3_AUX         VIA   -    MD0100PA00X+030194Y+032887X0200Y    R270 S0      
327P3V3_AUX         U16   -5          A01X+031063Y+032884X0220Y0530R090 S1      
327P3V3_AUX         C872  -1   M      A01X+030454Y+032887X0198Y0197R090 S1      
317P3V3_AUX         VIA   -    MD0100PA00X+028694Y+031504X0200Y         S0      
327P3V3_AUX         R101  -1          A01X+028694Y+031787X0198Y0197     S1      
317P3V3_AUX         VIA   -    MD0100PA00X+093073Y+030257X0200Y         S0      
327P3V3_AUX         R1004 -1          A01X+093073Y+030526X0198Y0197R180 S1      
327P3V3_AUX         C2612 -1          A18X+091690Y+031223X0198Y0197R180 S2      
317P3V3_AUX         VIA   -    MD0100PA00X+091306Y+031105X0200Y         S0      
327P3V3_AUX         U110  -9          A01X+091049Y+031105X0070Y0200R270 S1      
317P3V3_AUX         VIA   -    MD0100PA00X+088599Y+030537X0200Y         S0      
327P3V3_AUX         R4346 -1          A01X+088355Y+030537X0198Y0197R180 S1      
317P3V3_AUX         VIA   -    MD0100PA00X+088599Y+030937X0200Y         S0      
327P3V3_AUX         R4347 -1          A01X+088355Y+030937X0198Y0197R180 S1      
317P3V3_AUX         VIA   -    MD0100PA00X+080110Y+032586X0200Y         S0      
317P3V3_AUX         VIA   -    MD0100PA00X+080595Y+030168X0200Y         S0      
327P3V3_AUX         R4334 -1   M      A01X+080390Y+031737X0198Y0197     S1      
327P3V3_AUX         R4337 -1   M      A01X+080390Y+030537X0198Y0197     S1      
327P3V3_AUX         R4335 -1   M      A01X+080390Y+031337X0198Y0197     S1      
327P3V3_AUX         R4336 -1   M      A01X+080390Y+030937X0198Y0197     S1      
327P3V3_AUX         R4332 -1   M      A01X+080390Y+032537X0198Y0197     S1      
327P3V3_AUX         R4333 -1   M      A01X+080390Y+032137X0198Y0197     S1      
317P3V3_AUX         VIA   -    MD0100PA00X+002663Y+029562X0200Y         S0      
327P3V3_AUX         U383  -5          A01X+002616Y+028704X0240Y0240     S1      
327P3V3_AUX         C3667 -1   M      A01X+002663Y+029261X0198Y0197R180 S1      
317P3V3_AUX         VIA   -    MD0100PA00X+089805Y+026939X0200Y         S0      
317P3V3_AUX         VIA   -    MD0100PA00X+095128Y+025058X0200Y    R090 S0      
327P3V3_AUX         R5992 -1          A01X+095128Y+024810X0198Y0197R270 S1      
317P3V3_AUX         VIA   -    MD0100PA00X+002632Y+026208X0200Y         S0      
327P3V3_AUX         R5868 -1          A01X+002384Y+026208X0198Y0197R180 S1      
317P3V3_AUX         VIA   -    MD0100PA00X+170467Y+024208X0200Y         S0      
327P3V3_AUX         R6023 -1          A01X+170219Y+024208X0198Y0197R180 S1      
317P3V3_AUX         VIA   -    MD0100PA00X+160231Y+024208X0200Y         S0      
327P3V3_AUX         R6022 -1          A01X+159983Y+024208X0198Y0197R180 S1      
317P3V3_AUX         VIA   -    MD0100PA00X+149995Y+024208X0200Y         S0      
327P3V3_AUX         R6013 -1          A01X+149747Y+024208X0198Y0197R180 S1      
317P3V3_AUX         VIA   -    MD0100PA00X+139758Y+024208X0200Y         S0      
327P3V3_AUX         R6012 -1          A01X+139510Y+024208X0198Y0197R180 S1      
317P3V3_AUX         VIA   -    MD0100PA00X+124758Y+024208X0200Y         S0      
327P3V3_AUX         R6003 -1          A01X+124510Y+024208X0198Y0197R180 S1      
317P3V3_AUX         VIA   -    MD0100PA00X+114522Y+024208X0200Y         S0      
327P3V3_AUX         R6002 -1          A01X+114274Y+024208X0198Y0197R180 S1      
317P3V3_AUX         VIA   -    MD0100PA00X+104286Y+024208X0200Y         S0      
327P3V3_AUX         R5993 -1          A01X+104038Y+024208X0198Y0197R180 S1      
317P3V3_AUX         VIA   -    MD0100PA00X+079050Y+024208X0200Y         S0      
327P3V3_AUX         R5983 -1          A01X+078802Y+024208X0198Y0197R180 S1      
317P3V3_AUX         VIA   -    MD0100PA00X+068814Y+024208X0200Y         S0      
327P3V3_AUX         R5982 -1          A01X+068566Y+024208X0198Y0197R180 S1      
317P3V3_AUX         VIA   -    MD0100PA00X+058577Y+024208X0200Y         S0      
327P3V3_AUX         R5973 -1          A01X+058329Y+024208X0198Y0197R180 S1      
317P3V3_AUX         VIA   -    MD0100PA00X+048341Y+024208X0200Y         S0      
327P3V3_AUX         R5972 -1          A01X+048093Y+024208X0198Y0197R180 S1      
317P3V3_AUX         VIA   -    MD0100PA00X+033341Y+024208X0200Y         S0      
327P3V3_AUX         R5847 -1          A01X+033093Y+024208X0198Y0197R180 S1      
317P3V3_AUX         VIA   -    MD0100PA00X+023105Y+024208X0200Y         S0      
327P3V3_AUX         R5846 -1          A01X+022857Y+024208X0198Y0197R180 S1      
317P3V3_AUX         VIA   -    MD0100PA00X+012869Y+024208X0200Y         S0      
327P3V3_AUX         R5837 -1          A01X+012621Y+024208X0198Y0197R180 S1      
317P3V3_AUX         VIA   -    MD0100PA00X+002384Y+023930X0200Y         S0      
327P3V3_AUX         R5836 -1          A01X+002384Y+024208X0198Y0197R180 S1      
327P3V3_AUX         PC582 -1          A01X+169617Y+021298X0198Y0197R270 S1      
327P3V3_AUX         PC571 -2          A01X+169077Y+021401X0400Y0500R270 S1      
317P3V3_AUX         VIA   -    MD0100PA00X+169140Y+021808X0200Y    R090 S0      
317P3V3_AUX         VIA   -    MD0100PA00X+168860Y+021808X0200Y    R090 S0      
317P3V3_AUX         VIA   -    MD0100PA00X+169792Y+022197X0200Y    R270 S0      
317P3V3_AUX         VIA   -    MD0100PA00X+169792Y+021947X0200Y    R270 S0      
317P3V3_AUX         VIA   -    MD0100PA00X+169792Y+021697X0200Y    R270 S0      
317P3V3_AUX         VIA   -    MD0100PA00X+169520Y+021638X0200Y    R090 S0      
317P3V3_AUX         VIA   -    MD0100PA00X+169798Y+022632X0200Y    R090 S0      
327P3V3_AUX         PC569 -2          A01X+158841Y+021401X0400Y0500R270 S1      
327P3V3_AUX         PC570 -1          A01X+159381Y+021298X0198Y0197R270 S1      
317P3V3_AUX         VIA   -    MD0100PA00X+158904Y+021808X0200Y    R090 S0      
317P3V3_AUX         VIA   -    MD0100PA00X+159556Y+022197X0200Y    R270 S0      
317P3V3_AUX         VIA   -    MD0100PA00X+159556Y+021947X0200Y    R270 S0      
317P3V3_AUX         VIA   -    MD0100PA00X+159556Y+021697X0200Y    R270 S0      
317P3V3_AUX         VIA   -    MD0100PA00X+159284Y+021638X0200Y    R090 S0      
317P3V3_AUX         VIA   -    MD0100PA00X+159562Y+022632X0200Y    R090 S0      
317P3V3_AUX         VIA   -    MD0100PA00X+158624Y+021808X0200Y    R090 S0      
327P3V3_AUX         PC559 -2          A01X+148604Y+021401X0400Y0500R270 S1      
327P3V3_AUX         PC556 -1          A01X+149144Y+021298X0198Y0197R270 S1      
317P3V3_AUX         VIA   -    MD0100PA00X+148388Y+021808X0200Y    R090 S0      
317P3V3_AUX         VIA   -    MD0100PA00X+148668Y+021808X0200Y    R090 S0      
317P3V3_AUX         VIA   -    MD0100PA00X+149319Y+021947X0200Y    R270 S0      
317P3V3_AUX         VIA   -    MD0100PA00X+149319Y+021697X0200Y    R270 S0      
317P3V3_AUX         VIA   -    MD0100PA00X+149048Y+021638X0200Y    R090 S0      
317P3V3_AUX         VIA   -    MD0100PA00X+149319Y+022197X0200Y    R270 S0      
317P3V3_AUX         VIA   -    MD0100PA00X+149326Y+022632X0200Y    R090 S0      
327P3V3_AUX         PC544 -1          A01X+138908Y+021298X0198Y0197R270 S1      
327P3V3_AUX         PC581 -2          A01X+138368Y+021401X0400Y0500R270 S1      
317P3V3_AUX         VIA   -    M      A01X+138152Y+021808X0200Y    R090 S2      
017P3V3_AUX         VIA   -    M      A18X+138152Y+021808X0260Y    R090 S2      
017P3V3_AUX               -    MD0100PA00X+138152Y+021808                       
317P3V3_AUX         VIA   -    MD0100PA00X+138432Y+021808X0200Y    R090 S0      
317P3V3_AUX         VIA   -    MD0100PA00X+138812Y+021638X0200Y    R090 S0      
317P3V3_AUX         VIA   -    MD0100PA00X+139083Y+022197X0200Y    R270 S0      
317P3V3_AUX         VIA   -    MD0100PA00X+139090Y+022632X0200Y    R090 S0      
317P3V3_AUX         VIA   -    MD0100PA00X+139083Y+021947X0200Y    R270 S0      
317P3V3_AUX         VIA   -    MD0100PA00X+139083Y+021697X0200Y    R270 S0      
327P3V3_AUX         PC546 -1          A01X+123908Y+021298X0198Y0197R270 S1      
327P3V3_AUX         PC583 -2          A01X+123368Y+021401X0400Y0500R270 S1      
317P3V3_AUX         VIA   -    MD0100PA00X+123812Y+021638X0200Y    R090 S0      
317P3V3_AUX         VIA   -    MD0100PA00X+123432Y+021808X0200Y    R090 S0      
317P3V3_AUX         VIA   -    MD0100PA00X+123152Y+021808X0200Y    R090 S0      
317P3V3_AUX         VIA   -    MD0100PA00X+124083Y+021697X0200Y    R270 S0      
317P3V3_AUX         VIA   -    MD0100PA00X+124083Y+021947X0200Y    R270 S0      
317P3V3_AUX         VIA   -    MD0100PA00X+124090Y+022632X0200Y    R090 S0      
317P3V3_AUX         VIA   -    MD0100PA00X+124083Y+022197X0200Y    R270 S0      
327P3V3_AUX         PC545 -2          A01X+113132Y+021401X0400Y0500R270 S1      
327P3V3_AUX         PC558 -1          A01X+113672Y+021298X0198Y0197R270 S1      
317P3V3_AUX         VIA   -    MD0100PA00X+113576Y+021638X0200Y    R090 S0      
317P3V3_AUX         VIA   -    MD0100PA00X+113847Y+021697X0200Y    R270 S0      
317P3V3_AUX         VIA   -    MD0100PA00X+113847Y+021947X0200Y    R270 S0      
317P3V3_AUX         VIA   -    MD0100PA00X+113854Y+022632X0200Y    R090 S0      
317P3V3_AUX         VIA   -    MD0100PA00X+113847Y+022197X0200Y    R270 S0      
317P3V3_AUX         VIA   -    MD0100PA00X+113196Y+021808X0200Y    R090 S0      
317P3V3_AUX         VIA   -    MD0100PA00X+112916Y+021808X0200Y    R090 S0      
327P3V3_AUX         PC557 -2          A01X+102896Y+021401X0400Y0500R270 S1      
327P3V3_AUX         PC580 -1          A01X+103436Y+021298X0198Y0197R270 S1      
317P3V3_AUX         VIA   -    MD0100PA00X+102679Y+021808X0200Y    R090 S0      
317P3V3_AUX         VIA   -    MD0100PA00X+103339Y+021638X0200Y    R090 S0      
317P3V3_AUX         VIA   -    MD0100PA00X+103611Y+021697X0200Y    R270 S0      
317P3V3_AUX         VIA   -    MD0100PA00X+103611Y+021947X0200Y    R270 S0      
317P3V3_AUX         VIA   -    MD0100PA00X+103617Y+022632X0200Y    R090 S0      
317P3V3_AUX         VIA   -    MD0100PA00X+103611Y+022197X0200Y    R270 S0      
317P3V3_AUX         VIA   -    MD0100PA00X+102959Y+021808X0200Y    R090 S0      
327P3V3_AUX         PC496 -1          A01X+078200Y+021298X0198Y0197R270 S1      
327P3V3_AUX         PC497 -2          A01X+077660Y+021401X0400Y0500R270 S1      
317P3V3_AUX         VIA   -    MD0100PA00X+078374Y+021947X0200Y    R270 S0      
317P3V3_AUX         VIA   -    MD0100PA00X+078381Y+022632X0200Y    R090 S0      
317P3V3_AUX         VIA   -    MD0100PA00X+078374Y+022197X0200Y    R270 S0      
317P3V3_AUX         VIA   -    MD0100PA00X+078103Y+021638X0200Y    R090 S0      
317P3V3_AUX         VIA   -    MD0100PA00X+078374Y+021697X0200Y    R270 S0      
317P3V3_AUX         VIA   -    MD0100PA00X+077723Y+021808X0200Y    R090 S0      
317P3V3_AUX         VIA   -    M      A01X+077443Y+021808X0200Y    R090 S2      
017P3V3_AUX         VIA   -    M      A18X+077443Y+021808X0260Y    R090 S2      
017P3V3_AUX               -    MD0100PA00X+077443Y+021808                       
327P3V3_AUX         PC511 -2          A01X+067423Y+021401X0400Y0500R270 S1      
327P3V3_AUX         PC522 -1          A01X+067963Y+021298X0198Y0197R270 S1      
317P3V3_AUX         VIA   -    MD0100PA00X+067207Y+021808X0200Y    R090 S0      
317P3V3_AUX         VIA   -    MD0100PA00X+068145Y+022632X0200Y    R090 S0      
317P3V3_AUX         VIA   -    MD0100PA00X+068138Y+022197X0200Y    R270 S0      
317P3V3_AUX         VIA   -    MD0100PA00X+067867Y+021638X0200Y    R090 S0      
317P3V3_AUX         VIA   -    MD0100PA00X+068138Y+021697X0200Y    R270 S0      
317P3V3_AUX         VIA   -    MD0100PA00X+068138Y+021947X0200Y    R270 S0      
317P3V3_AUX         VIA   -    MD0100PA00X+067487Y+021808X0200Y    R090 S0      
327P3V3_AUX         PC532 -1          A01X+057727Y+021298X0198Y0197R270 S1      
327P3V3_AUX         PC521 -2          A01X+057187Y+021401X0400Y0500R270 S1      
317P3V3_AUX         VIA   -    MD0100PA00X+057251Y+021808X0200Y    R090 S0      
317P3V3_AUX         VIA   -    MD0100PA00X+056971Y+021808X0200Y    R090 S0      
317P3V3_AUX         VIA   -    MD0100PA00X+057902Y+022197X0200Y    R270 S0      
317P3V3_AUX         VIA   -    MD0100PA00X+057909Y+022632X0200Y    R090 S0      
317P3V3_AUX         VIA   -    MD0100PA00X+057902Y+021947X0200Y    R270 S0      
317P3V3_AUX         VIA   -    MD0100PA00X+057902Y+021697X0200Y    R270 S0      
317P3V3_AUX         VIA   -    MD0100PA00X+057631Y+021638X0200Y    R090 S0      
327P3V3_AUX         PC533 -2          A01X+046951Y+021401X0400Y0500R270 S1      
327P3V3_AUX         PC508 -1          A01X+047491Y+021298X0198Y0197R270 S1      
317P3V3_AUX         VIA   -    MD0100PA00X+047395Y+021638X0200Y    R090 S0      
317P3V3_AUX         VIA   -    MD0100PA00X+047015Y+021808X0200Y    R090 S0      
317P3V3_AUX         VIA   -    MD0100PA00X+046735Y+021808X0200Y    R090 S0      
317P3V3_AUX         VIA   -    MD0100PA00X+047666Y+022197X0200Y    R270 S0      
317P3V3_AUX         VIA   -    MD0100PA00X+047672Y+022632X0200Y    R090 S0      
317P3V3_AUX         VIA   -    MD0100PA00X+047666Y+021947X0200Y    R270 S0      
317P3V3_AUX         VIA   -    MD0100PA00X+047666Y+021697X0200Y    R270 S0      
327P3V3_AUX         PC499 -2          A01X+031951Y+021401X0400Y0500R270 S1      
327P3V3_AUX         PC498 -1          A01X+032491Y+021298X0198Y0197R270 S1      
317P3V3_AUX         VIA   -    MD0100PA00X+032666Y+022197X0200Y    R270 S0      
317P3V3_AUX         VIA   -    MD0100PA00X+032672Y+022632X0200Y    R090 S0      
317P3V3_AUX         VIA   -    MD0100PA00X+032666Y+021947X0200Y    R270 S0      
317P3V3_AUX         VIA   -    MD0100PA00X+032666Y+021697X0200Y    R270 S0      
317P3V3_AUX         VIA   -    MD0100PA00X+032394Y+021638X0200Y    R090 S0      
317P3V3_AUX         VIA   -    MD0100PA00X+032014Y+021808X0200Y    R090 S0      
317P3V3_AUX         VIA   -    MD0100PA00X+031734Y+021808X0200Y    R090 S0      
327P3V3_AUX         PC523 -2          A01X+021715Y+021401X0400Y0500R270 S1      
327P3V3_AUX         PC534 -1          A01X+022255Y+021298X0198Y0197R270 S1      
317P3V3_AUX         VIA   -    M      A01X+021498Y+021808X0200Y    R090 S2      
017P3V3_AUX         VIA   -    M      A18X+021498Y+021808X0260Y    R090 S2      
017P3V3_AUX               -    MD0100PA00X+021498Y+021808                       
317P3V3_AUX         VIA   -    MD0100PA00X+021778Y+021808X0200Y    R090 S0      
317P3V3_AUX         VIA   -    MD0100PA00X+022158Y+021638X0200Y    R090 S0      
317P3V3_AUX         VIA   -    MD0100PA00X+022430Y+022197X0200Y    R270 S0      
317P3V3_AUX         VIA   -    MD0100PA00X+022430Y+021947X0200Y    R270 S0      
317P3V3_AUX         VIA   -    MD0100PA00X+022430Y+021697X0200Y    R270 S0      
317P3V3_AUX         VIA   -    MD0100PA00X+022436Y+022632X0200Y    R090 S0      
327P3V3_AUX         PC520 -1          A01X+012018Y+021298X0198Y0197R270 S1      
327P3V3_AUX         PC509 -2          A01X+011478Y+021401X0400Y0500R270 S1      
317P3V3_AUX         VIA   -    MD0100PA00X+012193Y+022197X0200Y    R270 S0      
317P3V3_AUX         VIA   -    MD0100PA00X+012193Y+021947X0200Y    R270 S0      
317P3V3_AUX         VIA   -    MD0100PA00X+012193Y+021697X0200Y    R270 S0      
317P3V3_AUX         VIA   -    MD0100PA00X+011922Y+021638X0200Y    R090 S0      
317P3V3_AUX         VIA   -    MD0100PA00X+012200Y+022632X0200Y    R090 S0      
317P3V3_AUX         VIA   -    MD0100PA00X+011542Y+021808X0200Y    R090 S0      
317P3V3_AUX         VIA   -    MD0100PA00X+011262Y+021808X0200Y    R090 S0      
327P3V3_AUX         PC535 -2          A01X+001242Y+021401X0400Y0500R270 S1      
327P3V3_AUX         PC510 -1          A01X+001782Y+021298X0198Y0197R270 S1      
317P3V3_AUX         VIA   -    MD0100PA00X+001957Y+021697X0200Y    R270 S0      
317P3V3_AUX         VIA   -    MD0100PA00X+001686Y+021638X0200Y    R090 S0      
317P3V3_AUX         VIA   -    MD0100PA00X+001964Y+022632X0200Y    R090 S0      
317P3V3_AUX         VIA   -    MD0100PA00X+001306Y+021808X0200Y    R090 S0      
317P3V3_AUX         VIA   -    MD0100PA00X+001026Y+021808X0200Y    R090 S0      
317P3V3_AUX         VIA   -    MD0100PA00X+001957Y+022197X0200Y    R270 S0      
317P3V3_AUX         VIA   -    MD0100PA00X+001957Y+021947X0200Y    R270 S0      
317P3V3_AUX         VIA   -    MD0100PA00X+178592Y+020486X0200Y         S0      
327P3V3_AUX         R877  -1          A01X+178334Y+020486X0198Y0197R180 S1      
327P3V3_AUX         R1755 -1          A01X+179274Y+020072X0198Y0197R180 S1      
317P3V3_AUX         VIA   -    MD0100PA00X+168356Y+020486X0200Y         S0      
327P3V3_AUX         R874  -1          A01X+168098Y+020486X0198Y0197R180 S1      
317P3V3_AUX         VIA   -    MD0100PA00X+158119Y+020486X0200Y         S0      
327P3V3_AUX         R872  -1          A01X+157861Y+020486X0198Y0197R180 S1      
317P3V3_AUX         VIA   -    MD0100PA00X+147883Y+020486X0200Y         S0      
327P3V3_AUX         R870  -1          A01X+147625Y+020486X0198Y0197R180 S1      
317P3V3_AUX         VIA   -    MD0100PA00X+122647Y+020486X0200Y         S0      
327P3V3_AUX         R873  -1          A01X+122389Y+020486X0198Y0197R180 S1      
317P3V3_AUX         VIA   -    MD0100PA00X+112411Y+020486X0200Y         S0      
327P3V3_AUX         R871  -1          A01X+112153Y+020486X0198Y0197R180 S1      
317P3V3_AUX         VIA   -    MD0100PA00X+102174Y+020486X0200Y         S0      
327P3V3_AUX         R869  -1          A01X+101916Y+020486X0198Y0197R180 S1      
327P3V3_AUX         PC568 -1          A01X+093266Y+019815X0198Y0197R270 S1      
327P3V3_AUX         PC547 -2          A01X+092726Y+019918X0400Y0500R270 S1      
317P3V3_AUX         VIA   -    MD0100PA00X+092510Y+020326X0200Y    R090 S0      
317P3V3_AUX         VIA   -    MD0100PA00X+092790Y+020326X0200Y    R090 S0      
317P3V3_AUX         VIA   -    MD0100PA00X+093441Y+020464X0200Y    R270 S0      
317P3V3_AUX         VIA   -    MD0100PA00X+093448Y+021149X0200Y    R090 S0      
317P3V3_AUX         VIA   -    MD0100PA00X+093441Y+020714X0200Y    R270 S0      
317P3V3_AUX         VIA   -    MD0100PA00X+093170Y+020156X0200Y    R090 S0      
317P3V3_AUX         VIA   -    MD0100PA00X+093441Y+020214X0200Y    R270 S0      
317P3V3_AUX         VIA   -    MD0100PA00X+076938Y+020486X0200Y         S0      
327P3V3_AUX         R866  -1          A01X+076680Y+020486X0198Y0197R180 S1      
317P3V3_AUX         VIA   -    MD0100PA00X+066702Y+020486X0200Y         S0      
327P3V3_AUX         R864  -1          A01X+066444Y+020486X0198Y0197R180 S1      
317P3V3_AUX         VIA   -    MD0100PA00X+056466Y+020486X0200Y         S0      
327P3V3_AUX         R862  -1          A01X+056208Y+020486X0198Y0197R180 S1      
317P3V3_AUX         VIA   -    MD0100PA00X+031230Y+020486X0200Y         S0      
327P3V3_AUX         R865  -1          A01X+030972Y+020486X0198Y0197R180 S1      
317P3V3_AUX         VIA   -    MD0100PA00X+020993Y+020486X0200Y         S0      
327P3V3_AUX         R863  -1          A01X+020735Y+020486X0198Y0197R180 S1      
317P3V3_AUX         VIA   -    MD0100PA00X+010757Y+020486X0200Y         S0      
327P3V3_AUX         R861  -1          A01X+010499Y+020486X0198Y0197R180 S1      
317P3V3_AUX         VIA   -    MD0100PA00X+177798Y+018663X0200Y         S0      
327P3V3_AUX         R669  -1          A01X+178009Y+018866X0198Y0197     S1      
317P3V3_AUX         VIA   -    MD0100PA00X+176319Y+019194X0200Y         S0      
327P3V3_AUX         U78   -9          A01X+176278Y+018580X0090Y0240R090 S1      
327P3V3_AUX         C339  -1   M      A01X+175935Y+019194X0198Y0197R180 S1      
317P3V3_AUX         VIA   -    MD0100PA00X+167562Y+018663X0200Y         S0      
327P3V3_AUX         R658  -1          A01X+167773Y+018866X0198Y0197     S1      
317P3V3_AUX         VIA   -    MD0100PA00X+166083Y+019194X0200Y         S0      
327P3V3_AUX         U77   -9          A01X+166042Y+018580X0090Y0240R090 S1      
327P3V3_AUX         C336  -1   M      A01X+165699Y+019194X0198Y0197R180 S1      
317P3V3_AUX         VIA   -    MD0100PA00X+157326Y+018663X0200Y         S0      
327P3V3_AUX         R647  -1          A01X+157537Y+018866X0198Y0197     S1      
317P3V3_AUX         VIA   -    MD0100PA00X+155847Y+019194X0200Y         S0      
327P3V3_AUX         U76   -9          A01X+155806Y+018580X0090Y0240R090 S1      
327P3V3_AUX         C406  -1   M      A01X+155463Y+019194X0198Y0197R180 S1      
317P3V3_AUX         VIA   -    MD0100PA00X+147090Y+018663X0200Y         S0      
327P3V3_AUX         R636  -1          A01X+147301Y+018866X0198Y0197     S1      
317P3V3_AUX         VIA   -    MD0100PA00X+145610Y+019194X0200Y         S0      
327P3V3_AUX         U75   -9          A01X+145569Y+018580X0090Y0240R090 S1      
327P3V3_AUX         C333  -1   M      A01X+145226Y+019194X0198Y0197R180 S1      
317P3V3_AUX         VIA   -    MD0100PA00X+132090Y+018663X0200Y         S0      
327P3V3_AUX         R625  -1          A01X+132301Y+018866X0198Y0197     S1      
317P3V3_AUX         VIA   -    MD0100PA00X+130610Y+019194X0200Y         S0      
327P3V3_AUX         U74   -9          A01X+130569Y+018580X0090Y0240R090 S1      
327P3V3_AUX         C327  -1   M      A01X+130226Y+019194X0198Y0197R180 S1      
317P3V3_AUX         VIA   -    MD0100PA00X+121854Y+018663X0200Y         S0      
327P3V3_AUX         R614  -1          A01X+122064Y+018866X0198Y0197     S1      
317P3V3_AUX         VIA   -    MD0100PA00X+120374Y+019194X0200Y         S0      
327P3V3_AUX         U73   -9          A01X+120333Y+018580X0090Y0240R090 S1      
327P3V3_AUX         C324  -1   M      A01X+119990Y+019194X0198Y0197R180 S1      
317P3V3_AUX         VIA   -    MD0100PA00X+111617Y+018663X0200Y         S0      
327P3V3_AUX         R603  -1          A01X+111828Y+018866X0198Y0197     S1      
317P3V3_AUX         VIA   -    MD0100PA00X+110138Y+019194X0200Y         S0      
327P3V3_AUX         U72   -9          A01X+110097Y+018580X0090Y0240R090 S1      
327P3V3_AUX         C330  -1   M      A01X+109754Y+019194X0198Y0197R180 S1      
317P3V3_AUX         VIA   -    MD0100PA00X+101381Y+018663X0200Y         S0      
327P3V3_AUX         R592  -1          A01X+101592Y+018866X0198Y0197     S1      
317P3V3_AUX         VIA   -    MD0100PA00X+099902Y+019194X0200Y         S0      
327P3V3_AUX         U71   -9          A01X+099861Y+018580X0090Y0240R090 S1      
327P3V3_AUX         C321  -1   M      A01X+099518Y+019194X0198Y0197R180 S1      
317P3V3_AUX         VIA   -    MD0100PA00X+086381Y+018663X0200Y         S0      
327P3V3_AUX         R581  -1          A01X+086592Y+018866X0198Y0197     S1      
317P3V3_AUX         VIA   -    MD0100PA00X+084902Y+019194X0200Y         S0      
327P3V3_AUX         C312  -1   M      A01X+084518Y+019194X0198Y0197R180 S1      
327P3V3_AUX         U62   -9          A01X+084861Y+018580X0090Y0240R090 S1      
317P3V3_AUX         VIA   -    MD0100PA00X+076145Y+018663X0200Y         S0      
327P3V3_AUX         R570  -1          A01X+076356Y+018866X0198Y0197     S1      
317P3V3_AUX         VIA   -    MD0100PA00X+074666Y+019194X0200Y         S0      
327P3V3_AUX         U61   -9          A01X+074624Y+018580X0090Y0240R090 S1      
327P3V3_AUX         C318  -1   M      A01X+074282Y+019194X0198Y0197R180 S1      
317P3V3_AUX         VIA   -    MD0100PA00X+065909Y+018663X0200Y         S0      
327P3V3_AUX         R559  -1          A01X+066120Y+018866X0198Y0197     S1      
317P3V3_AUX         VIA   -    MD0100PA00X+064429Y+019194X0200Y         S0      
327P3V3_AUX         U60   -9          A01X+064388Y+018580X0090Y0240R090 S1      
327P3V3_AUX         C309  -1   M      A01X+064045Y+019194X0198Y0197R180 S1      
317P3V3_AUX         VIA   -    MD0100PA00X+055673Y+018663X0200Y         S0      
327P3V3_AUX         R548  -1          A01X+055883Y+018866X0198Y0197     S1      
317P3V3_AUX         VIA   -    MD0100PA00X+054193Y+019194X0200Y         S0      
327P3V3_AUX         U59   -9          A01X+054152Y+018580X0090Y0240R090 S1      
327P3V3_AUX         C315  -1   M      A01X+053809Y+019194X0198Y0197R180 S1      
317P3V3_AUX         VIA   -    MD0100PA00X+040672Y+018663X0200Y         S0      
317P3V3_AUX         VIA   -    MD0100PA00X+041466Y+020486X0200Y         S0      
327P3V3_AUX         R867  -1          A01X+041208Y+020486X0198Y0197R180 S1      
327P3V3_AUX         R537  -1          A01X+040883Y+018866X0198Y0197     S1      
317P3V3_AUX         VIA   -    MD0100PA00X+039193Y+019194X0200Y         S0      
327P3V3_AUX         U56   -9          A01X+039152Y+018580X0090Y0240R090 S1      
327P3V3_AUX         C207  -1   M      A01X+038809Y+019194X0198Y0197R180 S1      
317P3V3_AUX         VIA   -    MD0100PA00X+030436Y+018663X0200Y         S0      
327P3V3_AUX         R526  -1          A01X+030647Y+018866X0198Y0197     S1      
317P3V3_AUX         VIA   -    MD0100PA00X+028957Y+019194X0200Y         S0      
327P3V3_AUX         U55   -9          A01X+028916Y+018580X0090Y0240R090 S1      
327P3V3_AUX         C3668 -1   M      A01X+028573Y+019194X0198Y0197R180 S1      
317P3V3_AUX         VIA   -    MD0100PA00X+020200Y+018663X0200Y         S0      
327P3V3_AUX         R515  -1          A01X+020411Y+018866X0198Y0197     S1      
317P3V3_AUX         VIA   -    MD0100PA00X+018721Y+019194X0200Y         S0      
327P3V3_AUX         C210  -1   M      A01X+018337Y+019194X0198Y0197R180 S1      
327P3V3_AUX         U54   -9          A01X+018680Y+018580X0090Y0240R090 S1      
317P3V3_AUX         VIA   -    MD0100PA00X+009964Y+018663X0200Y         S0      
327P3V3_AUX         R504  -1          A01X+010175Y+018866X0198Y0197     S1      
317P3V3_AUX         VIA   -    MD0100PA00X+008484Y+019194X0200Y         S0      
327P3V3_AUX         U51   -9          A01X+008443Y+018580X0090Y0240R090 S1      
327P3V3_AUX         C201  -1   M      A01X+008100Y+019194X0198Y0197R180 S1      
317P3V3_AUX         VIA   -    MD0100PA00X+178589Y+017666X0200Y         S0      
327P3V3_AUX         R672  -2          A01X+178324Y+017666X0198Y0197     S1      
317P3V3_AUX         VIA   -    MD0100PA00X+178589Y+016866X0200Y         S0      
327P3V3_AUX         R671  -2          A01X+178324Y+016866X0198Y0197     S1      
317P3V3_AUX         VIA   -    MD0100PA00X+168352Y+017666X0200Y         S0      
327P3V3_AUX         R660  -2          A01X+168088Y+017666X0198Y0197     S1      
317P3V3_AUX         VIA   -    MD0100PA00X+168352Y+016866X0200Y         S0      
327P3V3_AUX         R659  -2          A01X+168088Y+016866X0198Y0197     S1      
317P3V3_AUX         VIA   -    MD0100PA00X+158116Y+017666X0200Y         S0      
327P3V3_AUX         R650  -2          A01X+157852Y+017666X0198Y0197     S1      
317P3V3_AUX         VIA   -    MD0100PA00X+158116Y+016866X0200Y         S0      
327P3V3_AUX         R648  -2          A01X+157852Y+016866X0198Y0197     S1      
317P3V3_AUX         VIA   -    MD0100PA00X+147880Y+017666X0200Y         S0      
327P3V3_AUX         R639  -2          A01X+147616Y+017666X0198Y0197     S1      
317P3V3_AUX         VIA   -    MD0100PA00X+147880Y+016866X0200Y         S0      
327P3V3_AUX         R637  -2          A01X+147616Y+016866X0198Y0197     S1      
317P3V3_AUX         VIA   -    MD0100PA00X+132880Y+017666X0200Y         S0      
327P3V3_AUX         R628  -2          A01X+132616Y+017666X0198Y0197     S1      
317P3V3_AUX         VIA   -    MD0100PA00X+132883Y+020486X0200Y         S0      
327P3V3_AUX         R876  -1          A01X+132625Y+020486X0198Y0197R180 S1      
317P3V3_AUX         VIA   -    MD0100PA00X+132880Y+016866X0200Y         S0      
327P3V3_AUX         R627  -2          A01X+132616Y+016866X0198Y0197     S1      
317P3V3_AUX         VIA   -    MD0100PA00X+122644Y+016866X0200Y         S0      
327P3V3_AUX         R616  -2          A01X+122379Y+016866X0198Y0197     S1      
317P3V3_AUX         VIA   -    MD0100PA00X+122644Y+017666X0200Y         S0      
327P3V3_AUX         R617  -2          A01X+122379Y+017666X0198Y0197     S1      
317P3V3_AUX         VIA   -    MD0100PA00X+112408Y+017666X0200Y         S0      
327P3V3_AUX         R606  -2          A01X+112143Y+017666X0198Y0197     S1      
317P3V3_AUX         VIA   -    MD0100PA00X+112408Y+016866X0200Y         S0      
327P3V3_AUX         R604  -2          A01X+112143Y+016866X0198Y0197     S1      
317P3V3_AUX         VIA   -    MD0100PA00X+102171Y+016866X0200Y         S0      
327P3V3_AUX         R594  -2          A01X+101907Y+016866X0198Y0197     S1      
317P3V3_AUX         VIA   -    MD0100PA00X+102171Y+017666X0200Y         S0      
327P3V3_AUX         R595  -2          A01X+101907Y+017666X0198Y0197     S1      
327P3V3_AUX         R1753 -1          A01X+087453Y+020050X0198Y0197R270 S1      
327P3V3_AUX         R868  -1          A01X+086916Y+020486X0198Y0197R180 S1      
317P3V3_AUX         VIA   -    MD0100PA00X+087174Y+020486X0200Y         S0      
317P3V3_AUX         VIA   -    MD0100PA00X+087171Y+017666X0200Y         S0      
327P3V3_AUX         R584  -2          A01X+086907Y+017666X0198Y0197     S1      
317P3V3_AUX         VIA   -    MD0100PA00X+087171Y+016866X0200Y         S0      
327P3V3_AUX         R582  -2          A01X+086907Y+016866X0198Y0197     S1      
317P3V3_AUX         VIA   -    MD0100PA00X+076935Y+016866X0200Y         S0      
327P3V3_AUX         R571  -2          A01X+076671Y+016866X0198Y0197     S1      
317P3V3_AUX         VIA   -    MD0100PA00X+076935Y+017666X0200Y         S0      
327P3V3_AUX         R572  -2          A01X+076671Y+017666X0198Y0197     S1      
317P3V3_AUX         VIA   -    MD0100PA00X+066699Y+016866X0200Y         S0      
327P3V3_AUX         R560  -2          A01X+066435Y+016866X0198Y0197     S1      
317P3V3_AUX         VIA   -    MD0100PA00X+066699Y+017666X0200Y         S0      
327P3V3_AUX         R561  -2          A01X+066435Y+017666X0198Y0197     S1      
317P3V3_AUX         VIA   -    MD0100PA00X+056463Y+016866X0200Y         S0      
327P3V3_AUX         R549  -2          A01X+056198Y+016866X0198Y0197     S1      
317P3V3_AUX         VIA   -    MD0100PA00X+056463Y+017666X0200Y         S0      
327P3V3_AUX         R550  -2          A01X+056198Y+017666X0198Y0197     S1      
317P3V3_AUX         VIA   -    MD0100PA00X+041463Y+016866X0200Y         S0      
327P3V3_AUX         R539  -2          A01X+041198Y+016866X0198Y0197     S1      
317P3V3_AUX         VIA   -    MD0100PA00X+041463Y+017666X0200Y         S0      
327P3V3_AUX         R540  -2          A01X+041198Y+017666X0198Y0197     S1      
317P3V3_AUX         VIA   -    MD0100PA00X+031226Y+016866X0200Y         S0      
327P3V3_AUX         R528  -2          A01X+030962Y+016866X0198Y0197     S1      
317P3V3_AUX         VIA   -    MD0100PA00X+031226Y+017666X0200Y         S0      
327P3V3_AUX         R529  -2          A01X+030962Y+017666X0198Y0197     S1      
317P3V3_AUX         VIA   -    MD0100PA00X+020990Y+016866X0200Y         S0      
327P3V3_AUX         R517  -2          A01X+020726Y+016866X0198Y0197     S1      
317P3V3_AUX         VIA   -    MD0100PA00X+020990Y+017666X0200Y         S0      
327P3V3_AUX         R518  -2          A01X+020726Y+017666X0198Y0197     S1      
317P3V3_AUX         VIA   -    MD0100PA00X+010754Y+016866X0200Y         S0      
327P3V3_AUX         R505  -2          A01X+010490Y+016866X0198Y0197     S1      
317P3V3_AUX         VIA   -    MD0100PA00X+010754Y+017666X0200Y         S0      
327P3V3_AUX         R507  -2          A01X+010490Y+017666X0198Y0197     S1      
317P3V3_AUX         VIA   -    MD0100PA00X+004848Y+018081X0200Y         S0      
327P3V3_AUX         R5540 -1          A01X+004848Y+017761X0198Y0197R180 S1      
317P3V3_AUX         VIA   -    MD0100PA00X+168219Y+016131X0200Y         S0      
327P3V3_AUX         R5584 -1          A01X+168278Y+015802X0198Y0197R270 S1      
317P3V3_AUX         VIA   -    MD0100PA00X+157983Y+016131X0200Y         S0      
327P3V3_AUX         R5578 -1          A01X+158042Y+015802X0198Y0197R270 S1      
317P3V3_AUX         VIA   -    MD0100PA00X+147746Y+016131X0200Y         S0      
327P3V3_AUX         R5572 -1          A01X+147806Y+015802X0198Y0197R270 S1      
317P3V3_AUX         VIA   -    MD0100PA00X+137510Y+016131X0200Y         S0      
327P3V3_AUX         R5566 -1          A01X+137569Y+015802X0198Y0197R270 S1      
317P3V3_AUX         VIA   -    MD0100PA00X+122510Y+016131X0200Y         S0      
327P3V3_AUX         R5581 -1          A01X+122569Y+015802X0198Y0197R270 S1      
317P3V3_AUX         VIA   -    MD0100PA00X+112274Y+016131X0200Y         S0      
327P3V3_AUX         R5575 -1          A01X+112333Y+015802X0198Y0197R270 S1      
317P3V3_AUX         VIA   -    MD0100PA00X+102038Y+016131X0200Y         S0      
327P3V3_AUX         R5569 -1          A01X+102097Y+015802X0198Y0197R270 S1      
317P3V3_AUX         VIA   -    MD0100PA00X+091802Y+016131X0200Y         S0      
327P3V3_AUX         R5563 -1          A01X+091861Y+015802X0198Y0197R270 S1      
317P3V3_AUX         VIA   -    MD0100PA00X+076802Y+016131X0200Y         S0      
327P3V3_AUX         R5560 -1          A01X+076861Y+015802X0198Y0197R270 S1      
317P3V3_AUX         VIA   -    MD0100PA00X+066565Y+016131X0200Y         S0      
327P3V3_AUX         R5557 -1          A01X+066624Y+015802X0198Y0197R270 S1      
317P3V3_AUX         VIA   -    MD0100PA00X+056329Y+016131X0200Y         S0      
327P3V3_AUX         R5554 -1          A01X+056388Y+015802X0198Y0197R270 S1      
317P3V3_AUX         VIA   -    MD0100PA00X+046093Y+016131X0200Y         S0      
327P3V3_AUX         R5551 -1          A01X+046152Y+015802X0198Y0197R270 S1      
317P3V3_AUX         VIA   -    MD0100PA00X+031093Y+016131X0200Y         S0      
327P3V3_AUX         R5548 -1          A01X+031152Y+015802X0198Y0197R270 S1      
317P3V3_AUX         VIA   -    MD0100PA00X+020857Y+016131X0200Y         S0      
327P3V3_AUX         R5545 -1          A01X+020916Y+015802X0198Y0197R270 S1      
317P3V3_AUX         VIA   -    MD0100PA00X+010620Y+016131X0200Y         S0      
327P3V3_AUX         R5542 -1          A01X+010680Y+015802X0198Y0197R270 S1      
327P3V3_AUX         PC668 -1          A01X+000826Y+015910X0198Y0197R270 S1      
327P3V3_AUX         PU81  -1_2        A01X+001544Y+016010X0295Y0354R090 S1      
317P3V3_AUX         VIA   -    MD0100PA00X+001097Y+015907X0200Y         S0      
317P3V3_AUX         VIA   -    MD0100PA00X+001097Y+016207X0200Y         S0      
317P3V3_AUX         VIA   -    MD0100PA00X+170032Y+014286X0200Y         S0      
327P3V3_AUX         U396  -5          A01X+169171Y+014265X0240Y0240     S1      
327P3V3_AUX         C3673 -1   M      A01X+169782Y+014286X0198Y0197R090 S1      
317P3V3_AUX         VIA   -    MD0100PA00X+165118Y+014125X0200Y         S0      
327P3V3_AUX         R6117 -1          A01X+165415Y+014125X0198Y0197     S1      
317P3V3_AUX         VIA   -    MD0100PA00X+159796Y+014286X0200Y         S0      
327P3V3_AUX         C3674 -1   M      A01X+159546Y+014286X0198Y0197R090 S1      
327P3V3_AUX         U397  -5          A01X+158935Y+014265X0240Y0240     S1      
317P3V3_AUX         VIA   -    MD0100PA00X+154882Y+014125X0200Y         S0      
327P3V3_AUX         R6116 -1          A01X+155179Y+014125X0198Y0197     S1      
317P3V3_AUX         VIA   -    MD0100PA00X+149560Y+014286X0200Y         S0      
327P3V3_AUX         C3670 -1   M      A01X+149310Y+014286X0198Y0197R090 S1      
327P3V3_AUX         U394  -5          A01X+148699Y+014265X0240Y0240     S1      
317P3V3_AUX         VIA   -    MD0100PA00X+144645Y+014125X0200Y         S0      
327P3V3_AUX         R6105 -1          A01X+144943Y+014125X0198Y0197     S1      
317P3V3_AUX         VIA   -    MD0100PA00X+139324Y+014286X0200Y         S0      
327P3V3_AUX         U395  -5          A01X+138463Y+014265X0240Y0240     S1      
327P3V3_AUX         C3672 -1   M      A01X+139074Y+014286X0198Y0197R090 S1      
317P3V3_AUX         VIA   -    MD0100PA00X+134409Y+014125X0200Y         S0      
327P3V3_AUX         R6104 -1          A01X+134707Y+014125X0198Y0197     S1      
317P3V3_AUX         VIA   -    MD0100PA00X+124324Y+014286X0200Y         S0      
327P3V3_AUX         U392  -5          A01X+123463Y+014265X0240Y0240     S1      
327P3V3_AUX         C3671 -1   M      A01X+124074Y+014286X0198Y0197R090 S1      
317P3V3_AUX         VIA   -    MD0100PA00X+119409Y+014125X0200Y         S0      
327P3V3_AUX         R6093 -1          A01X+119707Y+014125X0198Y0197     S1      
317P3V3_AUX         VIA   -    MD0100PA00X+114088Y+014286X0200Y         S0      
327P3V3_AUX         U393  -5          A01X+113226Y+014265X0240Y0240     S1      
327P3V3_AUX         C3676 -1   M      A01X+113838Y+014286X0198Y0197R090 S1      
317P3V3_AUX         VIA   -    MD0100PA00X+109173Y+014125X0200Y         S0      
327P3V3_AUX         R6092 -1          A01X+109470Y+014125X0198Y0197     S1      
317P3V3_AUX         VIA   -    MD0100PA00X+103851Y+014286X0200Y         S0      
327P3V3_AUX         U390  -5          A01X+102990Y+014265X0240Y0240     S1      
327P3V3_AUX         C3669 -1   M      A01X+103601Y+014286X0198Y0197R090 S1      
317P3V3_AUX         VIA   -    MD0100PA00X+098937Y+014125X0200Y         S0      
327P3V3_AUX         R6081 -1          A01X+099234Y+014125X0198Y0197     S1      
317P3V3_AUX         VIA   -    MD0100PA00X+093615Y+014286X0200Y         S0      
327P3V3_AUX         U391  -5          A01X+092754Y+014265X0240Y0240     S1      
327P3V3_AUX         C3675 -1   M      A01X+093365Y+014286X0198Y0197R090 S1      
317P3V3_AUX         VIA   -    MD0100PA00X+088700Y+014125X0200Y         S0      
327P3V3_AUX         R6080 -1          A01X+088998Y+014125X0198Y0197     S1      
317P3V3_AUX         VIA   -    MD0100PA00X+078615Y+014286X0200Y         S0      
327P3V3_AUX         U388  -5          A01X+077754Y+014265X0240Y0240     S1      
327P3V3_AUX         C3666 -1   M      A01X+078365Y+014286X0198Y0197R090 S1      
317P3V3_AUX         VIA   -    MD0100PA00X+073700Y+014125X0200Y         S0      
327P3V3_AUX         R6069 -1          A01X+073998Y+014125X0198Y0197     S1      
317P3V3_AUX         VIA   -    MD0100PA00X+068379Y+014286X0200Y         S0      
327P3V3_AUX         U389  -5          A01X+067518Y+014265X0240Y0240     S1      
327P3V3_AUX         C3665 -1   M      A01X+068129Y+014286X0198Y0197R090 S1      
317P3V3_AUX         VIA   -    MD0100PA00X+063464Y+014125X0200Y         S0      
327P3V3_AUX         R6068 -1          A01X+063762Y+014125X0198Y0197     S1      
317P3V3_AUX         VIA   -    MD0100PA00X+058143Y+014286X0200Y         S0      
327P3V3_AUX         U386  -5          A01X+057282Y+014265X0240Y0240     S1      
327P3V3_AUX         C3662 -1   M      A01X+057893Y+014286X0198Y0197R090 S1      
317P3V3_AUX         VIA   -    MD0100PA00X+053228Y+014125X0200Y         S0      
327P3V3_AUX         R6057 -1          A01X+053526Y+014125X0198Y0197     S1      
317P3V3_AUX         VIA   -    MD0100PA00X+047906Y+014286X0200Y         S0      
327P3V3_AUX         U387  -5          A01X+047045Y+014265X0240Y0240     S1      
327P3V3_AUX         C3663 -1   M      A01X+047656Y+014286X0198Y0197R090 S1      
317P3V3_AUX         VIA   -    MD0100PA00X+042992Y+014125X0200Y         S0      
327P3V3_AUX         R6056 -1          A01X+043290Y+014125X0198Y0197     S1      
317P3V3_AUX         VIA   -    MD0100PA00X+032906Y+014286X0200Y         S0      
327P3V3_AUX         C3664 -1   M      A01X+032656Y+014286X0198Y0197R090 S1      
327P3V3_AUX         U384  -5          A01X+032045Y+014265X0240Y0240     S1      
317P3V3_AUX         VIA   -    MD0100PA00X+027992Y+014125X0200Y         S0      
327P3V3_AUX         R5881 -1          A01X+028289Y+014125X0198Y0197     S1      
327P3V3_AUX         U385  -5          A01X+021809Y+014265X0240Y0240     S1      
317P3V3_AUX         VIA   -    MD0100PA00X+022670Y+014286X0200Y         S0      
327P3V3_AUX         C204  -1   M      A01X+022420Y+014286X0198Y0197R090 S1      
317P3V3_AUX         VIA   -    MD0100PA00X+017756Y+014125X0200Y         S0      
327P3V3_AUX         R5880 -1          A01X+018053Y+014125X0198Y0197     S1      
317P3V3_AUX         VIA   -    MD0100PA00X+012434Y+014286X0200Y         S0      
327P3V3_AUX         U382  -5          A01X+011573Y+014265X0240Y0240     S1      
327P3V3_AUX         C3661 -1   M      A01X+012184Y+014286X0198Y0197R090 S1      
317P3V3_AUX         VIA   -    MD0100PA00X+007519Y+014125X0200Y         S0      
327P3V3_AUX         R5869 -1          A01X+007817Y+014125X0198Y0197     S1      
317P3V3_AUX         VIA   -    MD0100PA00X+001986Y+014136X0200Y         S0      
327P3V3_AUX         R1631 -2          A01X+001986Y+013896X0198Y0197R090 S1      
317P3V3_AUX         VIA   -    MD0100PA00X+000908Y+013579X0200Y    R180 S0      
327P3V3_AUX         C2711 -2   M      A01X+000650Y+013579X0198Y0197R270 S1      
327P3V3_AUX         U126  -8          A01X+000846Y+012884X0240Y0460R180 S1      
317P3V3_AUX         VIA   -    MD0100PA00X+170059Y+010250X0200Y         S0      
327P3V3_AUX         R4082 -1          A01X+170318Y+010250X0198Y0197     S1      
327P3V3_AUX         PC969 -1          A01X+168065Y+011663X0198Y0197R270 S1      
327P3V3_AUX         PU134 -1_2        A01X+168782Y+011762X0295Y0354R090 S1      
317P3V3_AUX         VIA   -    MD0100PA00X+168335Y+011959X0200Y         S0      
317P3V3_AUX         VIA   -    MD0100PA00X+168335Y+011659X0200Y         S0      
317P3V3_AUX         VIA   -    MD0100PA00X+159823Y+010250X0200Y         S0      
327P3V3_AUX         R4080 -1          A01X+160082Y+010250X0198Y0197     S1      
327P3V3_AUX         PU133 -1_2        A01X+158546Y+011762X0295Y0354R090 S1      
327P3V3_AUX         PC968 -1          A01X+157828Y+011663X0198Y0197R270 S1      
317P3V3_AUX         VIA   -    MD0100PA00X+158099Y+011959X0200Y         S0      
317P3V3_AUX         VIA   -    MD0100PA00X+158099Y+011659X0200Y         S0      
317P3V3_AUX         VIA   -    MD0100PA00X+149587Y+010250X0200Y         S0      
327P3V3_AUX         R4078 -1          A01X+149846Y+010250X0198Y0197     S1      
327P3V3_AUX         PC949 -1          A01X+147592Y+011663X0198Y0197R270 S1      
327P3V3_AUX         PU132 -1_2        A01X+148310Y+011762X0295Y0354R090 S1      
317P3V3_AUX         VIA   -    MD0100PA00X+147862Y+011959X0200Y         S0      
317P3V3_AUX         VIA   -    MD0100PA00X+147862Y+011659X0200Y         S0      
317P3V3_AUX         VIA   -    MD0100PA00X+139350Y+010250X0200Y         S0      
327P3V3_AUX         R4076 -1          A01X+139610Y+010250X0198Y0197     S1      
327P3V3_AUX         PC948 -1          A01X+137356Y+011663X0198Y0197R270 S1      
327P3V3_AUX         PU131 -1_2        A01X+138074Y+011762X0295Y0354R090 S1      
317P3V3_AUX         VIA   -    MD0100PA00X+137626Y+011959X0200Y         S0      
317P3V3_AUX         VIA   -    MD0100PA00X+137626Y+011659X0200Y         S0      
317P3V3_AUX         VIA   -    MD0100PA00X+124350Y+010250X0200Y         S0      
327P3V3_AUX         R4074 -1          A01X+124610Y+010250X0198Y0197     S1      
327P3V3_AUX         PU130 -1_2        A01X+123074Y+011762X0295Y0354R090 S1      
327P3V3_AUX         PC959 -1          A01X+122356Y+011663X0198Y0197R270 S1      
317P3V3_AUX         VIA   -    MD0100PA00X+122626Y+011959X0200Y         S0      
317P3V3_AUX         VIA   -    MD0100PA00X+122626Y+011659X0200Y         S0      
317P3V3_AUX         VIA   -    MD0100PA00X+114114Y+010250X0200Y         S0      
327P3V3_AUX         R4072 -1          A01X+114374Y+010250X0198Y0197     S1      
327P3V3_AUX         PU129 -1_2        A01X+112838Y+011762X0295Y0354R090 S1      
327P3V3_AUX         PC939 -1          A01X+112120Y+011663X0198Y0197R270 S1      
317P3V3_AUX         VIA   -    MD0100PA00X+112390Y+011959X0200Y         S0      
317P3V3_AUX         VIA   -    MD0100PA00X+112390Y+011659X0200Y         S0      
317P3V3_AUX         VIA   -    MD0100PA00X+103878Y+010250X0200Y         S0      
327P3V3_AUX         R4070 -1          A01X+104137Y+010250X0198Y0197     S1      
327P3V3_AUX         PU128 -1_2        A01X+102601Y+011762X0295Y0354R090 S1      
327P3V3_AUX         PC958 -1          A01X+101884Y+011663X0198Y0197R270 S1      
317P3V3_AUX         VIA   -    MD0100PA00X+102154Y+011959X0200Y         S0      
317P3V3_AUX         VIA   -    MD0100PA00X+102154Y+011659X0200Y         S0      
317P3V3_AUX         VIA   -    MD0100PA00X+093642Y+010250X0200Y         S0      
327P3V3_AUX         R4068 -1          A01X+093901Y+010250X0198Y0197     S1      
327P3V3_AUX         PC938 -1          A01X+091647Y+011663X0198Y0197R270 S1      
327P3V3_AUX         PU127 -1_2        A01X+092365Y+011762X0295Y0354R090 S1      
317P3V3_AUX         VIA   -    MD0100PA00X+091918Y+011959X0200Y         S0      
317P3V3_AUX         VIA   -    MD0100PA00X+091918Y+011659X0200Y         S0      
317P3V3_AUX         VIA   -    MD0100PA00X+078642Y+010250X0200Y         S0      
327P3V3_AUX         R4066 -1          A01X+078901Y+010250X0198Y0197     S1      
327P3V3_AUX         PU126 -1_2        A01X+077365Y+011762X0295Y0354R090 S1      
327P3V3_AUX         PC929 -1          A01X+076647Y+011663X0198Y0197R270 S1      
317P3V3_AUX         VIA   -    MD0100PA00X+076918Y+011959X0200Y         S0      
317P3V3_AUX         VIA   -    MD0100PA00X+076918Y+011659X0200Y         S0      
317P3V3_AUX         VIA   -    MD0100PA00X+068406Y+010250X0200Y         S0      
327P3V3_AUX         R4064 -1          A01X+068665Y+010250X0198Y0197     S1      
327P3V3_AUX         PC928 -1          A01X+066411Y+011663X0198Y0197R270 S1      
327P3V3_AUX         PU125 -1_2        A01X+067129Y+011762X0295Y0354R090 S1      
317P3V3_AUX         VIA   -    MD0100PA00X+066681Y+011959X0200Y         S0      
317P3V3_AUX         VIA   -    MD0100PA00X+066681Y+011659X0200Y         S0      
317P3V3_AUX         VIA   -    MD0100PA00X+058169Y+010250X0200Y         S0      
327P3V3_AUX         R4062 -1          A01X+058429Y+010250X0198Y0197     S1      
327P3V3_AUX         PC919 -1          A01X+056175Y+011663X0198Y0197R270 S1      
327P3V3_AUX         PU124 -1_2        A01X+056893Y+011762X0295Y0354R090 S1      
317P3V3_AUX         VIA   -    MD0100PA00X+056445Y+011959X0200Y         S0      
317P3V3_AUX         VIA   -    MD0100PA00X+056445Y+011659X0200Y         S0      
317P3V3_AUX         VIA   -    MD0100PA00X+047933Y+010250X0200Y         S0      
327P3V3_AUX         R4060 -1          A01X+048193Y+010250X0198Y0197     S1      
327P3V3_AUX         PC918 -1          A01X+045939Y+011663X0198Y0197R270 S1      
327P3V3_AUX         PU123 -1_2        A01X+046657Y+011762X0295Y0354R090 S1      
317P3V3_AUX         VIA   -    MD0100PA00X+046209Y+011959X0200Y         S0      
317P3V3_AUX         VIA   -    MD0100PA00X+046209Y+011659X0200Y         S0      
317P3V3_AUX         VIA   -    MD0100PA00X+032933Y+010250X0200Y         S0      
327P3V3_AUX         R4058 -1          A01X+033192Y+010250X0198Y0197     S1      
327P3V3_AUX         PU84  -1_2        A01X+031656Y+011762X0295Y0354R090 S1      
327P3V3_AUX         PC679 -1          A01X+030939Y+011663X0198Y0197R270 S1      
317P3V3_AUX         VIA   -    MD0100PA00X+031209Y+011959X0200Y         S0      
317P3V3_AUX         VIA   -    MD0100PA00X+031209Y+011659X0200Y         S0      
317P3V3_AUX         VIA   -    MD0100PA00X+022697Y+010250X0200Y         S0      
327P3V3_AUX         R4056 -1          A01X+022956Y+010250X0198Y0197     S1      
327P3V3_AUX         PC678 -1          A01X+020702Y+011663X0198Y0197R270 S1      
327P3V3_AUX         PU83  -1_2        A01X+021420Y+011762X0295Y0354R090 S1      
317P3V3_AUX         VIA   -    MD0100PA00X+020973Y+011959X0200Y         S0      
317P3V3_AUX         VIA   -    MD0100PA00X+020973Y+011659X0200Y         S0      
317P3V3_AUX         VIA   -    MD0100PA00X+012461Y+010250X0200Y         S0      
327P3V3_AUX         R4054 -1          A01X+012720Y+010250X0198Y0197     S1      
327P3V3_AUX         PU82  -1_2        A01X+011184Y+011762X0295Y0354R090 S1      
327P3V3_AUX         PC669 -1          A01X+010466Y+011663X0198Y0197R270 S1      
317P3V3_AUX         VIA   -    MD0100PA00X+010736Y+011959X0200Y         S0      
317P3V3_AUX         VIA   -    MD0100PA00X+010736Y+011659X0200Y         S0      
317P3V3_AUX         VIA   -    MD0100PA00X+002244Y+010250X0200Y         S0      
327P3V3_AUX         R4055 -1          A01X+002484Y+010250X0198Y0197     S1      
317P3V3_AUX         VIA   -    MD0100PA00X+179037Y+009466X0200Y         S0      
327P3V3_AUX         R1732 -2          A01X+179037Y+009197X0198Y0197R090 S1      
317P3V3_AUX         VIA   -    MD0100PA00X+177960Y+008880X0200Y    R180 S0      
327P3V3_AUX         U141  -8          A01X+177898Y+008185X0240Y0460R180 S1      
327P3V3_AUX         C2735 -2   M      A01X+177702Y+008880X0198Y0197R270 S1      
317P3V3_AUX         VIA   -    MD0100PA00X+168801Y+009437X0200Y         S0      
327P3V3_AUX         R1729 -2          A01X+168801Y+009197X0198Y0197R090 S1      
317P3V3_AUX         VIA   -    MD0100PA00X+167724Y+008880X0200Y    R180 S0      
327P3V3_AUX         U140  -8          A01X+167662Y+008185X0240Y0460R180 S1      
327P3V3_AUX         C2733 -2   M      A01X+167466Y+008880X0198Y0197R270 S1      
317P3V3_AUX         VIA   -    MD0100PA00X+158565Y+009437X0200Y         S0      
327P3V3_AUX         R1718 -2          A01X+158565Y+009197X0198Y0197R090 S1      
317P3V3_AUX         VIA   -    MD0100PA00X+157488Y+008880X0200Y    R180 S0      
327P3V3_AUX         U139  -8          A01X+157425Y+008185X0240Y0460R180 S1      
327P3V3_AUX         C2741 -2   M      A01X+157229Y+008880X0198Y0197R270 S1      
317P3V3_AUX         VIA   -    MD0100PA00X+148329Y+009437X0200Y         S0      
327P3V3_AUX         R1715 -2          A01X+148329Y+009197X0198Y0197R090 S1      
317P3V3_AUX         VIA   -    MD0100PA00X+147251Y+008880X0200Y    R180 S0      
327P3V3_AUX         U138  -8          A01X+147189Y+008185X0240Y0460R180 S1      
327P3V3_AUX         C2731 -2   M      A01X+146993Y+008880X0198Y0197R270 S1      
317P3V3_AUX         VIA   -    MD0100PA00X+123092Y+009437X0200Y         S0      
327P3V3_AUX         R1701 -2          A01X+123092Y+009197X0198Y0197R090 S1      
317P3V3_AUX         VIA   -    MD0100PA00X+122015Y+008880X0200Y    R180 S0      
327P3V3_AUX         U136  -8          A01X+121953Y+008185X0240Y0460R180 S1      
327P3V3_AUX         C2729 -2   M      A01X+121757Y+008880X0198Y0197R270 S1      
317P3V3_AUX         VIA   -    MD0100PA00X+112856Y+009437X0200Y         S0      
327P3V3_AUX         R1690 -2          A01X+112856Y+009197X0198Y0197R090 S1      
317P3V3_AUX         VIA   -    MD0100PA00X+111779Y+008880X0200Y    R180 S0      
327P3V3_AUX         U135  -8          A01X+111717Y+008185X0240Y0460R180 S1      
327P3V3_AUX         C2737 -2   M      A01X+111521Y+008880X0198Y0197R270 S1      
317P3V3_AUX         VIA   -    MD0100PA00X+101543Y+008880X0200Y    R180 S0      
327P3V3_AUX         U134  -8          A01X+101480Y+008185X0240Y0460R180 S1      
327P3V3_AUX         C2727 -2   M      A01X+101284Y+008880X0198Y0197R270 S1      
317P3V3_AUX         VIA   -    MD0100PA00X+102620Y+009437X0200Y         S0      
327P3V3_AUX         R1687 -2          A01X+102620Y+009197X0198Y0197R090 S1      
317P3V3_AUX         VIA   -    MD0100PA00X+087620Y+009437X0200Y         S0      
327P3V3_AUX         R1676 -2          A01X+087620Y+009197X0198Y0197R090 S1      
317P3V3_AUX         VIA   -    MD0100PA00X+086543Y+008880X0200Y    R180 S0      
327P3V3_AUX         U133  -8          A01X+086480Y+008185X0240Y0460R180 S1      
327P3V3_AUX         C2725 -2   M      A01X+086284Y+008880X0198Y0197R270 S1      
317P3V3_AUX         VIA   -    MD0100PA00X+077384Y+009437X0200Y         S0      
327P3V3_AUX         R1673 -2          A01X+077384Y+009197X0198Y0197R090 S1      
317P3V3_AUX         VIA   -    MD0100PA00X+076306Y+008880X0200Y    R180 S0      
327P3V3_AUX         U132  -8          A01X+076244Y+008185X0240Y0460R180 S1      
327P3V3_AUX         C2723 -2   M      A01X+076048Y+008880X0198Y0197R270 S1      
317P3V3_AUX         VIA   -    MD0100PA00X+067148Y+009437X0200Y         S0      
327P3V3_AUX         R1662 -2          A01X+067148Y+009197X0198Y0197R090 S1      
317P3V3_AUX         VIA   -    MD0100PA00X+066070Y+008880X0200Y    R180 S0      
327P3V3_AUX         U131  -8          A01X+066008Y+008185X0240Y0460R180 S1      
327P3V3_AUX         C2721 -2   M      A01X+065812Y+008880X0198Y0197R270 S1      
317P3V3_AUX         VIA   -    MD0100PA00X+056911Y+009437X0200Y         S0      
327P3V3_AUX         R1659 -2          A01X+056911Y+009197X0198Y0197R090 S1      
317P3V3_AUX         VIA   -    MD0100PA00X+055834Y+008880X0200Y    R180 S0      
327P3V3_AUX         U130  -8          A01X+055772Y+008185X0240Y0460R180 S1      
327P3V3_AUX         C2719 -2   M      A01X+055576Y+008880X0198Y0197R270 S1      
317P3V3_AUX         VIA   -    MD0100PA00X+031675Y+009437X0200Y         S0      
327P3V3_AUX         R1645 -2          A01X+031675Y+009197X0198Y0197R090 S1      
317P3V3_AUX         VIA   -    MD0100PA00X+030598Y+008880X0200Y    R180 S0      
327P3V3_AUX         U128  -8          A01X+030536Y+008185X0240Y0460R180 S1      
327P3V3_AUX         C2715 -2   M      A01X+030340Y+008880X0198Y0197R270 S1      
317P3V3_AUX         VIA   -    MD0100PA00X+021439Y+009437X0200Y         S0      
327P3V3_AUX         R1634 -2          A01X+021439Y+009197X0198Y0197R090 S1      
317P3V3_AUX         VIA   -    MD0100PA00X+020362Y+008880X0200Y    R180 S0      
327P3V3_AUX         C2713 -2   M      A01X+020103Y+008880X0198Y0197R270 S1      
327P3V3_AUX         U127  -8          A01X+020299Y+008185X0240Y0460R180 S1      
317P3V3_AUX         VIA   -    MD0100PA00X+147997Y+004078X0200Y    R090 S0      
327P3V3_AUX         U417  -8          A01X+148354Y+003264X0240Y0520R270 S1      
327P3V3_AUX         C3871 -1   M      A01X+147997Y+003824X0198Y0197R180 S1      
317P3V3_AUX         VIA   -    MD0100PA00X+031226Y+003754X0200Y    R090 S0      
327P3V3_AUX         U416  -8          A01X+031582Y+002941X0240Y0520R270 S1      
327P3V3_AUX         C3870 -1   M      A01X+031226Y+003501X0198Y0197R180 S1      
317P3V3_AUX         VIA   -    MD0100PA00X+149862Y+002304X0200Y    R090 S0      
327P3V3_AUX         R5816 -2          A01X+149620Y+002304X0198Y0197     S1      
317P3V3_AUX         VIA   -    MD0100PA00X+149862Y+003104X0200Y    R090 S0      
327P3V3_AUX         R5815 -2          A01X+149620Y+003104X0198Y0197     S1      
317P3V3_AUX         VIA   -    MD0100PA00X+133665Y+002263X0200Y    R270 S0      
327P3V3_AUX         R1704 -2          A01X+133425Y+002263X0198Y0197     S1      
317P3V3_AUX         VIA   -    MD0100PA00X+133107Y+003340X0200Y    R090 S0      
327P3V3_AUX         U137  -8          A01X+132412Y+003402X0240Y0460R090 S1      
327P3V3_AUX         C2739 -2   M      A01X+133107Y+003598X0198Y0197R180 S1      
317P3V3_AUX         VIA   -    MD0100PA00X+042247Y+002263X0200Y    R270 S0      
327P3V3_AUX         R1648 -2          A01X+042007Y+002263X0198Y0197     S1      
317P3V3_AUX         VIA   -    MD0100PA00X+041690Y+003340X0200Y    R090 S0      
327P3V3_AUX         U129  -8          A01X+040995Y+003402X0240Y0460R090 S1      
327P3V3_AUX         C2717 -2   M      A01X+041690Y+003598X0198Y0197R180 S1      
317P3V3_AUX         VIA   -    MD0100PA00X+033090Y+002781X0200Y    R090 S0      
327P3V3_AUX         R5805 -2          A01X+032848Y+002781X0198Y0197     S1      
317P3V3_AUX         VIA   -    MD0100PA00X+149862Y+001904X0200Y    R090 S0      
327P3V3_AUX         R5817 -2          A01X+149620Y+001904X0198Y0197     S1      
317P3V3_AUX         VIA   -    MD0100PA00X+033090Y+001981X0200Y    R090 S0      
327P3V3_AUX         R5806 -2          A01X+032848Y+001981X0198Y0197     S1      
317P3V3_AUX         VIA   -    MD0100PA00X+033090Y+001581X0200Y    R090 S0      
327P3V3_AUX         R5807 -2          A01X+032848Y+001581X0198Y0197     S1      
327P3V3_AUX         R6824 -1          A01X+101093Y+135794X0198Y0197     S1      
327P3V3_AUX         U450  -6          A18X+089398Y+069214X0110Y0200R270 S2      
327P3V3_AUX         Q251  -S          A01X+002004Y+144974X0320Y0360     S1      
317P3V3_AUX         VIA   -    MD0100PA00X+002360Y+144974X0200Y         S0      
317P3V3_AUX         VIA   -    MD0100PA00X+079498Y+133123X0200Y         S0      
317P3V3_AUX         VIA   -    MD0100PA00X+079498Y+133403X0200Y         S0      
317P3V3_AUX         VIA   -    MD0100PA00X+041746Y+156958X0200Y    R090 S0      
327P3V3_AUX         R5446 -1          A01X+041746Y+156658X0198Y0197R270 S1      
327P3V3_AUX         R5442 -1          A18X+041582Y+155935X0198Y0197R090 S2      
317P3V3_AUX         VIA   -    MD0100PA00X+040146Y+156956X0200Y         S0      
327P3V3_AUX         R5454 -1          A01X+040146Y+156658X0198Y0197R270 S1      
317P3V3_AUX         VIA   -    MD0100PA00X+039746Y+156956X0200Y         S0      
327P3V3_AUX         R5452 -1          A01X+039746Y+156658X0198Y0197R270 S1      
317P3V3_AUX         VIA   -    MD0100PA00X+038202Y+155970X0200Y         S0      
327P3V3_AUX         R5459 -1   M      A01X+038444Y+155970X0198Y0197     S1      
317P3V3_AUX         VIA   -    MD0100PA00X+038190Y+154480X0200Y         S0      
327P3V3_AUX         R5450 -1   M      A01X+038444Y+154370X0198Y0197     S1      
317P3V3_AUX         VIA   -    MD0100PA00X+039309Y+142360X0180Y    R180 S0      
317P3V3_AUX         VIA   -    MD0100PA00X+039589Y+142360X0180Y    R180 S0      
317P3V3_AUX         VIA   -    MD0100PA00X+004762Y+134367X0200Y         S0      
327P3V3_AUX         R6758 -1          A01X+002722Y+143855X0198Y0197R090 S1      
317P3V3_AUX         VIA   -    MD0100PA00X+002986Y+143855X0200Y         S0      
317P3V3_AUX         VIA   -     D0100PA00X+005526Y+158348X0200Y    R180 S0      
317P3V3_AUX         VIA   -     D0100PA00X+005806Y+158348X0200Y    R180 S0      
317P3V3_AUX         VIA   -     D0100PA00X+006086Y+158348X0200Y    R180 S0      
327P3V3_AUX         C3652 -1   M      A01X+006309Y+161515X0198Y0197R270 S1      
317P3V3_AUX         VIA   -    MD0100PA00X+006055Y+161515X0200Y    R180 S0      
327P3V3_AUX         U328  -8          A01X+006869Y+161872X0240Y0520     S1      
317P3V3_AUX         VIA   -    MD0100PA00X+007029Y+163380X0200Y    R180 S0      
327P3V3_AUX         R5594 -2          A01X+007029Y+163138X0198Y0197R090 S1      
317P3V3_AUX         VIA   -    MD0100PA00X+007829Y+163380X0200Y    R180 S0      
327P3V3_AUX         R5589 -2          A01X+007829Y+163138X0198Y0197R090 S1      
317P3V3_AUX         VIA   -    MD0100PA00X+008229Y+163380X0200Y    R180 S0      
327P3V3_AUX         R5590 -2          A01X+008229Y+163138X0198Y0197R090 S1      
327m3471            R828  -2          A01X+049209Y+099534X0198Y0197R090 S1      
327m3471            VIA   -    M      A01X+049101Y+100050X0300Y         S1      
327m3471            PU6   -10         A01X+048258Y+100785X0070Y0240     S1      
327m3472            R830  -2          A01X+050902Y+103077X0198Y0197R180 S1      
327m3472            PU6   -20         A01X+048494Y+102439X0070Y0240R090 S1      
327m3472            VIA   -    M      A01X+049707Y+102606X0300Y         S1      
327m3472            C832  -2   M      A01X+050102Y+103077X0198Y0197R180 S1      
327P0V8_PEX0_VDD    VIA   -           A18X+045936Y+099676X0260Y    R090 S2      
327P0V8_PEX0_VDD    PU6   -39         A01X+046605Y+101179X0070Y0240R090 S1      
327P0V8_PEX0_VDD    PC45  -1   M      A01X+045936Y+100718X0198Y0197R180 S1      
317P0V8_PEX0_VDD    VIA   -    MD0100PA00X+045936Y+100468X0200Y         S0      
327P0V8_PEX0_VDD    PC44  -1          A18X+045931Y+100732X0198Y0197R180 S2      
327P0V8_PEX0_VDD    PR65  -2   M      A18X+045936Y+100218X0198Y0197R180 S2      
317m3473            VIA   -    M      A01X+049844Y+100877X0200Y         S2      
017m3473            VIA   -    M      A18X+049844Y+100877X0260Y         S2      
017m3473                  -    MD0100PA00X+049844Y+100877                       
327m3473            PU6   -14         A01X+048494Y+101494X0070Y0240R090 S1      
327m3473            PR85  -2          A01X+050102Y+100877X0198Y0197R180 S1      
327m3474            VIA   -    M      A18X+032568Y+128795X0260Y         S2      
327m3474            PJ19  -1          A18X+039567Y+127629X0200Y0400R090 S2      
317m3474            VIA   -    MD0080PA00X+028533Y+118927X0160Y         S0      
327m3474            PEX0  -W39        A01X+028720Y+118740X0180Y         S1      
327m3475            VIA   -    M      A18X+032062Y+128445X0260Y         S2      
327m3475            PJ18  -1          A18X+039567Y+127209X0200Y0400R090 S2      
317m3475            VIA   -    MD0080PA00X+028907Y+118927X0160Y         S0      
327m3475            PEX0  -V39        A01X+028720Y+119114X0180Y         S1      
327m3476            R832  -2          A01X+050902Y+102027X0198Y0197R180 S1      
317m3476            VIA   -    M      A01X+049858Y+101627X0200Y         S2      
017m3476            VIA   -    M      A18X+049858Y+101627X0260Y         S2      
017m3476                  -    MD0100PA00X+049858Y+101627                       
327m3476            PU6   -16         A01X+048494Y+101809X0070Y0240R090 S1      
327m3476            R831  -2   M      A01X+050902Y+101627X0198Y0197R180 S1      
327m3476            C833  -1   M      A01X+050102Y+101627X0198Y0197     S1      
327m3477            PR7165-2          A01X+050088Y+102026X0198Y0197R180 S1      
327m3477            VIA   -    M      A01X+049204Y+102049X0300Y         S1      
327m3477            PU6   -19         A01X+048494Y+102282X0070Y0240R090 S1      
327m3478            PR80  -2          A01X+045717Y+102477X0198Y0197     S1      
327m3478            PU6   -32         A01X+046605Y+102282X0070Y0240R090 S1      
327m3478            PC50  -1   M      A01X+046109Y+102469X0198Y0197R090 S1      
327P0V8_PEX0_ADDR   PR92  -1   M      A01X+044867Y+102277X0198Y0197R180 S1      
317P0V8_PEX0_ADDR   VIA   -    M      A01X+045114Y+102179X0200Y         S2      
017P0V8_PEX0_ADDR   VIA   -    M      A18X+045114Y+102179X0260Y         S2      
017P0V8_PEX0_ADDR         -    MD0100PA00X+045114Y+102179                       
327P0V8_PEX0_ADDR   PU6   -34         A01X+046605Y+101966X0070Y0240R090 S1      
327P0V8_PEX0_ADDR   PR91  -2          A01X+044867Y+102627X0198Y0197     S1      
327m3479            PR90  -1          A18X+046438Y+102360X0198Y0197R270 S2      
327m3479            VIA   -    M      A18X+046489Y+101907X0260Y    R090 S2      
327m3479            PU6   -36         A01X+046605Y+101652X0070Y0240R090 S1      
317m3479            VIA   -    MD0100PA00X+046218Y+101682X0200Y         S0      
327m3479            PC53  -1   M      A18X+046452Y+101457X0198Y0197R180 S2      
327P0V8_PEX1        C1384 -1          A18X+070876Y+117349X0120Y0150R090 S2      
327P0V8_PEX1        C1369 -1          A18X+071624Y+117349X0120Y0150R090 S2      
327P0V8_PEX1        C1405 -1          A18X+069380Y+117349X0120Y0150R090 S2      
327P0V8_PEX1        C1410 -1          A18X+070128Y+117349X0120Y0150R090 S2      
327P0V8_PEX1        C1407 -1          A18X+068258Y+117349X0120Y0150R090 S2      
327P0V8_PEX1        C1403 -1          A18X+067510Y+117349X0120Y0150R090 S2      
327P0V8_PEX1        C1379 -1          A18X+066762Y+117349X0120Y0150R090 S2      
327P0V8_PEX1        C1401 -1          A18X+066014Y+117349X0120Y0150R090 S2      
327P0V8_PEX1        C1400 -1          A18X+065266Y+117349X0120Y0150R090 S2      
327P0V8_PEX1        C1371 -1          A18X+065184Y+118179X0120Y0150     S2      
327P0V8_PEX1        C1392 -1          A18X+064974Y+117825X0120Y0150R180 S2      
327P0V8_PEX1        C1357 -1          A18X+070479Y+116229X0280Y0320R090 S2      
327P0V8_PEX1        C1398 -1          A18X+070502Y+117139X0120Y0150R270 S2      
327P0V8_PEX1        C1409 -1          A18X+071250Y+115853X0120Y0150R090 S2      
327P0V8_PEX1        C1385 -1          A18X+070502Y+115853X0120Y0150R090 S2      
327P0V8_PEX1        C1399 -1          A18X+071250Y+117139X0120Y0150R270 S2      
327P0V8_PEX1        C1383 -1          A18X+068632Y+117139X0120Y0150R270 S2      
327P0V8_PEX1        C1411 -1          A18X+069754Y+117139X0120Y0150R270 S2      
327P0V8_PEX1        C1362 -1          A18X+068932Y+116683X0120Y0150     S2      
327P0V8_PEX1        C1380 -1          A18X+068632Y+115853X0120Y0150R090 S2      
327P0V8_PEX1        C1396 -1          A18X+069754Y+115853X0120Y0150R090 S2      
327P0V8_PEX1        C1356 -1          A18X+067113Y+116229X0280Y0320R090 S2      
327P0V8_PEX1        C1355 -1          A18X+068609Y+116229X0280Y0320R090 S2      
327P0V8_PEX1        C1404 -1          A18X+067884Y+117139X0120Y0150R270 S2      
327P0V8_PEX1        C1394 -1          A18X+067136Y+117139X0120Y0150R270 S2      
327P0V8_PEX1        C1376 -1          A18X+067884Y+115853X0120Y0150R090 S2      
327P0V8_PEX1        C1389 -1          A18X+067136Y+115853X0120Y0150R090 S2      
327P0V8_PEX1        C1388 -1          A18X+065640Y+117139X0120Y0150R270 S2      
327P0V8_PEX1        C1395 -1          A18X+066388Y+117139X0120Y0150R270 S2      
327P0V8_PEX1        C1378 -1          A18X+066388Y+115853X0120Y0150R090 S2      
327P0V8_PEX1        C1382 -1          A18X+065640Y+115853X0120Y0150R090 S2      
327P0V8_PEX1        C1367 -1          A18X+064892Y+117139X0120Y0150R270 S2      
327P0V8_PEX1        C1368 -1          A18X+064892Y+115853X0120Y0150R090 S2      
327P0V8_PEX1        C1408 -1          A18X+070876Y+115643X0120Y0150R270 S2      
327P0V8_PEX1        C1386 -1          A18X+071624Y+115643X0120Y0150R270 S2      
327P0V8_PEX1        C1397 -1          A18X+070128Y+115643X0120Y0150R270 S2      
327P0V8_PEX1        C1406 -1          A18X+069380Y+115643X0120Y0150R270 S2      
327P0V8_PEX1        C1377 -1          A18X+067510Y+115643X0120Y0150R270 S2      
327P0V8_PEX1        C1402 -1          A18X+068258Y+115643X0120Y0150R270 S2      
327P0V8_PEX1        C1387 -1          A18X+066014Y+115643X0120Y0150R270 S2      
327P0V8_PEX1        C1390 -1          A18X+066762Y+115643X0120Y0150R270 S2      
327P0V8_PEX1        C1381 -1          A18X+065266Y+115643X0120Y0150R270 S2      
327P0V8_PEX1        C1360 -1          A18X+065184Y+114813X0120Y0150     S2      
327P0V8_PEX1        C1361 -1          A18X+064974Y+115187X0120Y0150R180 S2      
327P0V8_PEX1        C1359 -1          A18X+064974Y+114439X0120Y0150R180 S2      
327P0V8_PEX1        C1358 -1          A18X+072454Y+115561X0120Y0150R180 S2      
327P0V8_PEX1        C1372 -1          A18X+072454Y+117431X0120Y0150R180 S2      
327P0V8_PEX1        C1365 -1   M      A18X+064954Y+118510X0120Y0150R180 S2      
317P0V8_PEX1        VIA   -    MD0080PA00X+065266Y+117431X0160Y         S0      
317P0V8_PEX1        VIA   -    MD0080PA00X+065266Y+118179X0160Y         S0      
317P0V8_PEX1        VIA   -    MD0080PA00X+064892Y+117805X0160Y         S0      
317P0V8_PEX1        VIA   -    MD0080PA00X+064892Y+118553X0160Y         S0      
317P0V8_PEX1        VIA   -    MD0080PA00X+065266Y+116683X0160Y         S0      
317P0V8_PEX1        VIA   -    MD0080PA00X+064892Y+117057X0160Y         S0      
317P0V8_PEX1        VIA   -    MD0080PA00X+064892Y+115935X0160Y         S0      
317P0V8_PEX1        VIA   -    MD0080PA00X+064892Y+115187X0160Y         S0      
317P0V8_PEX1        VIA   -    MD0080PA00X+064892Y+114439X0160Y         S0      
317P0V8_PEX1        VIA   -    MD0080PA00X+065266Y+115561X0160Y         S0      
317P0V8_PEX1        VIA   -    MD0080PA00X+065266Y+114813X0160Y         S0      
317P0V8_PEX1        VIA   -    MD0080PA00X+066762Y+115561X0160Y         S0      
317P0V8_PEX1        VIA   -    MD0080PA00X+066014Y+115561X0160Y         S0      
317P0V8_PEX1        VIA   -    MD0080PA00X+066014Y+117431X0160Y         S0      
317P0V8_PEX1        VIA   -    MD0080PA00X+066762Y+117431X0160Y         S0      
317P0V8_PEX1        VIA   -    MD0080PA00X+066762Y+116683X0160Y         S0      
317P0V8_PEX1        VIA   -    MD0080PA00X+065640Y+115935X0160Y         S0      
317P0V8_PEX1        VIA   -    MD0080PA00X+066388Y+115935X0160Y         S0      
317P0V8_PEX1        VIA   -    MD0080PA00X+065640Y+117057X0160Y         S0      
317P0V8_PEX1        VIA   -    MD0080PA00X+066014Y+116683X0160Y         S0      
317P0V8_PEX1        VIA   -    MD0080PA00X+066388Y+117057X0160Y         S0      
317P0V8_PEX1        VIA   -    MD0080PA00X+067510Y+115561X0160Y         S0      
317P0V8_PEX1        VIA   -    MD0080PA00X+068258Y+115561X0160Y         S0      
317P0V8_PEX1        VIA   -    MD0080PA00X+067510Y+117431X0160Y         S0      
317P0V8_PEX1        VIA   -    MD0080PA00X+068258Y+117431X0160Y         S0      
317P0V8_PEX1        VIA   -    MD0080PA00X+068632Y+115935X0160Y         S0      
317P0V8_PEX1        VIA   -    MD0080PA00X+068632Y+117057X0160Y         S0      
317P0V8_PEX1        VIA   -    MD0080PA00X+067884Y+115935X0160Y         S0      
317P0V8_PEX1        VIA   -    MD0080PA00X+067136Y+115935X0160Y         S0      
317P0V8_PEX1        VIA   -    MD0080PA00X+067510Y+116683X0160Y         S0      
317P0V8_PEX1        VIA   -    MD0080PA00X+067136Y+117057X0160Y         S0      
317P0V8_PEX1        VIA   -    MD0080PA00X+067884Y+117057X0160Y         S0      
317P0V8_PEX1        VIA   -    MD0080PA00X+068258Y+116683X0160Y         S0      
317P0V8_PEX1        VIA   -    MD0080PA00X+069380Y+117431X0160Y         S0      
317P0V8_PEX1        VIA   -    MD0080PA00X+070128Y+117431X0160Y         S0      
317P0V8_PEX1        VIA   -    MD0080PA00X+070128Y+116683X0160Y         S0      
317P0V8_PEX1        VIA   -    MD0080PA00X+069754Y+115935X0160Y         S0      
317P0V8_PEX1        VIA   -    MD0080PA00X+069754Y+117057X0160Y         S0      
317P0V8_PEX1        VIA   -    MD0080PA00X+069380Y+116683X0160Y         S0      
317P0V8_PEX1        VIA   -    MD0080PA00X+069380Y+115561X0160Y         S0      
317P0V8_PEX1        VIA   -    MD0080PA00X+070128Y+115561X0160Y         S0      
317P0V8_PEX1        VIA   -    MD0080PA00X+070876Y+117431X0160Y         S0      
317P0V8_PEX1        VIA   -    MD0080PA00X+071624Y+117431X0160Y         S0      
317P0V8_PEX1        VIA   -    MD0080PA00X+070876Y+116683X0160Y         S0      
317P0V8_PEX1        VIA   -    MD0080PA00X+071250Y+117057X0160Y         S0      
317P0V8_PEX1        VIA   -    MD0080PA00X+070502Y+117057X0160Y         S0      
317P0V8_PEX1        VIA   -    MD0080PA00X+071250Y+115935X0160Y         S0      
317P0V8_PEX1        VIA   -    MD0080PA00X+070502Y+115935X0160Y         S0      
317P0V8_PEX1        VIA   -    MD0080PA00X+071624Y+116683X0160Y         S0      
317P0V8_PEX1        VIA   -    MD0080PA00X+071624Y+115561X0160Y         S0      
317P0V8_PEX1        VIA   -    MD0080PA00X+070876Y+115561X0160Y         S0      
317P0V8_PEX1        VIA   -    MD0080PA00X+072372Y+117431X0160Y         S0      
317P0V8_PEX1        VIA   -    MD0080PA00X+072372Y+115561X0160Y         S0      
327P0V8_PEX1        PR109 -2          A18X+049637Y+110882X0198Y0197R090 S2      
327P0V8_PEX1        PR113 -2          A18X+052850Y+110882X0198Y0197R090 S2      
327P0V8_PEX1        C4250 -1          A18X+053124Y+121631X0120Y0150R090 S2      
327P0V8_PEX1        C4251 -1          A18X+052813Y+121628X0120Y0150R090 S2      
327P0V8_PEX1        C4264 -1          A18X+050628Y+121628X0120Y0150R090 S2      
327P0V8_PEX1        C4260 -1          A18X+052369Y+121778X0280Y0320R180 S2      
327P0V8_PEX1        C4263 -1          A01X+052612Y+121805X0280Y0320R180 S1      
327P0V8_PEX1        C4247 -1          A01X+049960Y+121735X0280Y0320R180 S1      
327P0V8_PEX1        C4248 -1          A18X+051546Y+121778X0280Y0320R180 S2      
327P0V8_PEX1        C4246 -1   M      A18X+048905Y+121778X0280Y0320R180 S2      
327P0V8_PEX1        C4249 -1          A18X+051019Y+121778X0280Y0320R180 S2      
327P0V8_PEX1        C4262 -1          A18X+050220Y+121778X0280Y0320R180 S2      
327P0V8_PEX1        C4261 -1          A18X+049677Y+121778X0280Y0320R180 S2      
327P0V8_PEX1        C4265 -1          A18X+051967Y+121628X0120Y0150R090 S2      
327P0V8_PEX1        L29   -1   M      A01X+051283Y+125185X0460Y3860R090 S1      
327P0V8_PEX1        R5790 -1A  M      A01X+051283Y+125087X0590Y0790R090 S1      
327P0V8_PEX1        R5790 -1B  M      A01X+051283Y+125332X0100Y0200R090 S1      
327P0V8_PEX1        L28   -1   M      A01X+048923Y+123473X0460Y3860R180 S1      
327P0V8_PEX1        R5789 -1A  M      A01X+048972Y+123473X0590Y0790R180 S1      
327P0V8_PEX1        R5789 -1B  M      A01X+048727Y+123473X0100Y0200R180 S1      
327P0V8_PEX1        PC120 -1          A01X+052707Y+119197X0400Y0500R270 S1      
327P0V8_PEX1        PC102 -1          A01X+050014Y+119197X0400Y0500R270 S1      
327P0V8_PEX1        PC101 -1          A01X+047321Y+119197X0400Y0500R270 S1      
327P0V8_PEX1        PC105 -1          A01X+051360Y+118306X0950Y1110R090 S1      
327P0V8_PEX1        PC119 -1          A01X+048667Y+118306X0950Y1110R090 S1      
327P0V8_PEX1        PC116 -1          A01X+052827Y+115833X0198Y0197R270 S1      
327P0V8_PEX1        PL10  -2          A01X+051248Y+116776X1220Y1320R180 S1      
327P0V8_PEX1        PL9   -2          A01X+048465Y+116776X1220Y1320R180 S1      
327P0V8_PEX1        PC100 -1          A01X+046885Y+115833X0198Y0197R270 S1      
327P0V8_PEX1        L30   -1   M      A18X+051283Y+125185X0460Y3860R270 S2      
327P0V8_PEX1        R5787 -1A  M      A18X+051243Y+125087X0590Y0790R270 S2      
327P0V8_PEX1        R5787 -1B  M      A18X+051243Y+125332X0100Y0200R270 S2      
327P0V8_PEX1        L27   -1   M      A18X+048923Y+123473X0460Y3860     S2      
327P0V8_PEX1        R5788 -1A  M      A18X+048972Y+123473X0590Y0790     S2      
327P0V8_PEX1        R5788 -1B  M      A18X+048727Y+123473X0100Y0200     S2      
327P0V8_PEX1        PR10  -1          A18X+051314Y+119257X0280Y0320     S2      
327P0V8_PEX1        PC117 -1          A18X+050014Y+119197X0400Y0500R090 S2      
327P0V8_PEX1        PC121 -1          A18X+048667Y+119197X0400Y0500R090 S2      
327P0V8_PEX1        PR79  -1          A18X+047145Y+119347X0198Y0197     S2      
327P0V8_PEX1        PC104 -1          A18X+051248Y+116874X0950Y1110R090 S2      
327P0V8_PEX1        PC103 -1          A18X+049856Y+115904X0400Y0500R270 S2      
327P0V8_PEX1        PC118 -1          A18X+048465Y+116874X0950Y1110R090 S2      
327P0V8_PEX1        C1375 -1   M      A18X+071550Y+116683X0120Y0150     S2      
327P0V8_PEX1        C1393 -1   M      A18X+070802Y+116683X0120Y0150     S2      
327P0V8_PEX1        C1374 -1   M      A18X+070128Y+116683X0120Y0150     S2      
327P0V8_PEX1        C1373 -1   M      A18X+069380Y+116683X0120Y0150R180 S2      
327P0V8_PEX1        C1366 -1   M      A18X+067436Y+116683X0120Y0150     S2      
327P0V8_PEX1        C1363 -1   M      A18X+068184Y+116683X0120Y0150     S2      
327P0V8_PEX1        C1370 -1   M      A18X+065940Y+116683X0120Y0150     S2      
327P0V8_PEX1        C1364 -1   M      A18X+066688Y+116683X0120Y0150     S2      
327P0V8_PEX1        C1391 -1   M      A18X+065192Y+116683X0120Y0150     S2      
317P0V8_PEX1        VIA   -    MD0100PA00X+050256Y+115820X0200Y         S0      
317P0V8_PEX1        VIA   -    MD0100PA00X+051056Y+124619X0200Y         S0      
317P0V8_PEX1        VIA   -    MD0100PA00X+051056Y+124219X0200Y         S0      
317P0V8_PEX1        VIA   -    MD0100PA00X+051456Y+124619X0200Y         S0      
317P0V8_PEX1        VIA   -    MD0100PA00X+051456Y+124219X0200Y         S0      
317P0V8_PEX1        VIA   -    MD0100PA00X+049856Y+124619X0200Y         S0      
317P0V8_PEX1        VIA   -    M      A01X+049856Y+124219X0200Y         S2      
017P0V8_PEX1        VIA   -    M      A18X+049856Y+124219X0260Y         S2      
017P0V8_PEX1              -    MD0100PA00X+049856Y+124219                       
317P0V8_PEX1        VIA   -    MD0100PA00X+050256Y+124619X0200Y         S0      
317P0V8_PEX1        VIA   -    MD0100PA00X+050256Y+124219X0200Y         S0      
317P0V8_PEX1        VIA   -    MD0100PA00X+050656Y+124619X0200Y         S0      
317P0V8_PEX1        VIA   -    MD0100PA00X+050656Y+124219X0200Y         S0      
317P0V8_PEX1        VIA   -    MD0100PA00X+049456Y+124219X0200Y         S0      
317P0V8_PEX1        VIA   -    MD0100PA00X+049456Y+124619X0200Y         S0      
317P0V8_PEX1        VIA   -    MD0100PA00X+051056Y+123819X0200Y         S0      
317P0V8_PEX1        VIA   -    MD0100PA00X+051056Y+123419X0200Y         S0      
317P0V8_PEX1        VIA   -    MD0100PA00X+051056Y+123019X0200Y         S0      
317P0V8_PEX1        VIA   -    MD0100PA00X+051056Y+122619X0200Y         S0      
317P0V8_PEX1        VIA   -    MD0100PA00X+051456Y+123819X0200Y         S0      
317P0V8_PEX1        VIA   -    MD0100PA00X+051456Y+123419X0200Y         S0      
317P0V8_PEX1        VIA   -    M      A01X+051456Y+123019X0200Y         S2      
017P0V8_PEX1        VIA   -    M      A18X+051456Y+123019X0260Y         S2      
017P0V8_PEX1              -    MD0100PA00X+051456Y+123019                       
317P0V8_PEX1        VIA   -    MD0100PA00X+051456Y+122619X0200Y         S0      
317P0V8_PEX1        VIA   -    MD0100PA00X+051856Y+123419X0200Y         S0      
317P0V8_PEX1        VIA   -    MD0100PA00X+051856Y+123019X0200Y         S0      
317P0V8_PEX1        VIA   -    MD0100PA00X+051856Y+122619X0200Y         S0      
317P0V8_PEX1        VIA   -    MD0100PA00X+052256Y+122619X0200Y         S0      
317P0V8_PEX1        VIA   -    MD0100PA00X+049456Y+123819X0200Y         S0      
317P0V8_PEX1        VIA   -    MD0100PA00X+049456Y+123419X0200Y         S0      
317P0V8_PEX1        VIA   -    MD0100PA00X+049456Y+123019X0200Y         S0      
317P0V8_PEX1        VIA   -    MD0100PA00X+049456Y+122619X0200Y         S0      
317P0V8_PEX1        VIA   -    MD0100PA00X+049856Y+123819X0200Y         S0      
317P0V8_PEX1        VIA   -    MD0100PA00X+049856Y+123419X0200Y         S0      
317P0V8_PEX1        VIA   -    MD0100PA00X+049856Y+123019X0200Y         S0      
317P0V8_PEX1        VIA   -    M      A01X+049856Y+122619X0200Y         S2      
017P0V8_PEX1        VIA   -    M      A18X+049856Y+122619X0260Y         S2      
017P0V8_PEX1              -    MD0100PA00X+049856Y+122619                       
317P0V8_PEX1        VIA   -    MD0100PA00X+050256Y+123819X0200Y         S0      
317P0V8_PEX1        VIA   -    MD0100PA00X+050256Y+123419X0200Y         S0      
317P0V8_PEX1        VIA   -    MD0100PA00X+050256Y+123019X0200Y         S0      
317P0V8_PEX1        VIA   -    MD0100PA00X+050256Y+122619X0200Y         S0      
317P0V8_PEX1        VIA   -    M      A01X+050656Y+123819X0200Y         S2      
017P0V8_PEX1        VIA   -    M      A18X+050656Y+123819X0260Y         S2      
017P0V8_PEX1              -    MD0100PA00X+050656Y+123819                       
317P0V8_PEX1        VIA   -    MD0100PA00X+050656Y+123419X0200Y         S0      
317P0V8_PEX1        VIA   -    MD0100PA00X+050656Y+123019X0200Y         S0      
317P0V8_PEX1        VIA   -    MD0100PA00X+050656Y+122619X0200Y         S0      
317P0V8_PEX1        VIA   -    MD0100PA00X+051056Y+122219X0200Y         S0      
317P0V8_PEX1        VIA   -    MD0100PA00X+051456Y+122219X0200Y         S0      
317P0V8_PEX1        VIA   -    MD0100PA00X+051856Y+122219X0200Y         S0      
317P0V8_PEX1        VIA   -    MD0100PA00X+052256Y+122219X0200Y         S0      
317P0V8_PEX1        VIA   -    MD0100PA00X+049456Y+122219X0200Y         S0      
317P0V8_PEX1        VIA   -    MD0100PA00X+049856Y+122219X0200Y         S0      
317P0V8_PEX1        VIA   -    MD0100PA00X+050256Y+122219X0200Y         S0      
317P0V8_PEX1        VIA   -    MD0100PA00X+050656Y+122219X0200Y         S0      
317P0V8_PEX1        VIA   -    MD0100PA00X+052307Y+119262X0200Y         S0      
317P0V8_PEX1        VIA   -    MD0100PA00X+052307Y+119012X0200Y         S0      
317P0V8_PEX1        VIA   -    MD0100PA00X+049614Y+119262X0200Y         S0      
317P0V8_PEX1        VIA   -    MD0100PA00X+049614Y+119012X0200Y         S0      
317P0V8_PEX1        VIA   -    MD0100PA00X+050414Y+119262X0200Y    R180 S0      
317P0V8_PEX1        VIA   -    MD0100PA00X+050414Y+119012X0200Y    R180 S0      
317P0V8_PEX1        VIA   -    MD0100PA00X+047721Y+119012X0200Y    R180 S0      
317P0V8_PEX1        VIA   -    MD0100PA00X+047721Y+119262X0200Y    R180 S0      
317P0V8_PEX1        VIA   -    MD0100PA00X+049067Y+119012X0200Y    R180 S0      
317P0V8_PEX1        VIA   -    MD0100PA00X+049067Y+119262X0200Y    R180 S0      
327P0V8_PEX1        PEX1  -AC33       A01X+072185Y+117244X0180Y         S1      
327P0V8_PEX1        PEX1  -AC25       A01X+069193Y+117244X0180Y         S1      
327P0V8_PEX1        PEX1  -AC17       A01X+066201Y+117244X0180Y         S1      
327P0V8_PEX1        PEX1  -AA15       A01X+065453Y+117992X0180Y         S1      
327P0V8_PEX1        PEX1  -Y14 M      A01X+065079Y+118366X0180Y         S1      
317P0V8_PEX1        VIA   -    MD0100PA00X+052065Y+117488X0200Y         S0      
317P0V8_PEX1        VIA   -    MD0100PA00X+052315Y+117488X0200Y         S0      
317P0V8_PEX1        VIA   -    MD0100PA00X+052075Y+117942X0200Y    R180 S0      
317P0V8_PEX1        VIA   -    MD0100PA00X+052075Y+118192X0200Y    R180 S0      
317P0V8_PEX1        VIA   -    MD0100PA00X+052075Y+118442X0200Y    R180 S0      
317P0V8_PEX1        VIA   -    MD0100PA00X+052075Y+118692X0200Y    R180 S0      
317P0V8_PEX1        VIA   -    MD0100PA00X+050238Y+117488X0200Y         S0      
317P0V8_PEX1        VIA   -    MD0100PA00X+049532Y+117488X0200Y         S0      
317P0V8_PEX1        VIA   -    MD0100PA00X+049282Y+117488X0200Y         S0      
317P0V8_PEX1        VIA   -    MD0100PA00X+049382Y+117942X0200Y    R180 S0      
317P0V8_PEX1        VIA   -    MD0100PA00X+049382Y+118192X0200Y    R180 S0      
317P0V8_PEX1        VIA   -    MD0100PA00X+049382Y+118442X0200Y    R180 S0      
317P0V8_PEX1        VIA   -    MD0100PA00X+049382Y+118692X0200Y    R180 S0      
317P0V8_PEX1        VIA   -    MD0100PA00X+050488Y+117488X0200Y         S0      
317P0V8_PEX1        VIA   -    MD0100PA00X+050645Y+118671X0200Y         S0      
317P0V8_PEX1        VIA   -    MD0100PA00X+050645Y+118421X0200Y         S0      
317P0V8_PEX1        VIA   -    MD0100PA00X+050645Y+118171X0200Y         S0      
317P0V8_PEX1        VIA   -    MD0100PA00X+050645Y+117921X0200Y         S0      
317P0V8_PEX1        VIA   -    MD0100PA00X+047705Y+117488X0200Y         S0      
317P0V8_PEX1        VIA   -    MD0100PA00X+047952Y+118671X0200Y         S0      
317P0V8_PEX1        VIA   -    MD0100PA00X+047952Y+118421X0200Y         S0      
317P0V8_PEX1        VIA   -    MD0100PA00X+047952Y+118171X0200Y         S0      
317P0V8_PEX1        VIA   -    MD0100PA00X+047952Y+117921X0200Y         S0      
317P0V8_PEX1        VIA   -    MD0100PA00X+047455Y+117488X0200Y         S0      
327P0V8_PEX1        PEX1  -AE31       A01X+071437Y+116496X0180Y         S1      
327P0V8_PEX1        PEX1  -AE29       A01X+070689Y+116496X0180Y         S1      
327P0V8_PEX1        PEX1  -AD30M      A01X+071063Y+116870X0180Y         S1      
327P0V8_PEX1        PEX1  -AC31M      A01X+071437Y+117244X0180Y         S1      
327P0V8_PEX1        PEX1  -AE25       A01X+069193Y+116496X0180Y         S1      
327P0V8_PEX1        PEX1  -AC27M      A01X+069941Y+117244X0180Y         S1      
327P0V8_PEX1        PEX1  -AD26       A01X+069567Y+116870X0180Y         S1      
327P0V8_PEX1        PEX1  -AE27       A01X+069941Y+116496X0180Y         S1      
327P0V8_PEX1        PEX1  -AC29M      A01X+070689Y+117244X0180Y         S1      
327P0V8_PEX1        PEX1  -AD28M      A01X+070315Y+116870X0180Y         S1      
327P0V8_PEX1        PEX1  -AD22M      A01X+068071Y+116870X0180Y         S1      
327P0V8_PEX1        PEX1  -AE23       A01X+068445Y+116496X0180Y         S1      
327P0V8_PEX1        PEX1  -AC21M      A01X+067697Y+117244X0180Y         S1      
327P0V8_PEX1        PEX1  -AE21       A01X+067697Y+116496X0180Y         S1      
327P0V8_PEX1        PEX1  -AD20M      A01X+067323Y+116870X0180Y         S1      
327P0V8_PEX1        PEX1  -AC19M      A01X+066949Y+117244X0180Y         S1      
327P0V8_PEX1        PEX1  -AD24       A01X+068819Y+116870X0180Y         S1      
327P0V8_PEX1        PEX1  -AC23M      A01X+068445Y+117244X0180Y         S1      
327P0V8_PEX1        PEX1  -AC15M      A01X+065453Y+117244X0180Y         S1      
327P0V8_PEX1        PEX1  -AD16M      A01X+065827Y+116870X0180Y         S1      
327P0V8_PEX1        PEX1  -AE17       A01X+066201Y+116496X0180Y         S1      
327P0V8_PEX1        PEX1  -AB14M      A01X+065079Y+117618X0180Y         S1      
327P0V8_PEX1        PEX1  -AE19       A01X+066949Y+116496X0180Y         S1      
327P0V8_PEX1        PEX1  -AD18M      A01X+066575Y+116870X0180Y         S1      
327P0V8_PEX1        PEX1  -AF14       A01X+065079Y+116122X0180Y         S1      
327P0V8_PEX1        PEX1  -AE15       A01X+065453Y+116496X0180Y         S1      
327P0V8_PEX1        PEX1  -AD14M      A01X+065079Y+116870X0180Y         S1      
317P0V8_PEX1        VIA   -    MD0100PA00X+052827Y+116083X0200Y         S0      
317P0V8_PEX1        VIA   -    MD0100PA00X+052065Y+117238X0200Y         S0      
317P0V8_PEX1        VIA   -    MD0100PA00X+052315Y+117238X0200Y         S0      
317P0V8_PEX1        VIA   -    MD0100PA00X+052315Y+116988X0200Y         S0      
317P0V8_PEX1        VIA   -    MD0100PA00X+052315Y+116738X0200Y         S0      
317P0V8_PEX1        VIA   -    MD0100PA00X+052315Y+116488X0200Y         S0      
317P0V8_PEX1        VIA   -    MD0100PA00X+052315Y+116238X0200Y         S0      
317P0V8_PEX1        VIA   -    MD0100PA00X+052850Y+110636X0200Y         S0      
317P0V8_PEX1        VIA   -    MD0100PA00X+052065Y+116238X0200Y         S0      
317P0V8_PEX1        VIA   -    MD0100PA00X+052065Y+116488X0200Y         S0      
317P0V8_PEX1        VIA   -    MD0100PA00X+052065Y+116738X0200Y         S0      
317P0V8_PEX1        VIA   -    MD0100PA00X+052065Y+116988X0200Y         S0      
317P0V8_PEX1        VIA   -    MD0100PA00X+049532Y+116238X0200Y         S0      
317P0V8_PEX1        VIA   -    MD0100PA00X+049532Y+116488X0200Y         S0      
317P0V8_PEX1        VIA   -    MD0100PA00X+049532Y+116738X0200Y         S0      
317P0V8_PEX1        VIA   -    MD0100PA00X+049532Y+116988X0200Y         S0      
317P0V8_PEX1        VIA   -    MD0100PA00X+049532Y+117238X0200Y         S0      
317P0V8_PEX1        VIA   -    MD0100PA00X+049282Y+117238X0200Y         S0      
317P0V8_PEX1        VIA   -    MD0100PA00X+049282Y+116988X0200Y         S0      
317P0V8_PEX1        VIA   -    MD0100PA00X+049282Y+116738X0200Y         S0      
317P0V8_PEX1        VIA   -    MD0100PA00X+049282Y+116488X0200Y         S0      
317P0V8_PEX1        VIA   -    MD0100PA00X+049282Y+116238X0200Y         S0      
317P0V8_PEX1        VIA   -    MD0100PA00X+049637Y+110630X0200Y         S0      
317P0V8_PEX1        VIA   -    MD0100PA00X+050488Y+116238X0200Y         S0      
317P0V8_PEX1        VIA   -    MD0100PA00X+050488Y+116488X0200Y         S0      
317P0V8_PEX1        VIA   -    MD0100PA00X+050488Y+116738X0200Y         S0      
317P0V8_PEX1        VIA   -    MD0100PA00X+050488Y+116988X0200Y         S0      
317P0V8_PEX1        VIA   -    MD0100PA00X+050488Y+117238X0200Y         S0      
317P0V8_PEX1        VIA   -    MD0100PA00X+050238Y+116238X0200Y         S0      
317P0V8_PEX1        VIA   -    MD0100PA00X+050238Y+116488X0200Y         S0      
317P0V8_PEX1        VIA   -    MD0100PA00X+050238Y+116738X0200Y         S0      
317P0V8_PEX1        VIA   -    MD0100PA00X+050238Y+116988X0200Y         S0      
317P0V8_PEX1        VIA   -    MD0100PA00X+050238Y+117238X0200Y         S0      
317P0V8_PEX1        VIA   -    MD0100PA00X+047705Y+116238X0200Y         S0      
317P0V8_PEX1        VIA   -    MD0100PA00X+047705Y+116488X0200Y         S0      
317P0V8_PEX1        VIA   -    MD0100PA00X+047705Y+116738X0200Y         S0      
317P0V8_PEX1        VIA   -    MD0100PA00X+047705Y+116988X0200Y         S0      
317P0V8_PEX1        VIA   -    MD0100PA00X+047705Y+117238X0200Y         S0      
317P0V8_PEX1        VIA   -    MD0100PA00X+046885Y+116083X0200Y         S0      
317P0V8_PEX1        VIA   -    MD0100PA00X+047455Y+116238X0200Y         S0      
317P0V8_PEX1        VIA   -    MD0100PA00X+047455Y+116488X0200Y         S0      
317P0V8_PEX1        VIA   -    MD0100PA00X+047455Y+116738X0200Y         S0      
317P0V8_PEX1        VIA   -    MD0100PA00X+047455Y+116988X0200Y         S0      
317P0V8_PEX1        VIA   -    MD0100PA00X+047455Y+117238X0200Y         S0      
327P0V8_PEX1        PEX1  -AG33       A01X+072185Y+115748X0180Y         S1      
327P0V8_PEX1        PEX1  -AG29M      A01X+070689Y+115748X0180Y         S1      
327P0V8_PEX1        PEX1  -AF28       A01X+070315Y+116122X0180Y         S1      
327P0V8_PEX1        PEX1  -AF30       A01X+071063Y+116122X0180Y         S1      
327P0V8_PEX1        PEX1  -AG31M      A01X+071437Y+115748X0180Y         S1      
327P0V8_PEX1        PEX1  -AG27M      A01X+069941Y+115748X0180Y         S1      
327P0V8_PEX1        PEX1  -AF26       A01X+069567Y+116122X0180Y         S1      
327P0V8_PEX1        PEX1  -AG25       A01X+069193Y+115748X0180Y         S1      
327P0V8_PEX1        PEX1  -AG23M      A01X+068445Y+115748X0180Y         S1      
327P0V8_PEX1        PEX1  -AF24       A01X+068819Y+116122X0180Y         S1      
327P0V8_PEX1        PEX1  -AF22       A01X+068071Y+116122X0180Y         S1      
327P0V8_PEX1        PEX1  -AG21M      A01X+067697Y+115748X0180Y         S1      
327P0V8_PEX1        PEX1  -AF18       A01X+066575Y+116122X0180Y         S1      
327P0V8_PEX1        PEX1  -AG17M      A01X+066201Y+115748X0180Y         S1      
327P0V8_PEX1        PEX1  -AG19M      A01X+066949Y+115748X0180Y         S1      
327P0V8_PEX1        PEX1  -AF20       A01X+067323Y+116122X0180Y         S1      
327P0V8_PEX1        PEX1  -AJ15       A01X+065453Y+115000X0180Y         S1      
327P0V8_PEX1        PEX1  -AK14M      A01X+065079Y+114626X0180Y         S1      
327P0V8_PEX1        PEX1  -AF16       A01X+065827Y+116122X0180Y         S1      
327P0V8_PEX1        PEX1  -AG15M      A01X+065453Y+115748X0180Y         S1      
327P0V8_PEX1        PEX1  -AH14M      A01X+065079Y+115374X0180Y         S1      
327m3480            PC6608-1          A18X+040518Y+108588X0400Y0500R180 S2      
317m3480            VIA   -    MD0100PA00X+040885Y+109096X0200Y    R090 S0      
327m3480            PC6607-1          A18X+040519Y+109307X0400Y0500R180 S2      
327m3480            PC6609-1          A18X+043974Y+109309X0400Y0500     S2      
317m3480            VIA   -    MD0100PA00X+041230Y+109123X0200Y    R090 S0      
317m3480            VIA   -    MD0100PA00X+041202Y+108820X0200Y    R090 S0      
317m3480            VIA   -    MD0100PA00X+041502Y+108820X0200Y    R090 S2      
317m3480            VIA   -    MD0100PA00X+041502Y+108520X0200Y    R090 S0      
317m3480            VIA   -    MD0100PA00X+041499Y+108250X0200Y         S0      
317m3480            VIA   -    MD0100PA00X+041202Y+108520X0200Y    R090 S0      
317m3480            VIA   -    MD0100PA00X+041199Y+108250X0200Y         S0      
327m3480            PC6610-1          A01X+040518Y+108588X0400Y0500     S1      
327m3480            PL5   -1          A01X+041097Y+107868X0420Y0990R270 S1      
327m3480            PC64  -1          A01X+043824Y+108033X0630Y1380R180 S1      
327m3480            PC60  -1          A18X+044536Y+111775X0400Y0500R090 S2      
327m3480            PC63  -1          A18X+044322Y+110990X0400Y0500R270 S2      
327m3480            PC79  -1          A18X+043736Y+111775X0400Y0500R090 S2      
327m3480            PC77  -1          A18X+041323Y+111775X0400Y0500R090 S2      
327m3480            PC78  -1          A18X+041110Y+110990X0400Y0500R270 S2      
327m3480            PC62  -1          A18X+040523Y+111775X0400Y0500R090 S2      
327m3480            PU8   -30         A01X+044123Y+111023X0090Y0240R180 S1      
327m3480            PC76  -1          A01X+043529Y+111982X0198Y0197R090 S1      
317m3480            VIA   -    MD0100PA00X+043692Y+110940X0200Y         S0      
317m3480            VIA   -    MD0100PA00X+043702Y+111240X0200Y         S0      
317m3480            VIA   -    MD0100PA00X+043482Y+111090X0200Y         S0      
317m3480            VIA   -    MD0100PA00X+043482Y+111380X0200Y         S0      
317m3480            VIA   -    MD0100PA00X+043912Y+111060X0200Y         S0      
317m3480            VIA   -    MD0100PA00X+044136Y+111880X0200Y         S0      
317m3480            VIA   -    MD0100PA00X+044136Y+111610X0200Y         S0      
317m3480            VIA   -    MD0100PA00X+043991Y+111365X0200Y         S0      
317m3480            VIA   -    MD0100PA00X+044671Y+111365X0200Y         S0      
317m3480            VIA   -    MD0100PA00X+044421Y+111365X0200Y         S0      
327m3480            PU8   -25_2M      A01X+044324Y+111661X0810Y0910R090 S1      
327m3480            PU7   -30         A01X+040910Y+111023X0090Y0240R180 S1      
327m3480            PC59  -1          A01X+040316Y+111982X0198Y0197R090 S1      
317m3480            VIA   -    MD0100PA00X+040270Y+111380X0200Y         S0      
317m3480            VIA   -    MD0100PA00X+040480Y+110940X0200Y         S0      
317m3480            VIA   -    MD0100PA00X+040490Y+111240X0200Y         S0      
317m3480            VIA   -    MD0100PA00X+040700Y+111060X0200Y         S0      
317m3480            VIA   -    MD0100PA00X+040923Y+111880X0200Y         S0      
317m3480            VIA   -    MD0100PA00X+040778Y+111365X0200Y         S0      
317m3480            VIA   -    MD0100PA00X+041208Y+111365X0200Y         S0      
317m3480            VIA   -    MD0100PA00X+041458Y+111365X0200Y         S0      
327m3480            PU7   -25_2M      A01X+041111Y+111661X0810Y0910R090 S1      
317m3480            VIA   -    MD0100PA00X+040270Y+111090X0200Y         S0      
327m3480            PC75  -1          A01X+044124Y+109883X0198Y0197     S1      
317m3480            VIA   -    MD0100PA00X+043482Y+110800X0200Y         S0      
317m3480            VIA   -    MD0100PA00X+043624Y+109309X0200Y         S0      
317m3480            VIA   -    MD0100PA00X+043902Y+110800X0200Y         S0      
327m3480            PC58  -1          A01X+040912Y+109883X0198Y0197     S1      
317m3480            VIA   -    MD0100PA00X+040270Y+110800X0200Y         S0      
317m3480            VIA   -    MD0100PA00X+040690Y+110800X0200Y         S0      
327m3480            PC80  -1          A01X+043974Y+109309X0400Y0500R180 S1      
317m3480            VIA   -    MD0100PA00X+043088Y+108182X0200Y         S2      
317m3480            VIA   -    MD0100PA00X+043338Y+108182X0200Y         S0      
317m3480            VIA   -    MD0100PA00X+043624Y+109029X0200Y         S0      
317m3480            VIA   -    MD0100PA00X+043338Y+108432X0200Y         S0      
317m3480            VIA   -    MD0100PA00X+043338Y+108682X0200Y         S0      
317m3480            VIA   -    MD0100PA00X+043088Y+108682X0200Y         S0      
317m3480            VIA   -    MD0100PA00X+043088Y+108432X0200Y         S0      
317m3480            VIA   -    MD0100PA00X+043338Y+108932X0200Y         S0      
317m3480            VIA   -    MD0100PA00X+043338Y+109182X0200Y         S0      
317m3480            VIA   -    MD0100PA00X+040902Y+108520X0200Y    R090 S0      
317m3480            VIA   -    MD0100PA00X+040902Y+108770X0200Y    R090 S0      
317m3480            VIA   -    MD0100PA00X+040899Y+108250X0200Y         S0      
327m3480            PC61  -1          A01X+040519Y+109307X0400Y0500     S1      
317m3480            VIA   -    MD0100PA00X+040885Y+109396X0200Y    R090 S0      
327m3481            VIA   -    M      A18X+053857Y+128914X0260Y         S2      
327m3481            PJ21  -1          A18X+053029Y+128880X0200Y0400R270 S2      
317m3481            VIA   -    MD0080PA00X+074242Y+118927X0160Y         S0      
327m3481            PEX1  -W39        A01X+074429Y+118740X0180Y         S1      
327m3482            VIA   -    M      A01X+049566Y+101542X0300Y         S1      
327m3482            PU6   -15         A01X+048494Y+101652X0070Y0240R090 S1      
327m3482            PR83  -1          A01X+050102Y+101227X0198Y0197     S1      
327m3483            PR77  -1          A01X+049436Y+103218X0198Y0197R180 S1      
327m3483            VIA   -           A01X+050142Y+103768X0300Y         S1      
327m3483            PJ5   -2   M      A01X+049574Y+103768X0280Y0320R270 S1      
327P0V8_PEX0_VCC2   PR7166-2          A18X+045368Y+111123X0198Y0197R180 S2      
327P0V8_PEX0_VCC2   R6763 -1   M      A18X+045758Y+111247X0198Y0197R090 S2      
327P0V8_PEX0_VCC2   PR103 -2   M      A18X+046091Y+111582X0198Y0197R090 S2      
317P0V8_PEX0_VCC2   VIA   -    MD0100PA00X+046360Y+111590X0200Y         S0      
327P0V8_PEX0_VCC2   PU8   -3          A01X+045879Y+111624X0090Y0240R270 S1      
327P0V8_PEX0_VCC2   PC81  -1   M      A01X+046341Y+111347X0198Y0197R270 S1      
327m3484            PR95  -1          A18X+045638Y+102362X0198Y0197R270 S2      
317m3484            VIA   -    M      A01X+045988Y+101886X0200Y         S2      
017m3484            VIA   -    M      A18X+045988Y+101886X0260Y         S2      
017m3484                  -    MD0100PA00X+045988Y+101886                       
327m3484            PU6   -35         A01X+046605Y+101809X0070Y0240R090 S1      
327m3484            PC55  -1   M      A18X+046038Y+102362X0198Y0197R270 S2      
327m3485            PR104 -2          A01X+044658Y+110256X0198Y0197R270 S1      
327m3485            PC82  -2          A01X+044280Y+110256X0198Y0197R270 S1      
327P0V8_PEX1_TSEN   PR90  -2          A18X+046438Y+102676X0198Y0197R270 S2      
317P0V8_PEX1_TSEN   VIA   -    M      A01X+046438Y+103853X0200Y         S2      
017P0V8_PEX1_TSEN   VIA   -    M      A18X+046438Y+103853X0260Y         S2      
017P0V8_PEX1_TSEN         -    MD0100PA00X+046438Y+103853                       
317P0V8_PEX1_TSEN   VIA   -    MD0100PA00X+048637Y+110555X0200Y         S0      
327P0V8_PEX1_TSEN   PU9   -36         A01X+048532Y+111023X0090Y0240R180 S1      
327P0V8_PEX1_TSEN   PU10  -36         A01X+051745Y+111023X0090Y0240R180 S1      
317P0V8_PEX1_TSEN   VIA   -    MD0100PA00X+051850Y+110555X0200Y         S0      
327m3486            PR104 -1          A01X+044658Y+110570X0198Y0197R270 S1      
327m3486            PU8   -33         A01X+044654Y+111023X0090Y0240R180 S1      
327m3487            PL6   -1          A01X+041906Y+114354X1220Y1320R180 S1      
327m3487            PU7   -10_1       A01X+041721Y+113307X0240Y1700R270 S1      
327m3488            PR106 -1          A01X+045466Y+110192X0198Y0197R270 S1      
317m3488            VIA   -    M      A01X+045547Y+110434X0200Y         S2      
017m3488            VIA   -    M      A18X+045547Y+110434X0260Y         S2      
017m3488                  -    MD0100PA00X+045547Y+110434                       
327m3488            PU8   -37         A01X+045363Y+111023X0090Y0240R180 S1      
327m3489            PR100 -1          A01X+041446Y+110570X0198Y0197R270 S1      
327m3489            PU7   -33         A01X+041442Y+111023X0090Y0240R180 S1      
327m3490            PR101 -1          A18X+043162Y+111205X0198Y0197R090 S2      
327m3490            PU7   -1          A01X+042666Y+111269X0090Y0240R270 S1      
317m3490            VIA   -    MD0100PA00X+042781Y+111009X0200Y         S0      
317P0V8_PEX0_VCC1   VIA   -    MD0100PA00X+043148Y+111590X0200Y         S0      
327P0V8_PEX0_VCC1   PU7   -3          A01X+042666Y+111624X0090Y0240R270 S1      
327P0V8_PEX0_VCC1   PC65  -1   M      A01X+043128Y+111347X0198Y0197R270 S1      
327P0V8_PEX0_VCC1   PR99  -2   M      A18X+042878Y+111582X0198Y0197R090 S2      
327P0V8_PEX0_VCC1   PR7167-2          A18X+042166Y+111123X0198Y0197R180 S2      
327P0V8_PEX0_VCC1   R6762 -1   M      A18X+042543Y+111247X0198Y0197R090 S2      
327m3491            PR105 -1          A18X+046397Y+111197X0198Y0197R090 S2      
327m3491            PU8   -1          A01X+045879Y+111269X0090Y0240R270 S1      
317m3491            VIA   -    MD0100PA00X+045994Y+111009X0200Y         S0      
317m3492            VIA   -    MD0080PA00X+020305Y+112943X0160Y         S0      
317m3492            VIA   -    MD0080PA00X+021053Y+112943X0160Y         S0      
317m3492            VIA   -    MD0080PA00X+021427Y+112943X0160Y         S0      
317m3492            VIA   -    MD0080PA00X+020305Y+120049X0160Y         S0      
317m3492            VIA   -    MD0080PA00X+020679Y+120049X0160Y         S0      
317m3492            VIA   -    MD0080PA00X+019931Y+120049X0160Y         S0      
317m3492            VIA   -    MD0080PA00X+021053Y+120049X0160Y         S0      
317m3492            VIA   -    MD0080PA00X+021427Y+120049X0160Y         S0      
317m3492            VIA   -    MD0080PA00X+020679Y+112943X0160Y         S0      
317m3492            VIA   -    MD0080PA00X+019931Y+112943X0160Y         S0      
317m3492            VIA   -    MD0080PA00X+022923Y+120049X0160Y         S0      
317m3492            VIA   -    MD0080PA00X+022549Y+120049X0160Y         S0      
317m3492            VIA   -    MD0080PA00X+022175Y+120049X0160Y         S0      
317m3492            VIA   -    MD0080PA00X+021801Y+120049X0160Y         S0      
317m3492            VIA   -    MD0080PA00X+022549Y+112943X0160Y         S0      
317m3492            VIA   -    MD0080PA00X+022175Y+112943X0160Y         S0      
317m3492            VIA   -    MD0080PA00X+021801Y+112943X0160Y         S0      
317m3492            VIA   -    MD0080PA00X+022923Y+112943X0160Y         S0      
317m3492            VIA   -    MD0080PA00X+024045Y+120049X0160Y         S0      
317m3492            VIA   -    MD0080PA00X+023671Y+112943X0160Y         S0      
317m3492            VIA   -    MD0080PA00X+024045Y+112943X0160Y         S0      
317m3492            VIA   -    MD0080PA00X+024419Y+112943X0160Y         S0      
317m3492            VIA   -    MD0080PA00X+024419Y+120049X0160Y         S0      
317m3492            VIA   -    MD0080PA00X+023671Y+120049X0160Y         S0      
317m3492            VIA   -    MD0080PA00X+025167Y+112943X0160Y         S0      
317m3492            VIA   -    MD0080PA00X+025541Y+112943X0160Y         S0      
317m3492            VIA   -    MD0080PA00X+026289Y+112943X0160Y         S0      
317m3492            VIA   -    MD0080PA00X+025915Y+112943X0160Y         S0      
317m3492            VIA   -    MD0080PA00X+024793Y+112943X0160Y         S0      
317m3492            VIA   -    MD0080PA00X+025541Y+120049X0160Y         S0      
317m3492            VIA   -    MD0080PA00X+024793Y+120049X0160Y         S0      
317m3492            VIA   -    MD0080PA00X+025167Y+120049X0160Y         S0      
317m3492            VIA   -    MD0080PA00X+026289Y+120049X0160Y         S0      
317m3492            VIA   -    MD0080PA00X+025915Y+120049X0160Y         S0      
317m3492            VIA   -    MD0080PA00X+026663Y+112943X0160Y         S0      
317m3492            VIA   -    MD0080PA00X+026663Y+120049X0160Y         S0      
317m3492            VIA   -    MD0080PA00X+028533Y+117431X0160Y         S0      
317m3492            VIA   -    MD0080PA00X+028533Y+115935X0160Y         S0      
317m3492            VIA   -    MD0080PA00X+028533Y+116683X0160Y         S0      
317m3492            VIA   -    MD0080PA00X+028533Y+117057X0160Y         S0      
317m3492            VIA   -    MD0080PA00X+028533Y+115561X0160Y         S0      
327m3492            C4224 -1          A01X+006719Y+104614X0120Y0150     S1      
327m3492            C4225 -1          A01X+006716Y+105078X0120Y0150     S1      
327m3492            C4238 -1          A01X+006721Y+105565X0120Y0150     S1      
327m3492            C4239 -1          A01X+006727Y+106081X0120Y0150     S1      
327m3492            R6469 -1          A01X+000681Y+100570X0198Y0197R270 S1      
327m3492            R6462 -1          A01X+003366Y+100570X0198Y0197R270 S1      
327m3492            R6464 -1          A01X+004586Y+100570X0198Y0197R270 S1      
327m3492            R6461 -1          A01X+002756Y+100570X0198Y0197R270 S1      
327m3492            R6463 -1          A01X+003955Y+100570X0198Y0197R270 S1      
327m3492            R6474 -1          A01X+005195Y+100570X0198Y0197R270 S1      
327m3492            R6473 -1          A01X+005783Y+100570X0198Y0197R270 S1      
327m3492            R6465 -1          A01X+006577Y+100570X0198Y0197R270 S1      
327m3492            R6466 -1          A01X+006178Y+100570X0198Y0197R270 S1      
327m3492            R6470 -1          A01X+001070Y+100570X0198Y0197R270 S1      
327m3492            R6471 -1          A01X+001464Y+100570X0198Y0197R270 S1      
327m3492            R6472 -1          A01X+002151Y+100570X0198Y0197R270 S1      
327m3492            C2962 -1          A18X+026300Y+120131X0120Y0150R270 S2      
327m3492            C2980 -1          A18X+026674Y+120131X0120Y0150R270 S2      
327m3492            C2956 -1          A18X+025926Y+120131X0120Y0150R270 S2      
327m3492            C2954 -1          A18X+025552Y+120131X0120Y0150R270 S2      
327m3492            C2952 -1          A18X+025178Y+120131X0120Y0150R270 S2      
327m3492            C2966 -1          A18X+024804Y+120131X0120Y0150R270 S2      
327m3492            C2978 -1          A18X+024056Y+120131X0120Y0150R270 S2      
327m3492            C2975 -1          A18X+023682Y+120131X0120Y0150R270 S2      
327m3492            C2964 -1          A18X+024430Y+120131X0120Y0150R270 S2      
327m3492            C2945 -1          A18X+023292Y+120008X0280Y0320     S2      
327m3492            C2967 -1          A18X+022902Y+120131X0120Y0150R270 S2      
327m3492            C2974 -1          A18X+022528Y+120131X0120Y0150R270 S2      
327m3492            C2970 -1          A18X+022154Y+120131X0120Y0150R270 S2      
327m3492            C2976 -1          A18X+021780Y+120131X0120Y0150R270 S2      
327m3492            C2986 -1          A18X+021032Y+120131X0120Y0150R270 S2      
327m3492            C2983 -1          A18X+020284Y+120131X0120Y0150R270 S2      
327m3492            C2982 -1          A18X+020658Y+120131X0120Y0150R270 S2      
327m3492            C2973 -1          A18X+021406Y+120131X0120Y0150R270 S2      
327m3492            C2984 -1          A18X+019910Y+120131X0120Y0150R270 S2      
327m3492            PEX0  -T33        A01X+026476Y+119862X0180Y         S1      
327m3492            PEX0  -T31        A01X+025728Y+119862X0180Y         S1      
327m3492            PEX0  -T32        A01X+026102Y+119862X0180Y         S1      
327m3492            PEX0  -T29        A01X+024980Y+119862X0180Y         S1      
327m3492            PEX0  -T28        A01X+024606Y+119862X0180Y         S1      
327m3492            PEX0  -T30        A01X+025354Y+119862X0180Y         S1      
327m3492            PEX0  -T25        A01X+023484Y+119862X0180Y         S1      
327m3492            PEX0  -T27        A01X+024232Y+119862X0180Y         S1      
327m3492            PEX0  -T26        A01X+023858Y+119862X0180Y         S1      
327m3492            PEX0  -T21        A01X+021988Y+119862X0180Y         S1      
327m3492            PEX0  -T22        A01X+022362Y+119862X0180Y         S1      
327m3492            PEX0  -T23        A01X+022736Y+119862X0180Y         S1      
327m3492            PEX0  -T24        A01X+023110Y+119862X0180Y         S1      
327m3492            PEX0  -T20        A01X+021614Y+119862X0180Y         S1      
327m3492            PEX0  -T19        A01X+021240Y+119862X0180Y         S1      
327m3492            PEX0  -T16        A01X+020118Y+119862X0180Y         S1      
327m3492            PEX0  -T18        A01X+020866Y+119862X0180Y         S1      
327m3492            PEX0  -T17        A01X+020492Y+119862X0180Y         S1      
327m3492            C2950 -1          A18X+028615Y+115748X0120Y0150R180 S2      
327m3492            C2949 -1          A18X+028615Y+116122X0120Y0150R180 S2      
327m3492            C2948 -1          A18X+028615Y+116870X0120Y0150R180 S2      
327m3492            C2947 -1          A18X+028615Y+117244X0120Y0150R180 S2      
327m3492            C2977 -1          A18X+028615Y+116496X0120Y0150R180 S2      
327m3492            PEX0  -AC38       A01X+028346Y+117244X0180Y         S1      
327m3492            PEX0  -AD38       A01X+028346Y+116870X0180Y         S1      
327m3492            PEX0  -AE38       A01X+028346Y+116496X0180Y         S1      
327m3492            PEX0  -AF38       A01X+028346Y+116122X0180Y         S1      
327m3492            PEX0  -AG38       A01X+028346Y+115748X0180Y         S1      
327m3492            L84   -2   M      A01X+005005Y+104137X0460Y3860     S1      
327m3492            R6129 -2A  M      A01X+005054Y+104168X0590Y0790     S1      
327m3492            R6129 -2B  M      A01X+004809Y+104168X0100Y0200     S1      
327m3492            L82   -2   M      A01X+001592Y+104168X0460Y3860R180 S1      
327m3492            R6127 -2A  M      A01X+001542Y+104168X0590Y0790R180 S1      
327m3492            R6127 -2B  M      A01X+001787Y+104168X0100Y0200R180 S1      
317m3492            VIA   -    MD0100PA00X+005320Y+101776X0200Y         S0      
317m3492            VIA   -    MD0100PA00X+005320Y+101420X0200Y         S0      
327m3492            L85   -2   M      A18X+005005Y+104137X0460Y3860R180 S2      
327m3492            R6128 -2A  M      A18X+005054Y+104168X0590Y0790R180 S2      
327m3492            R6128 -2B  M      A18X+004809Y+104168X0100Y0200R180 S2      
317m3492            VIA   -    MD0100PA00X+004870Y+101798X0200Y         S0      
317m3492            VIA   -    MD0100PA00X+003820Y+101776X0200Y         S0      
317m3492            VIA   -    MD0100PA00X+004420Y+101776X0200Y         S0      
317m3492            VIA   -    MD0100PA00X+004120Y+101420X0200Y         S0      
317m3492            VIA   -    MD0100PA00X+004720Y+101420X0200Y         S0      
317m3492            VIA   -    MD0100PA00X+003520Y+101420X0200Y         S0      
317m3492            VIA   -    MD0100PA00X+002620Y+101776X0200Y         S0      
317m3492            VIA   -    MD0100PA00X+003220Y+101776X0200Y         S0      
317m3492            VIA   -    MD0100PA00X+002920Y+101420X0200Y         S0      
327m3492            L83   -2   M      A18X+001592Y+104168X0460Y3860     S2      
327m3492            R6126 -2A  M      A18X+001542Y+104168X0590Y0790     S2      
327m3492            R6126 -2B  M      A18X+001787Y+104168X0100Y0200     S2      
317m3492            VIA   -    MD0100PA00X+002020Y+101776X0200Y         S0      
317m3492            VIA   -    MD0100PA00X+002020Y+101420X0200Y         S0      
317m3492            VIA   -    MD0100PA00X+001420Y+101776X0200Y         S0      
317m3492            VIA   -    M      A01X+001420Y+101420X0200Y         S2      
017m3492            VIA   -    M      A18X+001420Y+101420X0260Y         S2      
017m3492                  -    MD0100PA00X+001420Y+101420                       
317m3492            VIA   -    MD0100PA00X+003882Y+100927X0200Y         S0      
317m3492            VIA   -    MD0100PA00X+004500Y+100951X0200Y         S0      
317m3492            VIA   -    MD0100PA00X+005054Y+100959X0200Y         S0      
317m3492            VIA   -    M      A01X+004247Y+100674X0200Y         S2      
017m3492            VIA   -    M      A18X+004247Y+100674X0260Y         S2      
017m3492                  -    MD0100PA00X+004247Y+100674                       
317m3492            VIA   -    MD0100PA00X+004868Y+100651X0200Y         S0      
317m3492            VIA   -    MD0100PA00X+002616Y+100998X0200Y         S0      
317m3492            VIA   -    MD0100PA00X+003209Y+100975X0200Y         S0      
317m3492            VIA   -    MD0100PA00X+002446Y+100640X0200Y         S0      
317m3492            VIA   -    M      A01X+003048Y+100651X0200Y         S2      
017m3492            VIA   -    M      A18X+003048Y+100651X0260Y         S2      
017m3492                  -    MD0100PA00X+003048Y+100651                       
317m3492            VIA   -    MD0100PA00X+003653Y+100632X0200Y         S0      
317m3492            VIA   -    MD0100PA00X+002022Y+100975X0200Y         S0      
317m3492            VIA   -    MD0100PA00X+001436Y+100991X0200Y         S0      
317m3492            VIA   -    MD0100PA00X+001703Y+100682X0200Y         S0      
327m3492            C2953 -1          A18X+026663Y+112861X0120Y0150R090 S2      
327m3492            C2963 -1          A18X+026289Y+112861X0120Y0150R090 S2      
327m3492            C2968 -1          A18X+025167Y+112861X0120Y0150R090 S2      
327m3492            C2965 -1          A18X+025541Y+112861X0120Y0150R090 S2      
327m3492            C2979 -1          A18X+025915Y+112861X0120Y0150R090 S2      
327m3492            C2969 -1          A18X+024793Y+112861X0120Y0150R090 S2      
327m3492            C2961 -1          A18X+024419Y+112861X0120Y0150R090 S2      
327m3492            C2960 -1          A18X+024045Y+112861X0120Y0150R090 S2      
327m3492            C2959 -1          A18X+023684Y+112861X0120Y0150R090 S2      
327m3492            C2944 -1          A18X+023294Y+112961X0280Y0320R180 S2      
327m3492            C2958 -1          A18X+022904Y+112861X0120Y0150R090 S2      
327m3492            C2957 -1          A18X+022175Y+112861X0120Y0150R090 S2      
327m3492            C2951 -1          A18X+022549Y+112861X0120Y0150R090 S2      
327m3492            C2955 -1          A18X+021801Y+112861X0120Y0150R090 S2      
327m3492            C2985 -1          A18X+020305Y+112861X0120Y0150R090 S2      
327m3492            C2981 -1          A18X+020679Y+112861X0120Y0150R090 S2      
327m3492            C2972 -1          A18X+021427Y+112861X0120Y0150R090 S2      
327m3492            C2971 -1          A18X+021053Y+112861X0120Y0150R090 S2      
327m3492            C2946 -1          A18X+019931Y+112861X0120Y0150R090 S2      
327m3492            PEX0  -AP33       A01X+026476Y+113130X0180Y         S1      
327m3492            PEX0  -AP28       A01X+024606Y+113130X0180Y         S1      
327m3492            PEX0  -AP31       A01X+025728Y+113130X0180Y         S1      
327m3492            PEX0  -AP32       A01X+026102Y+113130X0180Y         S1      
327m3492            PEX0  -AP30       A01X+025354Y+113130X0180Y         S1      
327m3492            PEX0  -AP29       A01X+024980Y+113130X0180Y         S1      
327m3492            PEX0  -AP27       A01X+024232Y+113130X0180Y         S1      
327m3492            PEX0  -AP26       A01X+023858Y+113130X0180Y         S1      
327m3492            PEX0  -AP25       A01X+023484Y+113130X0180Y         S1      
327m3492            PEX0  -AP24       A01X+023110Y+113130X0180Y         S1      
327m3492            PEX0  -AP21       A01X+021988Y+113130X0180Y         S1      
327m3492            PEX0  -AP22       A01X+022362Y+113130X0180Y         S1      
327m3492            PEX0  -AP23       A01X+022736Y+113130X0180Y         S1      
327m3492            PEX0  -AP16       A01X+020118Y+113130X0180Y         S1      
327m3492            PEX0  -AP18       A01X+020866Y+113130X0180Y         S1      
327m3492            PEX0  -AP20       A01X+021614Y+113130X0180Y         S1      
327m3492            PEX0  -AP19       A01X+021240Y+113130X0180Y         S1      
327m3492            PEX0  -AP17       A01X+020492Y+113130X0180Y         S1      
317m3493            VIA   -    MD0100PA01X+124597Y+140850X0180Y         S0      
317m3493            J13   -F3   D0122PA01X+132240Y+159681X0282Y    R180 S3      
327m3493            C546  -2          A01X+124607Y+140359X0120Y0150R090 S1      
317m3494            VIA   -    MD0100PA01X+124257Y+140850X0180Y         S0      
317m3494            J13   -G3   D0122PA01X+132240Y+159169X0282Y    R180 S3      
327m3494            C545  -2          A01X+124247Y+140359X0120Y0150R090 S1      
327m3495            C1192 -1          A18X+026581Y+116683X0120Y0150     S2      
327m3495            C1163 -1          A18X+027119Y+115935X0120Y0150R180 S2      
327m3495            C1161 -1          A18X+027119Y+117057X0120Y0150R180 S2      
327m3495            C1162 -1          A18X+027119Y+116683X0120Y0150R180 S2      
327m3495            C1174 -1          A18X+026289Y+117139X0120Y0150R270 S2      
327m3495            C1166 -1          A18X+026290Y+115853X0120Y0150R090 S2      
327m3495            C1169 -1          A18X+026476Y+114357X0120Y0150R090 S2      
327m3495            C1191 -1          A18X+026476Y+115105X0120Y0150R090 S2      
327m3495            C1209 -1          A18X+025354Y+115105X0120Y0150R090 S2      
327m3495            C1236 -1          A18X+025354Y+114357X0120Y0150R090 S2      
327m3495            C1237 -1          A18X+024980Y+114357X0120Y0150R090 S2      
327m3495            C1168 -1          A18X+025728Y+114357X0120Y0150R090 S2      
327m3495            C1172 -1          A18X+026102Y+114357X0120Y0150R090 S2      
327m3495            C1211 -1          A18X+024980Y+115105X0120Y0150R090 S2      
327m3495            C1167 -1          A18X+025728Y+115105X0120Y0150R090 S2      
327m3495            C1195 -1          A18X+026102Y+115105X0120Y0150R090 S2      
327m3495            C1208 -1          A18X+024232Y+114357X0120Y0150R090 S2      
327m3495            C1212 -1          A18X+023484Y+114357X0120Y0150R090 S2      
327m3495            C1221 -1          A18X+023858Y+114357X0120Y0150R090 S2      
327m3495            C1240 -1          A18X+024606Y+114357X0120Y0150R090 S2      
327m3495            C1223 -1          A18X+023858Y+115105X0120Y0150R090 S2      
327m3495            C1224 -1          A18X+023484Y+115105X0120Y0150R090 S2      
327m3495            C1230 -1          A18X+024606Y+115105X0120Y0150R090 S2      
327m3495            C1207 -1          A18X+024232Y+115105X0120Y0150R090 S2      
327m3495            C1219 -1          A18X+021614Y+115105X0120Y0150R090 S2      
327m3495            C1199 -1          A18X+021614Y+114357X0120Y0150R090 S2      
327m3495            C1197 -1          A18X+022362Y+115105X0120Y0150R090 S2      
327m3495            C1200 -1          A18X+022736Y+115105X0120Y0150R090 S2      
327m3495            C1201 -1          A18X+021988Y+115105X0120Y0150R090 S2      
327m3495            C1165 -1          A18X+023110Y+115105X0120Y0150R090 S2      
327m3495            C1203 -1          A18X+022362Y+114357X0120Y0150R090 S2      
327m3495            C1215 -1          A18X+021988Y+114357X0120Y0150R090 S2      
327m3495            C1235 -1          A18X+022736Y+114357X0120Y0150R090 S2      
327m3495            C1183 -1          A18X+023110Y+114357X0120Y0150R090 S2      
327m3495            C1225 -1          A18X+021240Y+115105X0120Y0150R090 S2      
327m3495            C1185 -1          A18X+020118Y+115105X0120Y0150R090 S2      
327m3495            C1187 -1          A18X+020492Y+115105X0120Y0150R090 S2      
327m3495            C1188 -1          A18X+020866Y+115105X0120Y0150R090 S2      
327m3495            C1206 -1          A18X+021240Y+114357X0120Y0150R090 S2      
327m3495            C1176 -1          A18X+020492Y+114357X0120Y0150R090 S2      
327m3495            C1184 -1          A18X+020118Y+114357X0120Y0150R090 S2      
327m3495            C1186 -1          A18X+020866Y+114357X0120Y0150R090 S2      
327m3495            C1164 -1          A18X+026827Y+117805X0120Y0150R180 S2      
317m3495            VIA   -    MD0080PA00X+021053Y+117805X0160Y         S0      
317m3495            VIA   -    MD0080PA00X+021427Y+117805X0160Y         S0      
317m3495            VIA   -    MD0080PA00X+019931Y+117805X0160Y         S0      
317m3495            VIA   -    MD0080PA00X+020305Y+117805X0160Y         S0      
317m3495            VIA   -    MD0080PA00X+020679Y+117805X0160Y         S0      
317m3495            VIA   -    MD0080PA00X+021053Y+118553X0160Y         S0      
317m3495            VIA   -    MD0080PA00X+021427Y+118553X0160Y         S0      
317m3495            VIA   -    MD0080PA00X+020679Y+118553X0160Y         S0      
317m3495            VIA   -    MD0080PA00X+019931Y+118553X0160Y         S0      
317m3495            VIA   -    MD0080PA00X+020305Y+118553X0160Y         S0      
317m3495            VIA   -    MD0080PA00X+019931Y+115187X0160Y         S0      
317m3495            VIA   -    MD0080PA00X+020305Y+115187X0160Y         S0      
317m3495            VIA   -    MD0080PA00X+020679Y+115187X0160Y         S0      
317m3495            VIA   -    MD0080PA00X+021053Y+115187X0160Y         S0      
317m3495            VIA   -    MD0080PA00X+021427Y+115187X0160Y         S0      
317m3495            VIA   -    MD0080PA00X+021053Y+114439X0160Y         S0      
317m3495            VIA   -    MD0080PA00X+021427Y+114439X0160Y         S0      
317m3495            VIA   -    MD0080PA00X+019931Y+114439X0160Y         S0      
317m3495            VIA   -    MD0080PA00X+020305Y+114439X0160Y         S0      
317m3495            VIA   -    MD0080PA00X+020679Y+114439X0160Y         S0      
317m3495            VIA   -    MD0080PA00X+022923Y+117805X0160Y         S0      
317m3495            VIA   -    MD0080PA00X+021801Y+117805X0160Y         S0      
317m3495            VIA   -    MD0080PA00X+022175Y+117805X0160Y         S0      
317m3495            VIA   -    MD0080PA00X+022549Y+117805X0160Y         S0      
317m3495            VIA   -    MD0080PA00X+022923Y+118553X0160Y         S0      
317m3495            VIA   -    MD0080PA00X+022175Y+118553X0160Y         S0      
317m3495            VIA   -    MD0080PA00X+021801Y+118553X0160Y         S0      
317m3495            VIA   -    MD0080PA00X+022549Y+118553X0160Y         S0      
317m3495            VIA   -    MD0080PA00X+022549Y+115187X0160Y         S0      
317m3495            VIA   -    MD0080PA00X+021801Y+115187X0160Y         S0      
317m3495            VIA   -    MD0080PA00X+022175Y+115187X0160Y         S0      
317m3495            VIA   -    MD0080PA00X+022923Y+115187X0160Y         S0      
317m3495            VIA   -    MD0080PA00X+022923Y+114439X0160Y         S0      
317m3495            VIA   -    MD0080PA00X+021801Y+114439X0160Y         S0      
317m3495            VIA   -    MD0080PA00X+022175Y+114439X0160Y         S0      
317m3495            VIA   -    MD0080PA00X+022549Y+114439X0160Y         S0      
317m3495            VIA   -    MD0080PA00X+024419Y+117805X0160Y         S0      
317m3495            VIA   -    MD0080PA00X+023671Y+117805X0160Y         S0      
317m3495            VIA   -    MD0080PA00X+024045Y+117805X0160Y         S0      
317m3495            VIA   -    MD0080PA00X+024419Y+118553X0160Y         S0      
317m3495            VIA   -    MD0080PA00X+023671Y+118553X0160Y         S0      
317m3495            VIA   -    MD0080PA00X+024045Y+118553X0160Y         S0      
317m3495            VIA   -    MD0080PA00X+024419Y+114439X0160Y         S0      
317m3495            VIA   -    MD0080PA00X+023671Y+114439X0160Y         S0      
317m3495            VIA   -    MD0080PA00X+024045Y+114439X0160Y         S0      
317m3495            VIA   -    MD0080PA00X+024419Y+115187X0160Y         S0      
317m3495            VIA   -    MD0080PA00X+023671Y+115187X0160Y         S0      
317m3495            VIA   -    MD0080PA00X+024045Y+115187X0160Y         S0      
317m3495            VIA   -    MD0080PA00X+025915Y+114439X0160Y         S0      
317m3495            VIA   -    MD0080PA00X+026289Y+114439X0160Y         S0      
317m3495            VIA   -    MD0080PA00X+025167Y+115187X0160Y         S0      
317m3495            VIA   -    MD0080PA00X+025541Y+115187X0160Y         S0      
317m3495            VIA   -    MD0080PA00X+024793Y+115187X0160Y         S0      
317m3495            VIA   -    MD0080PA00X+026289Y+115187X0160Y         S0      
317m3495            VIA   -    MD0080PA00X+025915Y+115187X0160Y         S0      
317m3495            VIA   -    MD0080PA00X+026289Y+117805X0160Y         S0      
317m3495            VIA   -    MD0080PA00X+025915Y+117805X0160Y         S0      
317m3495            VIA   -    MD0080PA00X+025541Y+117805X0160Y         S0      
317m3495            VIA   -    MD0080PA00X+024793Y+117805X0160Y         S0      
317m3495            VIA   -    MD0080PA00X+025167Y+117805X0160Y         S0      
317m3495            VIA   -    MD0080PA00X+026289Y+118553X0160Y         S0      
317m3495            VIA   -    MD0080PA00X+025915Y+118553X0160Y         S0      
317m3495            VIA   -    MD0080PA00X+025167Y+118553X0160Y         S0      
317m3495            VIA   -    MD0080PA00X+025541Y+118553X0160Y         S0      
317m3495            VIA   -    MD0080PA00X+024793Y+118553X0160Y         S0      
317m3495            VIA   -    MD0080PA00X+026289Y+115935X0160Y         S0      
317m3495            VIA   -    MD0080PA00X+026289Y+117057X0160Y         S0      
317m3495            VIA   -    MD0080PA00X+025541Y+114439X0160Y         S0      
317m3495            VIA   -    MD0080PA00X+024793Y+114439X0160Y         S0      
317m3495            VIA   -    MD0080PA00X+025167Y+114439X0160Y         S0      
317m3495            VIA   -    MD0080PA00X+026663Y+116683X0160Y         S0      
317m3495            VIA   -    MD0080PA00X+027037Y+116683X0160Y         S0      
317m3495            VIA   -    MD0080PA00X+027037Y+115935X0160Y         S0      
317m3495            VIA   -    MD0080PA00X+026663Y+115935X0160Y         S0      
317m3495            VIA   -    MD0080PA00X+027037Y+117057X0160Y         S0      
317m3495            VIA   -    MD0080PA00X+026663Y+117057X0160Y         S0      
317m3495            VIA   -    MD0080PA00X+026663Y+114439X0160Y         S0      
317m3495            VIA   -    MD0080PA00X+026663Y+115187X0160Y         S0      
317m3495            VIA   -    MD0080PA00X+026663Y+117805X0160Y         S0      
317m3495            VIA   -    MD0080PA00X+026663Y+118553X0160Y         S0      
327m3495            VIA   -           A18X+046057Y+123022X0260Y         S2      
327m3495            VIA   -           A18X+045751Y+122411X0260Y         S2      
327m3495            VIA   -           A18X+045956Y+123924X0260Y         S2      
327m3495            R6459 -1          A01X+045562Y+125242X0198Y0197R090 S1      
327m3495            R6460 -1          A01X+046057Y+125242X0198Y0197R090 S1      
327m3495            R6454 -1          A01X+046132Y+122106X0198Y0197R270 S1      
327m3495            R6453 -1          A01X+045602Y+122106X0198Y0197R270 S1      
327m3495            C4211 -1          A18X+045875Y+124416X0120Y0150R180 S2      
327m3495            C4210 -1          A18X+045875Y+124751X0120Y0150R180 S2      
327m3495            C4209 -1          A18X+045875Y+125410X0120Y0150R180 S2      
327m3495            C4208 -1          A18X+045875Y+125070X0120Y0150R180 S2      
327m3495            R6458 -1   M      A18X+042577Y+126540X0198Y0197R270 S2      
327m3495            R6457 -1   M      A18X+043166Y+126540X0198Y0197R270 S2      
327m3495            R6452 -1          A18X+043632Y+126364X0198Y0197R270 S2      
327m3495            R6451 -1          A18X+044108Y+126364X0198Y0197R270 S2      
327m3495            R6456 -1          A18X+044625Y+126367X0198Y0197R270 S2      
327m3495            R6455 -1          A18X+045138Y+126372X0198Y0197R270 S2      
327m3495            R6450 -1          A18X+045647Y+126374X0198Y0197R270 S2      
327m3495            R6449 -1          A18X+046168Y+126376X0198Y0197R270 S2      
327m3495            C1157 -1          A01X+045644Y+124752X0280Y0320R270 S1      
327m3495            C1171 -1          A18X+026476Y+118635X0120Y0150R270 S2      
327m3495            C1170 -1          A18X+026476Y+117887X0120Y0150R270 S2      
327m3495            C1232 -1          A18X+024980Y+117887X0120Y0150R270 S2      
327m3495            C1213 -1          A18X+024980Y+118635X0120Y0150R270 S2      
327m3495            C1210 -1          A18X+025354Y+117887X0120Y0150R270 S2      
327m3495            C1204 -1          A18X+025354Y+118635X0120Y0150R270 S2      
327m3495            C1196 -1          A18X+026102Y+118635X0120Y0150R270 S2      
327m3495            C1193 -1          A18X+025728Y+118635X0120Y0150R270 S2      
327m3495            C1175 -1          A18X+026102Y+117887X0120Y0150R270 S2      
327m3495            C1173 -1          A18X+025728Y+117887X0120Y0150R270 S2      
327m3495            C1239 -1          A18X+024232Y+117887X0120Y0150R270 S2      
327m3495            C1238 -1          A18X+024232Y+118635X0120Y0150R270 S2      
327m3495            C1233 -1          A18X+024606Y+118635X0120Y0150R270 S2      
327m3495            C1229 -1          A18X+023858Y+117887X0120Y0150R270 S2      
327m3495            C1228 -1          A18X+023484Y+118635X0120Y0150R270 S2      
327m3495            C1227 -1          A18X+024606Y+117887X0120Y0150R270 S2      
327m3495            C1226 -1          A18X+023858Y+118635X0120Y0150R270 S2      
327m3495            C1214 -1          A18X+023484Y+117887X0120Y0150R270 S2      
327m3495            C1205 -1          A18X+022362Y+117887X0120Y0150R270 S2      
327m3495            C1202 -1          A18X+021988Y+118635X0120Y0150R270 S2      
327m3495            C1198 -1          A18X+022362Y+118635X0120Y0150R270 S2      
327m3495            C1189 -1          A18X+023110Y+117887X0120Y0150R270 S2      
327m3495            C1181 -1          A18X+023110Y+118635X0120Y0150R270 S2      
327m3495            C1234 -1          A18X+022736Y+117887X0120Y0150R270 S2      
327m3495            C1231 -1          A18X+022736Y+118635X0120Y0150R270 S2      
327m3495            C1216 -1          A18X+021988Y+117887X0120Y0150R270 S2      
327m3495            C1220 -1          A18X+021614Y+117887X0120Y0150R270 S2      
327m3495            C1217 -1          A18X+021614Y+118635X0120Y0150R270 S2      
327m3495            C1222 -1          A18X+021240Y+118635X0120Y0150R270 S2      
327m3495            C1218 -1          A18X+021240Y+117887X0120Y0150R270 S2      
327m3495            C1194 -1          A18X+020866Y+118635X0120Y0150R270 S2      
327m3495            C1190 -1          A18X+020866Y+117887X0120Y0150R270 S2      
327m3495            C1182 -1          A18X+020492Y+117887X0120Y0150R270 S2      
327m3495            C1180 -1          A18X+020492Y+118635X0120Y0150R270 S2      
327m3495            C1178 -1          A18X+020118Y+118635X0120Y0150R270 S2      
327m3495            C1177 -1          A18X+020118Y+117887X0120Y0150R270 S2      
327m3495            C1179 -1          A18X+019750Y+118635X0120Y0150R270 S2      
327m3495            C1158 -1   M      A18X+045047Y+121778X0280Y0320R180 S2      
327m3495            C1159 -1          A18X+046101Y+121778X0280Y0320R180 S2      
327m3495            C1160 -1          A18X+045581Y+121778X0280Y0320R180 S2      
327m3495            L47   -2   M      A18X+041452Y+126425X0460Y3860R270 S2      
327m3495            R5785 -2A  M      A18X+041452Y+126425X0590Y0790R270 S2      
327m3495            R5785 -2B  M      A18X+041452Y+126180X0100Y0200R270 S2      
327m3495            L48   -2   M      A18X+045052Y+123473X0460Y3860R180 S2      
327m3495            R5784 -2A  M      A18X+045101Y+123473X0590Y0790R180 S2      
327m3495            R5784 -2B  M      A18X+044856Y+123473X0100Y0200R180 S2      
317m3495            VIA   -    MD0100PA00X+044370Y+125716X0200Y         S0      
317m3495            VIA   -    MD0100PA00X+044670Y+125716X0200Y         S0      
317m3495            VIA   -    MD0100PA00X+044670Y+126016X0200Y         S0      
317m3495            VIA   -    MD0100PA00X+044370Y+126016X0200Y         S0      
317m3495            VIA   -    MD0100PA00X+044970Y+125716X0200Y         S0      
317m3495            VIA   -    MD0100PA00X+044970Y+126016X0200Y         S0      
317m3495            VIA   -    MD0100PA00X+042870Y+126016X0200Y         S0      
317m3495            VIA   -    MD0100PA00X+043470Y+125716X0200Y         S0      
317m3495            VIA   -    MD0100PA00X+043470Y+126016X0200Y         S0      
317m3495            VIA   -    MD0100PA00X+043170Y+125716X0200Y         S0      
317m3495            VIA   -    MD0100PA00X+043170Y+126016X0200Y         S0      
317m3495            VIA   -    MD0100PA00X+042870Y+125716X0200Y         S0      
317m3495            VIA   -    MD0100PA00X+043770Y+125716X0200Y         S0      
317m3495            VIA   -    MD0100PA00X+043770Y+126016X0200Y         S0      
317m3495            VIA   -    MD0100PA00X+044070Y+125716X0200Y         S0      
317m3495            VIA   -    MD0100PA00X+044070Y+126016X0200Y         S0      
317m3495            VIA   -    MD0100PA00X+041970Y+126016X0200Y         S0      
317m3495            VIA   -    MD0100PA00X+041970Y+125716X0200Y         S0      
317m3495            VIA   -    MD0100PA00X+042570Y+126016X0200Y         S0      
317m3495            VIA   -    MD0100PA00X+042270Y+125716X0200Y         S0      
317m3495            VIA   -    MD0100PA00X+042270Y+126016X0200Y         S0      
317m3495            VIA   -    MD0100PA00X+042570Y+125716X0200Y         S0      
327m3495            L50   -2   M      A01X+041452Y+126425X0460Y3860R090 S1      
327m3495            R5783 -2A  M      A01X+041452Y+126425X0590Y0790R090 S1      
327m3495            R5783 -2B  M      A01X+041452Y+126180X0100Y0200R090 S1      
327m3495            L49   -2   M      A01X+045052Y+123473X0460Y3860     S1      
327m3495            R5786 -2A  M      A01X+045101Y+123473X0590Y0790     S1      
327m3495            R5786 -2B  M      A01X+044856Y+123473X0100Y0200     S1      
327m3495            PEX0  -Y33        A01X+026476Y+118366X0180Y         S1      
327m3495            PEX0  -AB33       A01X+026476Y+117618X0180Y         S1      
327m3495            PEX0  -Y25        A01X+023484Y+118366X0180Y         S1      
327m3495            PEX0  -Y27 M      A01X+024232Y+118366X0180Y         S1      
327m3495            PEX0  -Y26 M      A01X+023858Y+118366X0180Y         S1      
327m3495            PEX0  -Y31 M      A01X+025728Y+118366X0180Y         S1      
327m3495            PEX0  -Y30 M      A01X+025354Y+118366X0180Y         S1      
327m3495            PEX0  -Y29 M      A01X+024980Y+118366X0180Y         S1      
327m3495            PEX0  -Y32 M      A01X+026102Y+118366X0180Y         S1      
327m3495            PEX0  -Y28 M      A01X+024606Y+118366X0180Y         S1      
327m3495            PEX0  -AB25       A01X+023484Y+117618X0180Y         S1      
327m3495            PEX0  -AB27M      A01X+024232Y+117618X0180Y         S1      
327m3495            PEX0  -AB26M      A01X+023858Y+117618X0180Y         S1      
327m3495            PEX0  -AB28M      A01X+024606Y+117618X0180Y         S1      
327m3495            PEX0  -AB31M      A01X+025728Y+117618X0180Y         S1      
327m3495            PEX0  -AB29M      A01X+024980Y+117618X0180Y         S1      
327m3495            PEX0  -AB30M      A01X+025354Y+117618X0180Y         S1      
327m3495            PEX0  -AB32M      A01X+026102Y+117618X0180Y         S1      
327m3495            PEX0  -Y18 M      A01X+020866Y+118366X0180Y         S1      
327m3495            PEX0  -Y16 M      A01X+020118Y+118366X0180Y         S1      
327m3495            PEX0  -Y17 M      A01X+020492Y+118366X0180Y         S1      
327m3495            PEX0  -Y21 M      A01X+021988Y+118366X0180Y         S1      
327m3495            PEX0  -Y20 M      A01X+021614Y+118366X0180Y         S1      
327m3495            PEX0  -Y23 M      A01X+022736Y+118366X0180Y         S1      
327m3495            PEX0  -Y22 M      A01X+022362Y+118366X0180Y         S1      
327m3495            PEX0  -Y24        A01X+023110Y+118366X0180Y         S1      
327m3495            PEX0  -Y19 M      A01X+021240Y+118366X0180Y         S1      
327m3495            PEX0  -AB18M      A01X+020866Y+117618X0180Y         S1      
327m3495            PEX0  -AB17M      A01X+020492Y+117618X0180Y         S1      
327m3495            PEX0  -AB16M      A01X+020118Y+117618X0180Y         S1      
327m3495            PEX0  -AB21M      A01X+021988Y+117618X0180Y         S1      
327m3495            PEX0  -AB23M      A01X+022736Y+117618X0180Y         S1      
327m3495            PEX0  -AB22M      A01X+022362Y+117618X0180Y         S1      
327m3495            PEX0  -AB20M      A01X+021614Y+117618X0180Y         S1      
327m3495            PEX0  -AB24       A01X+023110Y+117618X0180Y         S1      
327m3495            PEX0  -AB19M      A01X+021240Y+117618X0180Y         S1      
327m3495            PEX0  -AE34M      A01X+026850Y+116496X0180Y         S1      
327m3495            PEX0  -AE33       A01X+026476Y+116496X0180Y         S1      
327m3495            PEX0  -AD33M      A01X+026476Y+116870X0180Y         S1      
327m3495            PEX0  -AD34M      A01X+026850Y+116870X0180Y         S1      
327m3495            PEX0  -AD32       A01X+026102Y+116870X0180Y         S1      
327m3495            PEX0  -AF32       A01X+026102Y+116122X0180Y         S1      
327m3495            PEX0  -AF33M      A01X+026476Y+116122X0180Y         S1      
327m3495            PEX0  -AF34M      A01X+026850Y+116122X0180Y         S1      
327m3495            PEX0  -AH25       A01X+023484Y+115374X0180Y         S1      
327m3495            PEX0  -AH27M      A01X+024232Y+115374X0180Y         S1      
327m3495            PEX0  -AH26M      A01X+023858Y+115374X0180Y         S1      
327m3495            PEX0  -AH28M      A01X+024606Y+115374X0180Y         S1      
327m3495            PEX0  -AH30M      A01X+025354Y+115374X0180Y         S1      
327m3495            PEX0  -AH32M      A01X+026102Y+115374X0180Y         S1      
327m3495            PEX0  -AH31M      A01X+025728Y+115374X0180Y         S1      
327m3495            PEX0  -AH33M      A01X+026476Y+115374X0180Y         S1      
327m3495            PEX0  -AH29M      A01X+024980Y+115374X0180Y         S1      
327m3495            PEX0  -AK25       A01X+023484Y+114626X0180Y         S1      
327m3495            PEX0  -AK26M      A01X+023858Y+114626X0180Y         S1      
327m3495            PEX0  -AK27M      A01X+024232Y+114626X0180Y         S1      
327m3495            PEX0  -AK28M      A01X+024606Y+114626X0180Y         S1      
327m3495            PEX0  -AK29M      A01X+024980Y+114626X0180Y         S1      
327m3495            PEX0  -AK30M      A01X+025354Y+114626X0180Y         S1      
327m3495            PEX0  -AK32M      A01X+026102Y+114626X0180Y         S1      
327m3495            PEX0  -AK33M      A01X+026476Y+114626X0180Y         S1      
327m3495            PEX0  -AK31M      A01X+025728Y+114626X0180Y         S1      
327m3495            PEX0  -AH24       A01X+023110Y+115374X0180Y         S1      
327m3495            PEX0  -AH22       A01X+022362Y+115374X0180Y         S1      
327m3495            PEX0  -AH21       A01X+021988Y+115374X0180Y         S1      
327m3495            PEX0  -AH23       A01X+022736Y+115374X0180Y         S1      
327m3495            PEX0  -AH20       A01X+021614Y+115374X0180Y         S1      
327m3495            PEX0  -AH19       A01X+021240Y+115374X0180Y         S1      
327m3495            PEX0  -AH18       A01X+020866Y+115374X0180Y         S1      
327m3495            PEX0  -AH17       A01X+020492Y+115374X0180Y         S1      
327m3495            PEX0  -AH16       A01X+020118Y+115374X0180Y         S1      
327m3495            PEX0  -AK18M      A01X+020866Y+114626X0180Y         S1      
327m3495            PEX0  -AK17M      A01X+020492Y+114626X0180Y         S1      
327m3495            PEX0  -AK16M      A01X+020118Y+114626X0180Y         S1      
327m3495            PEX0  -AK24       A01X+023110Y+114626X0180Y         S1      
327m3495            PEX0  -AK20M      A01X+021614Y+114626X0180Y         S1      
327m3495            PEX0  -AK21M      A01X+021988Y+114626X0180Y         S1      
327m3495            PEX0  -AK22M      A01X+022362Y+114626X0180Y         S1      
327m3495            PEX0  -AK23M      A01X+022736Y+114626X0180Y         S1      
327m3495            PEX0  -AK19M      A01X+021240Y+114626X0180Y         S1      
317P1V25_PEX0       VIA   -    MD0080PA00X+021053Y+113691X0160Y         S0      
317P1V25_PEX0       VIA   -    MD0080PA00X+021427Y+113691X0160Y         S0      
317P1V25_PEX0       VIA   -    MD0080PA00X+019931Y+113691X0160Y         S0      
317P1V25_PEX0       VIA   -    MD0080PA00X+020305Y+113691X0160Y         S0      
317P1V25_PEX0       VIA   -    MD0080PA00X+020679Y+113691X0160Y         S0      
317P1V25_PEX0       VIA   -    MD0080PA00X+020679Y+119301X0160Y         S0      
317P1V25_PEX0       VIA   -    MD0080PA00X+020305Y+119301X0160Y         S0      
317P1V25_PEX0       VIA   -    MD0080PA00X+019931Y+119301X0160Y         S0      
317P1V25_PEX0       VIA   -    MD0080PA00X+021053Y+119301X0160Y         S0      
317P1V25_PEX0       VIA   -    MD0080PA00X+021427Y+119301X0160Y         S0      
317P1V25_PEX0       VIA   -    MD0080PA00X+022923Y+119301X0160Y         S0      
317P1V25_PEX0       VIA   -    MD0080PA00X+022549Y+119301X0160Y         S0      
317P1V25_PEX0       VIA   -    MD0080PA00X+022175Y+119301X0160Y         S0      
317P1V25_PEX0       VIA   -    MD0080PA00X+021801Y+119301X0160Y         S0      
317P1V25_PEX0       VIA   -    MD0080PA00X+022923Y+113691X0160Y         S0      
317P1V25_PEX0       VIA   -    MD0080PA00X+021801Y+113691X0160Y         S0      
317P1V25_PEX0       VIA   -    MD0080PA00X+022175Y+113691X0160Y         S0      
317P1V25_PEX0       VIA   -    MD0080PA00X+022549Y+113691X0160Y         S0      
317P1V25_PEX0       VIA   -    MD0080PA00X+024419Y+119301X0160Y         S0      
317P1V25_PEX0       VIA   -    MD0080PA00X+023671Y+119301X0160Y         S0      
317P1V25_PEX0       VIA   -    MD0080PA00X+024045Y+119301X0160Y         S0      
317P1V25_PEX0       VIA   -    MD0080PA00X+024419Y+113691X0160Y         S0      
317P1V25_PEX0       VIA   -    MD0080PA00X+023671Y+113691X0160Y         S0      
317P1V25_PEX0       VIA   -    MD0080PA00X+024045Y+113691X0160Y         S0      
317P1V25_PEX0       VIA   -    MD0080PA00X+026289Y+113691X0160Y         S0      
317P1V25_PEX0       VIA   -    MD0080PA00X+025915Y+113691X0160Y         S0      
317P1V25_PEX0       VIA   -    MD0080PA00X+024793Y+113691X0160Y         S0      
317P1V25_PEX0       VIA   -    MD0080PA00X+025167Y+113691X0160Y         S0      
317P1V25_PEX0       VIA   -    MD0080PA00X+025541Y+113691X0160Y         S0      
317P1V25_PEX0       VIA   -    MD0080PA00X+025915Y+119301X0160Y         S0      
317P1V25_PEX0       VIA   -    MD0080PA00X+026289Y+119301X0160Y         S0      
317P1V25_PEX0       VIA   -    MD0080PA00X+024793Y+119301X0160Y         S0      
317P1V25_PEX0       VIA   -    MD0080PA00X+025541Y+119301X0160Y         S0      
317P1V25_PEX0       VIA   -    MD0080PA00X+025167Y+119301X0160Y         S0      
317P1V25_PEX0       VIA   -    MD0080PA00X+027785Y+117057X0160Y         S0      
317P1V25_PEX0       VIA   -    MD0080PA00X+027785Y+116683X0160Y         S0      
317P1V25_PEX0       VIA   -    MD0080PA00X+027785Y+115935X0160Y         S0      
317P1V25_PEX0       VIA   -    MD0080PA00X+027785Y+115561X0160Y         S0      
317P1V25_PEX0       VIA   -    MD0080PA00X+026663Y+113691X0160Y         S0      
317P1V25_PEX0       VIA   -    MD0080PA00X+026663Y+119301X0160Y         S0      
317P1V25_PEX0       VIA   -    MD0080PA00X+027785Y+117431X0160Y         S0      
317P1V25_PEX0       VIA   -    MD0080PA00X+030778Y+116683X0160Y    R180 S0      
317P1V25_PEX0       VIA   -    MD0080PA00X+030404Y+115935X0160Y    R090 S0      
317P1V25_PEX0       VIA   -    MD0080PA00X+030404Y+116683X0160Y    R180 S0      
327P1V25_PEX0       C4221 -1          A18X+004714Y+106477X0280Y0320R270 S2      
327P1V25_PEX0       C4223 -1          A18X+004085Y+107303X0120Y0150R180 S2      
327P1V25_PEX0       C4222 -1          A18X+003384Y+109382X0120Y0150R180 S2      
327P1V25_PEX0       C4237 -1          A18X+003389Y+109069X0120Y0150R180 S2      
327P1V25_PEX0       C4236 -1          A18X+003495Y+108264X0120Y0150R180 S2      
327P1V25_PEX0       C4220 -1          A18X+001502Y+106530X0280Y0320R090 S2      
327P1V25_PEX0       C4219 -1          A18X+001502Y+107059X0280Y0320R090 S2      
327P1V25_PEX0       C4232 -1          A18X+001508Y+107597X0280Y0320R090 S2      
327P1V25_PEX0       C4233 -1          A18X+001497Y+108129X0280Y0320R090 S2      
327P1V25_PEX0       C4235 -1          A18X+001497Y+109194X0280Y0320R090 S2      
327P1V25_PEX0       C4234 -1          A18X+001497Y+108653X0280Y0320R090 S2      
327P1V25_PEX0       C4218 -1          A18X+003369Y+108673X0280Y0320R270 S2      
317P1V25_PEX0       VIA   -    MD0100PA00X+007095Y+120584X0200Y         S0      
327P1V25_PEX0       PJ9   -2          A01X+006853Y+120584X0180Y0200R180 S1      
327P1V25_PEX0       PEX0  -V26 M      A01X+023858Y+119114X0180Y         S1      
327P1V25_PEX0       PEX0  -V25        A01X+023484Y+119114X0180Y         S1      
327P1V25_PEX0       PEX0  -V16 M      A01X+020118Y+119114X0180Y         S1      
327P1V25_PEX0       PEX0  -V17 M      A01X+020492Y+119114X0180Y         S1      
327P1V25_PEX0       PEX0  -V21 M      A01X+021988Y+119114X0180Y         S1      
327P1V25_PEX0       PEX0  -V20 M      A01X+021614Y+119114X0180Y         S1      
327P1V25_PEX0       PEX0  -V22 M      A01X+022362Y+119114X0180Y         S1      
327P1V25_PEX0       PEX0  -V23 M      A01X+022736Y+119114X0180Y         S1      
327P1V25_PEX0       PEX0  -V24        A01X+023110Y+119114X0180Y         S1      
327P1V25_PEX0       PEX0  -V19 M      A01X+021240Y+119114X0180Y         S1      
327P1V25_PEX0       PEX0  -V18 M      A01X+020866Y+119114X0180Y         S1      
327P1V25_PEX0       PEX0  -V27        A01X+024232Y+119114X0180Y         S1      
327P1V25_PEX0       PEX0  -V31        A01X+025728Y+119114X0180Y         S1      
327P1V25_PEX0       PEX0  -V32        A01X+026102Y+119114X0180Y         S1      
327P1V25_PEX0       PEX0  -V28        A01X+024606Y+119114X0180Y         S1      
327P1V25_PEX0       PEX0  -V30        A01X+025354Y+119114X0180Y         S1      
327P1V25_PEX0       PEX0  -V29        A01X+024980Y+119114X0180Y         S1      
327P1V25_PEX0       PEX0  -V33        A01X+026476Y+119114X0180Y         S1      
327P1V25_PEX0       C2909 -1          A18X+020492Y+119383X0120Y0150R270 S2      
327P1V25_PEX0       C2914 -1          A18X+020118Y+119383X0120Y0150R270 S2      
327P1V25_PEX0       C2915 -1          A18X+020866Y+119383X0120Y0150R270 S2      
327P1V25_PEX0       C2916 -1          A18X+021240Y+119383X0120Y0150R270 S2      
327P1V25_PEX0       C2912 -1          A18X+021614Y+119383X0120Y0150R270 S2      
327P1V25_PEX0       C2913 -1          A18X+021988Y+119383X0120Y0150R270 S2      
327P1V25_PEX0       C2917 -1          A18X+022736Y+119383X0120Y0150R270 S2      
327P1V25_PEX0       C2918 -1          A18X+022362Y+119383X0120Y0150R270 S2      
327P1V25_PEX0       C2922 -1          A18X+023110Y+119383X0120Y0150R270 S2      
327P1V25_PEX0       C2908 -1          A18X+024232Y+119383X0120Y0150R270 S2      
327P1V25_PEX0       C2901 -1          A18X+023858Y+119383X0120Y0150R270 S2      
327P1V25_PEX0       C2906 -1          A18X+023484Y+119383X0120Y0150R270 S2      
327P1V25_PEX0       C2907 -1          A18X+024606Y+119383X0120Y0150R270 S2      
327P1V25_PEX0       C2904 -1          A18X+025728Y+119383X0120Y0150R270 S2      
327P1V25_PEX0       C2905 -1          A18X+026102Y+119383X0120Y0150R270 S2      
327P1V25_PEX0       C2910 -1          A18X+024980Y+119383X0120Y0150R270 S2      
327P1V25_PEX0       C2939 -1          A18X+025354Y+119383X0120Y0150R270 S2      
327P1V25_PEX0       C2924 -1          A18X+026476Y+119383X0120Y0150R270 S2      
327P1V25_PEX0       C2903 -1          A18X+030616Y+116308X0280Y0320R270 S2      
327P1V25_PEX0       C2902 -1          A18X+030100Y+116309X0280Y0320R090 S2      
327P1V25_PEX0       PEX0  -AG36       A01X+027598Y+115748X0180Y         S1      
327P1V25_PEX0       PEX0  -AC36M      A01X+027598Y+117244X0180Y         S1      
327P1V25_PEX0       PEX0  -AD36M      A01X+027598Y+116870X0180Y         S1      
327P1V25_PEX0       PEX0  -AE36       A01X+027598Y+116496X0180Y         S1      
327P1V25_PEX0       PEX0  -AF36       A01X+027598Y+116122X0180Y         S1      
327P1V25_PEX0       C2929 -1          A18X+027867Y+115561X0120Y0150R180 S2      
327P1V25_PEX0       VIA   -           A18X+002120Y+109180X0260Y         S2      
327P1V25_PEX0       C2911 -1          A18X+027867Y+117057X0120Y0150R180 S2      
327P1V25_PEX0       C2926 -1          A18X+027867Y+116683X0120Y0150R180 S2      
327P1V25_PEX0       C2928 -1          A18X+027867Y+115935X0120Y0150R180 S2      
327P1V25_PEX0       C2925 -1          A18X+027867Y+117431X0120Y0150R180 S2      
327P1V25_PEX0       R778  -1          A01X+003516Y+107837X0198Y0197     S1      
327P1V25_PEX0       R770  -1          A01X+002479Y+107288X1150Y1380R090 S1      
327P1V25_PEX0       L84   -1   M      A01X+003765Y+104137X0460Y3860     S1      
327P1V25_PEX0       R6129 -1A  M      A01X+003716Y+104168X0590Y0790     S1      
327P1V25_PEX0       R6129 -1B  M      A01X+003961Y+104168X0100Y0200     S1      
327P1V25_PEX0       L82   -1   M      A01X+002832Y+104168X0460Y3860R180 S1      
327P1V25_PEX0       R6127 -1A  M      A01X+002881Y+104168X0590Y0790R180 S1      
327P1V25_PEX0       R6127 -1B  M      A01X+002636Y+104168X0100Y0200R180 S1      
327P1V25_PEX0       C2927 -1          A18X+026476Y+113609X0120Y0150R090 S2      
327P1V25_PEX0       C2940 -1          A18X+026102Y+113609X0120Y0150R090 S2      
327P1V25_PEX0       C2938 -1          A18X+024980Y+113609X0120Y0150R090 S2      
327P1V25_PEX0       C2936 -1          A18X+025728Y+113609X0120Y0150R090 S2      
327P1V25_PEX0       C2920 -1          A18X+025354Y+113609X0120Y0150R090 S2      
327P1V25_PEX0       C2921 -1          A18X+023858Y+113609X0120Y0150R090 S2      
327P1V25_PEX0       C2919 -1          A18X+024606Y+113609X0120Y0150R090 S2      
327P1V25_PEX0       C2941 -1          A18X+023484Y+113609X0120Y0150R090 S2      
327P1V25_PEX0       C2923 -1          A18X+024232Y+113609X0120Y0150R090 S2      
327P1V25_PEX0       C2937 -1          A18X+023110Y+113609X0120Y0150R090 S2      
327P1V25_PEX0       C2933 -1          A18X+021988Y+113609X0120Y0150R090 S2      
327P1V25_PEX0       C2943 -1          A18X+022736Y+113609X0120Y0150R090 S2      
327P1V25_PEX0       C2942 -1          A18X+022362Y+113609X0120Y0150R090 S2      
327P1V25_PEX0       C2932 -1          A18X+021614Y+113609X0120Y0150R090 S2      
327P1V25_PEX0       C2934 -1          A18X+021240Y+113609X0120Y0150R090 S2      
327P1V25_PEX0       C2931 -1          A18X+020492Y+113609X0120Y0150R090 S2      
327P1V25_PEX0       C2930 -1          A18X+020118Y+113609X0120Y0150R090 S2      
327P1V25_PEX0       C2935 -1          A18X+020866Y+113609X0120Y0150R090 S2      
327P1V25_PEX0       VIA   -           A18X+003602Y+106970X0260Y         S2      
327P1V25_PEX0       VIA   -           A18X+002035Y+106947X0260Y         S2      
327P1V25_PEX0       L85   -1   M      A18X+003765Y+104137X0460Y3860R180 S2      
327P1V25_PEX0       R6128 -1A  M      A18X+003716Y+104168X0590Y0790R180 S2      
327P1V25_PEX0       R6128 -1B  M      A18X+003961Y+104168X0100Y0200R180 S2      
327P1V25_PEX0       L83   -1   M      A18X+002832Y+104168X0460Y3860     S2      
327P1V25_PEX0       R6126 -1A  M      A18X+002881Y+104168X0590Y0790     S2      
327P1V25_PEX0       R6126 -1B  M      A18X+002636Y+104168X0100Y0200     S2      
327P1V25_PEX0       PEX0  -AM25       A01X+023484Y+113878X0180Y         S1      
327P1V25_PEX0       PEX0  -AM27M      A01X+024232Y+113878X0180Y         S1      
327P1V25_PEX0       PEX0  -AM26M      A01X+023858Y+113878X0180Y         S1      
327P1V25_PEX0       PEX0  -AM32M      A01X+026102Y+113878X0180Y         S1      
327P1V25_PEX0       PEX0  -AM30M      A01X+025354Y+113878X0180Y         S1      
327P1V25_PEX0       PEX0  -AM31M      A01X+025728Y+113878X0180Y         S1      
327P1V25_PEX0       PEX0  -AM29M      A01X+024980Y+113878X0180Y         S1      
327P1V25_PEX0       PEX0  -AM33M      A01X+026476Y+113878X0180Y         S1      
327P1V25_PEX0       PEX0  -AM28M      A01X+024606Y+113878X0180Y         S1      
317P1V25_PEX0       VIA   -    MD0100PA00X+002081Y+108018X0200Y    R090 S0      
317P1V25_PEX0       VIA   -    MD0100PA00X+002081Y+108268X0200Y    R090 S0      
317P1V25_PEX0       VIA   -    MD0100PA00X+002861Y+108018X0200Y    R090 S0      
317P1V25_PEX0       VIA   -    MD0100PA00X+002341Y+108018X0200Y    R090 S0      
317P1V25_PEX0       VIA   -    MD0100PA00X+002601Y+108018X0200Y    R090 S0      
317P1V25_PEX0       VIA   -    MD0100PA00X+002601Y+108268X0200Y    R090 S0      
317P1V25_PEX0       VIA   -    MD0100PA00X+002341Y+108268X0200Y    R090 S0      
317P1V25_PEX0       VIA   -    MD0100PA00X+002861Y+108268X0200Y    R090 S0      
317P1V25_PEX0       VIA   -    MD0100PA00X+004389Y+106510X0200Y    R090 S0      
317P1V25_PEX0       VIA   -    MD0100PA00X+003869Y+106510X0200Y    R090 S0      
317P1V25_PEX0       VIA   -    MD0100PA00X+004129Y+106510X0200Y    R090 S0      
317P1V25_PEX0       VIA   -    MD0100PA00X+004129Y+106260X0200Y    R090 S0      
317P1V25_PEX0       VIA   -    MD0100PA00X+003869Y+106260X0200Y    R090 S0      
317P1V25_PEX0       VIA   -    MD0100PA00X+004389Y+106260X0200Y    R090 S0      
317P1V25_PEX0       VIA   -    MD0100PA00X+002900Y+106303X0200Y    R090 S0      
317P1V25_PEX0       VIA   -    MD0100PA00X+002380Y+106303X0200Y    R090 S0      
317P1V25_PEX0       VIA   -    MD0100PA00X+002640Y+106303X0200Y    R090 S0      
317P1V25_PEX0       VIA   -    MD0100PA00X+002640Y+106553X0200Y    R090 S0      
317P1V25_PEX0       VIA   -    MD0100PA00X+002380Y+106553X0200Y    R090 S0      
317P1V25_PEX0       VIA   -    MD0100PA00X+002900Y+106553X0200Y    R090 S0      
317P1V25_PEX0       VIA   -    MD0100PA00X+003342Y+107566X0200Y         S0      
317P1V25_PEX0       VIA   -    MD0100PA00X+003592Y+107566X0200Y         S0      
317P1V25_PEX0       VIA   -    MD0100PA00X+003609Y+106510X0200Y    R090 S0      
317P1V25_PEX0       VIA   -    MD0100PA00X+003609Y+106260X0200Y    R090 S0      
317P1V25_PEX0       VIA   -    MD0100PA00X+002120Y+106303X0200Y    R090 S0      
317P1V25_PEX0       VIA   -    MD0100PA00X+002120Y+106553X0200Y    R090 S0      
327P1V25_PEX0       PEX0  -AM18M      A01X+020866Y+113878X0180Y         S1      
327P1V25_PEX0       PEX0  -AM17M      A01X+020492Y+113878X0180Y         S1      
327P1V25_PEX0       PEX0  -AM16M      A01X+020118Y+113878X0180Y         S1      
327P1V25_PEX0       PEX0  -AM21M      A01X+021988Y+113878X0180Y         S1      
327P1V25_PEX0       PEX0  -AM23M      A01X+022736Y+113878X0180Y         S1      
327P1V25_PEX0       PEX0  -AM22M      A01X+022362Y+113878X0180Y         S1      
327P1V25_PEX0       PEX0  -AM20M      A01X+021614Y+113878X0180Y         S1      
327P1V25_PEX0       PEX0  -AM24       A01X+023110Y+113878X0180Y         S1      
327P1V25_PEX0       PEX0  -AM19M      A01X+021240Y+113878X0180Y         S1      
327P0V8_PEX0        C1103 -1          A18X+019475Y+114813X0120Y0150     S2      
327P0V8_PEX0        C1141 -1          A18X+025167Y+115643X0120Y0150R270 S2      
327P0V8_PEX0        C1120 -1          A18X+025915Y+115643X0120Y0150R270 S2      
327P0V8_PEX0        C1136 -1          A18X+023671Y+115643X0120Y0150R270 S2      
327P0V8_PEX0        C1146 -1          A18X+024419Y+115643X0120Y0150R270 S2      
327P0V8_PEX0        C1147 -1          A18X+021801Y+115643X0120Y0150R270 S2      
327P0V8_PEX0        C1149 -1          A18X+022549Y+115643X0120Y0150R270 S2      
327P0V8_PEX0        C1139 -1          A18X+020305Y+115643X0120Y0150R270 S2      
327P0V8_PEX0        C1153 -1          A18X+021053Y+115643X0120Y0150R270 S2      
327P0V8_PEX0        C1125 -1          A18X+025915Y+117349X0120Y0150R090 S2      
327P0V8_PEX0        C1116 -1          A18X+025167Y+117349X0120Y0150R090 S2      
327P0V8_PEX0        C1114 -1          A18X+023671Y+117349X0120Y0150R090 S2      
327P0V8_PEX0        C1115 -1          A18X+024419Y+117349X0120Y0150R090 S2      
327P0V8_PEX0        C1151 -1          A18X+021801Y+117349X0120Y0150R090 S2      
327P0V8_PEX0        C1118 -1          A18X+022549Y+117349X0120Y0150R090 S2      
327P0V8_PEX0        C1121 -1          A18X+021053Y+117349X0120Y0150R090 S2      
327P0V8_PEX0        C1140 -1          A18X+020305Y+117349X0120Y0150R090 S2      
327P0V8_PEX0        C1132 -1          A18X+019265Y+117825X0120Y0150R180 S2      
327P0V8_PEX0        C1152 -1          A18X+019557Y+117349X0120Y0150R090 S2      
327P0V8_PEX0        C1144 -1          A18X+025541Y+115853X0120Y0150R090 S2      
327P0V8_PEX0        C1142 -1          A18X+024793Y+115853X0120Y0150R090 S2      
327P0V8_PEX0        C1143 -1          A18X+025541Y+117139X0120Y0150R270 S2      
327P0V8_PEX0        C1145 -1          A18X+024793Y+117139X0120Y0150R270 S2      
327P0V8_PEX0        C1102 -1          A18X+024770Y+116229X0280Y0320R090 S2      
327P0V8_PEX0        C1112 -1          A18X+023223Y+116683X0120Y0150     S2      
327P0V8_PEX0        C1117 -1          A18X+024045Y+117139X0120Y0150R270 S2      
327P0V8_PEX0        C1135 -1          A18X+024045Y+115853X0120Y0150R090 S2      
327P0V8_PEX0        C1101 -1          A18X+022900Y+116229X0280Y0320R090 S2      
327P0V8_PEX0        C1154 -1          A18X+022175Y+117139X0120Y0150R270 S2      
327P0V8_PEX0        C1133 -1          A18X+022929Y+117139X0120Y0150R270 S2      
327P0V8_PEX0        C1155 -1          A18X+022923Y+115853X0120Y0150R090 S2      
327P0V8_PEX0        C1156 -1          A18X+022175Y+115853X0120Y0150R090 S2      
327P0V8_PEX0        C1100 -1          A18X+021404Y+116229X0280Y0320R090 S2      
327P0V8_PEX0        C1148 -1          A18X+021427Y+117139X0120Y0150R270 S2      
327P0V8_PEX0        C1122 -1          A18X+020679Y+117139X0120Y0150R270 S2      
327P0V8_PEX0        C1138 -1          A18X+019931Y+117139X0120Y0150R270 S2      
327P0V8_PEX0        C1134 -1          A18X+020679Y+115853X0120Y0150R090 S2      
327P0V8_PEX0        C1150 -1          A18X+021427Y+115853X0120Y0150R090 S2      
327P0V8_PEX0        C1119 -1          A18X+019931Y+115853X0120Y0150R090 S2      
327P0V8_PEX0        C1123 -1          A18X+019183Y+117139X0120Y0150R270 S2      
327P0V8_PEX0        C1108 -1          A18X+019183Y+115853X0120Y0150R090 S2      
327P0V8_PEX0        C1106 -1          A18X+019265Y+115187X0120Y0150R180 S2      
327P0V8_PEX0        C1137 -1          A18X+019557Y+115643X0120Y0150R270 S2      
327P0V8_PEX0        C1104 -1          A18X+019265Y+114439X0120Y0150R180 S2      
327P0V8_PEX0        C1131 -1   M      A18X+019475Y+118179X0120Y0150     S2      
327P0V8_PEX0        C1126 -1          A18X+026745Y+117431X0120Y0150R180 S2      
327P0V8_PEX0        C1105 -1          A18X+026745Y+115561X0120Y0150R180 S2      
317P0V8_PEX0        VIA   -    MD0080PA00X+019557Y+117431X0160Y         S0      
317P0V8_PEX0        VIA   -    MD0080PA00X+019557Y+118179X0160Y         S0      
317P0V8_PEX0        VIA   -    MD0080PA00X+019183Y+117805X0160Y         S0      
317P0V8_PEX0        VIA   -    MD0080PA00X+019183Y+118553X0160Y         S0      
317P0V8_PEX0        VIA   -    MD0080PA00X+019557Y+116683X0160Y         S0      
317P0V8_PEX0        VIA   -    MD0080PA00X+019183Y+117057X0160Y         S0      
317P0V8_PEX0        VIA   -    MD0080PA00X+019183Y+115935X0160Y         S0      
317P0V8_PEX0        VIA   -    MD0080PA00X+019557Y+115561X0160Y         S0      
317P0V8_PEX0        VIA   -    MD0080PA00X+019557Y+114813X0160Y         S0      
317P0V8_PEX0        VIA   -    MD0080PA00X+019183Y+115187X0160Y         S0      
317P0V8_PEX0        VIA   -    MD0080PA00X+019183Y+114439X0160Y         S0      
317P0V8_PEX0        VIA   -    MD0080PA00X+021053Y+117431X0160Y         S0      
317P0V8_PEX0        VIA   -    MD0080PA00X+020305Y+117431X0160Y         S0      
317P0V8_PEX0        VIA   -    MD0080PA00X+019931Y+115935X0160Y         S0      
317P0V8_PEX0        VIA   -    MD0080PA00X+020679Y+115935X0160Y         S0      
317P0V8_PEX0        VIA   -    MD0080PA00X+019931Y+117057X0160Y         S0      
317P0V8_PEX0        VIA   -    MD0080PA00X+020305Y+116683X0160Y         S0      
317P0V8_PEX0        VIA   -    MD0080PA00X+020679Y+117057X0160Y         S0      
317P0V8_PEX0        VIA   -    MD0080PA00X+021427Y+115935X0160Y         S0      
317P0V8_PEX0        VIA   -    MD0080PA00X+021053Y+116683X0160Y         S0      
317P0V8_PEX0        VIA   -    MD0080PA00X+021427Y+117057X0160Y         S0      
317P0V8_PEX0        VIA   -    MD0080PA00X+020305Y+115561X0160Y         S0      
317P0V8_PEX0        VIA   -    MD0080PA00X+021053Y+115561X0160Y         S0      
317P0V8_PEX0        VIA   -    MD0080PA00X+021801Y+117431X0160Y         S0      
317P0V8_PEX0        VIA   -    MD0080PA00X+022549Y+117431X0160Y         S0      
317P0V8_PEX0        VIA   -    MD0080PA00X+022923Y+115935X0160Y         S0      
317P0V8_PEX0        VIA   -    MD0080PA00X+022923Y+117057X0160Y         S0      
317P0V8_PEX0        VIA   -    MD0080PA00X+022175Y+115935X0160Y         S0      
317P0V8_PEX0        VIA   -    MD0080PA00X+021801Y+116683X0160Y         S0      
317P0V8_PEX0        VIA   -    MD0080PA00X+022175Y+117057X0160Y         S0      
317P0V8_PEX0        VIA   -    MD0080PA00X+022549Y+116683X0160Y         S0      
317P0V8_PEX0        VIA   -    MD0080PA00X+022549Y+115561X0160Y         S0      
317P0V8_PEX0        VIA   -    MD0080PA00X+021801Y+115561X0160Y         S0      
317P0V8_PEX0        VIA   -    MD0080PA00X+024419Y+117431X0160Y         S0      
317P0V8_PEX0        VIA   -    MD0080PA00X+023671Y+117431X0160Y         S0      
317P0V8_PEX0        VIA   -    MD0080PA00X+024419Y+116683X0160Y         S0      
317P0V8_PEX0        VIA   -    MD0080PA00X+024045Y+115935X0160Y         S0      
317P0V8_PEX0        VIA   -    MD0080PA00X+024045Y+117057X0160Y         S0      
317P0V8_PEX0        VIA   -    MD0080PA00X+023671Y+116683X0160Y         S0      
317P0V8_PEX0        VIA   -    MD0080PA00X+024419Y+115561X0160Y         S0      
317P0V8_PEX0        VIA   -    MD0080PA00X+023671Y+115561X0160Y         S0      
317P0V8_PEX0        VIA   -    MD0080PA00X+025915Y+115561X0160Y         S0      
317P0V8_PEX0        VIA   -    MD0080PA00X+025167Y+115561X0160Y         S0      
317P0V8_PEX0        VIA   -    MD0080PA00X+025915Y+117431X0160Y         S0      
317P0V8_PEX0        VIA   -    MD0080PA00X+025167Y+117431X0160Y         S0      
317P0V8_PEX0        VIA   -    MD0080PA00X+025915Y+116683X0160Y         S0      
317P0V8_PEX0        VIA   -    MD0080PA00X+024793Y+115935X0160Y         S0      
317P0V8_PEX0        VIA   -    MD0080PA00X+025541Y+115935X0160Y         S0      
317P0V8_PEX0        VIA   -    MD0080PA00X+024793Y+117057X0160Y         S0      
317P0V8_PEX0        VIA   -    MD0080PA00X+025541Y+117057X0160Y         S0      
317P0V8_PEX0        VIA   -    MD0080PA00X+025167Y+116683X0160Y         S0      
317P0V8_PEX0        VIA   -    MD0080PA00X+026663Y+115561X0160Y         S0      
317P0V8_PEX0        VIA   -    MD0080PA00X+026663Y+117431X0160Y         S0      
327P0V8_PEX0        PR101 -2          A18X+043162Y+110890X0198Y0197R090 S2      
327P0V8_PEX0        PR105 -2          A18X+046397Y+110882X0198Y0197R090 S2      
327P0V8_PEX0        C4200 -1          A18X+040630Y+121610X0120Y0150R090 S2      
327P0V8_PEX0        C4201 -1          A18X+040260Y+121534X0120Y0150R090 S2      
327P0V8_PEX0        C4195 -1          A18X+039925Y+121537X0120Y0150R090 S2      
327P0V8_PEX0        C4190 -1          A18X+039595Y+121545X0120Y0150R090 S2      
327P0V8_PEX0        C4196 -1          A01X+040071Y+121759X0280Y0320R180 S1      
327P0V8_PEX0        C4198 -1          A18X+044384Y+121778X0280Y0320R180 S2      
327P0V8_PEX0        C4194 -1   M      A18X+043800Y+121778X0280Y0320R180 S2      
327P0V8_PEX0        C4192 -1          A18X+042456Y+121778X0280Y0320R180 S2      
327P0V8_PEX0        C4191 -1          A18X+041732Y+121778X0280Y0320R180 S2      
327P0V8_PEX0        C4193 -1          A18X+043010Y+121778X0280Y0320R180 S2      
327P0V8_PEX0        C4197 -1          A18X+041182Y+121778X0280Y0320R180 S2      
327P0V8_PEX0        C4199 -1          A01X+042682Y+121774X0280Y0320R180 S1      
327P0V8_PEX0        L50   -1   M      A01X+041452Y+125185X0460Y3860R090 S1      
327P0V8_PEX0        R5783 -1A  M      A01X+041452Y+125087X0590Y0790R090 S1      
327P0V8_PEX0        R5783 -1B  M      A01X+041452Y+125332X0100Y0200R090 S1      
327P0V8_PEX0        L49   -1   M      A01X+043812Y+123473X0460Y3860     S1      
327P0V8_PEX0        R5786 -1A  M      A01X+043763Y+123473X0590Y0790     S1      
327P0V8_PEX0        R5786 -1B  M      A01X+044008Y+123473X0100Y0200     S1      
327P0V8_PEX0        PC85  -1          A01X+045386Y+119197X0400Y0500R270 S1      
327P0V8_PEX0        PC69  -1          A01X+042693Y+119197X0400Y0500R270 S1      
327P0V8_PEX0        PC68  -1          A01X+040000Y+119197X0400Y0500R270 S1      
327P0V8_PEX0        PC72  -1          A01X+044040Y+118306X0950Y1110R090 S1      
327P0V8_PEX0        PC88  -1          A01X+041347Y+118306X0950Y1110R090 S1      
327P0V8_PEX0        PC67  -1          A01X+046269Y+115833X0198Y0197R270 S1      
327P0V8_PEX0        PL7   -2          A01X+044689Y+116776X1220Y1320R180 S1      
327P0V8_PEX0        PL6   -2          A01X+041906Y+116776X1220Y1320R180 S1      
327P0V8_PEX0        PC83  -1          A01X+040326Y+115833X0198Y0197R270 S1      
327P0V8_PEX0        L47   -1   M      A18X+041452Y+125185X0460Y3860R270 S2      
327P0V8_PEX0        R5785 -1A  M      A18X+041452Y+125087X0590Y0790R270 S2      
327P0V8_PEX0        R5785 -1B  M      A18X+041452Y+125332X0100Y0200R270 S2      
327P0V8_PEX0        L48   -1   M      A18X+043812Y+123473X0460Y3860R180 S2      
327P0V8_PEX0        R5784 -1A  M      A18X+043763Y+123473X0590Y0790R180 S2      
327P0V8_PEX0        R5784 -1B  M      A18X+044008Y+123473X0100Y0200R180 S2      
327P0V8_PEX0        PR76  -1          A18X+045562Y+119347X0198Y0197R180 S2      
327P0V8_PEX0        PR9   -1          A18X+043993Y+119257X0280Y0320     S2      
327P0V8_PEX0        PC84  -1          A18X+042693Y+119197X0400Y0500R090 S2      
327P0V8_PEX0        PC70  -1          A18X+041347Y+119197X0400Y0500R090 S2      
317P0V8_PEX0        VIA   -    MD0100PA00X+046269Y+116083X0200Y         S0      
327P0V8_PEX0        PC71  -1          A18X+044689Y+116874X0950Y1110R090 S2      
327P0V8_PEX0        PC86  -1          A18X+043298Y+115904X0400Y0500R270 S2      
317P0V8_PEX0        VIA   -    MD0100PA00X+043713Y+115827X0200Y         S0      
327P0V8_PEX0        PC87  -1          A18X+041906Y+116874X0950Y1110R090 S2      
317P0V8_PEX0        VIA   -    MD0100PA00X+043306Y+124143X0200Y    R180 S0      
317P0V8_PEX0        VIA   -    MD0100PA00X+043306Y+124543X0200Y    R180 S0      
317P0V8_PEX0        VIA   -    MD0100PA00X+042906Y+124143X0200Y    R180 S0      
317P0V8_PEX0        VIA   -    MD0100PA00X+042906Y+124543X0200Y    R180 S0      
317P0V8_PEX0        VIA   -    MD0100PA00X+042506Y+124143X0200Y    R180 S0      
317P0V8_PEX0        VIA   -    MD0100PA00X+042506Y+124543X0200Y    R180 S0      
317P0V8_PEX0        VIA   -    MD0100PA00X+042106Y+124143X0200Y    R180 S0      
317P0V8_PEX0        VIA   -    MD0100PA00X+042106Y+124543X0200Y    R180 S0      
317P0V8_PEX0        VIA   -    MD0100PA00X+041706Y+124143X0200Y    R180 S0      
317P0V8_PEX0        VIA   -    MD0100PA00X+041706Y+124543X0200Y    R180 S0      
317P0V8_PEX0        VIA   -    MD0100PA00X+041306Y+124143X0200Y    R180 S0      
317P0V8_PEX0        VIA   -    MD0100PA00X+041306Y+124543X0200Y    R180 S0      
317P0V8_PEX0        VIA   -    MD0100PA00X+040906Y+124143X0200Y    R180 S0      
317P0V8_PEX0        VIA   -    MD0100PA00X+040906Y+124543X0200Y    R180 S0      
317P0V8_PEX0        VIA   -    MD0100PA00X+040506Y+124143X0200Y    R180 S0      
317P0V8_PEX0        VIA   -    MD0100PA00X+040506Y+124543X0200Y    R180 S0      
317P0V8_PEX0        VIA   -    MD0100PA00X+040106Y+124143X0200Y    R180 S0      
317P0V8_PEX0        VIA   -    MD0100PA00X+043306Y+122543X0200Y    R180 S0      
317P0V8_PEX0        VIA   -    MD0100PA00X+043306Y+122943X0200Y    R180 S0      
317P0V8_PEX0        VIA   -    MD0100PA00X+043306Y+123343X0200Y    R180 S0      
317P0V8_PEX0        VIA   -    MD0100PA00X+043306Y+123743X0200Y    R180 S0      
317P0V8_PEX0        VIA   -    M      A01X+042906Y+122543X0200Y    R180 S2      
017P0V8_PEX0        VIA   -    M      A18X+042906Y+122543X0260Y    R180 S2      
017P0V8_PEX0              -    MD0100PA00X+042906Y+122543                       
317P0V8_PEX0        VIA   -    MD0100PA00X+042906Y+122943X0200Y    R180 S0      
317P0V8_PEX0        VIA   -    MD0100PA00X+042906Y+123343X0200Y    R180 S0      
317P0V8_PEX0        VIA   -    MD0100PA00X+042906Y+123743X0200Y    R180 S0      
317P0V8_PEX0        VIA   -    MD0100PA00X+042506Y+122543X0200Y    R180 S0      
317P0V8_PEX0        VIA   -    MD0100PA00X+042506Y+122943X0200Y    R180 S0      
317P0V8_PEX0        VIA   -    MD0100PA00X+042506Y+123343X0200Y    R180 S0      
317P0V8_PEX0        VIA   -    M      A01X+042506Y+123743X0200Y    R180 S2      
017P0V8_PEX0        VIA   -    M      A18X+042506Y+123743X0260Y    R180 S2      
017P0V8_PEX0              -    MD0100PA00X+042506Y+123743                       
317P0V8_PEX0        VIA   -    MD0100PA00X+042106Y+122543X0200Y    R180 S0      
317P0V8_PEX0        VIA   -    MD0100PA00X+042106Y+122943X0200Y    R180 S0      
317P0V8_PEX0        VIA   -    MD0100PA00X+042106Y+123343X0200Y    R180 S0      
317P0V8_PEX0        VIA   -    MD0100PA00X+042106Y+123743X0200Y    R180 S0      
317P0V8_PEX0        VIA   -    M      A01X+041706Y+122543X0200Y    R180 S2      
017P0V8_PEX0        VIA   -    M      A18X+041706Y+122543X0260Y    R180 S2      
017P0V8_PEX0              -    MD0100PA00X+041706Y+122543                       
317P0V8_PEX0        VIA   -    MD0100PA00X+041706Y+122943X0200Y    R180 S0      
317P0V8_PEX0        VIA   -    MD0100PA00X+041706Y+123343X0200Y    R180 S0      
317P0V8_PEX0        VIA   -    MD0100PA00X+041706Y+123743X0200Y    R180 S0      
317P0V8_PEX0        VIA   -    MD0100PA00X+041306Y+122543X0200Y    R180 S0      
317P0V8_PEX0        VIA   -    MD0100PA00X+041306Y+122943X0200Y    R180 S0      
317P0V8_PEX0        VIA   -    MD0100PA00X+041306Y+123343X0200Y    R180 S0      
317P0V8_PEX0        VIA   -    MD0100PA00X+041306Y+123743X0200Y    R180 S0      
317P0V8_PEX0        VIA   -    MD0100PA00X+040906Y+122543X0200Y    R180 S0      
317P0V8_PEX0        VIA   -    MD0100PA00X+040906Y+122943X0200Y    R180 S0      
317P0V8_PEX0        VIA   -    M      A01X+040906Y+123343X0200Y    R180 S2      
017P0V8_PEX0        VIA   -    M      A18X+040906Y+123343X0260Y    R180 S2      
017P0V8_PEX0              -    MD0100PA00X+040906Y+123343                       
317P0V8_PEX0        VIA   -    MD0100PA00X+040906Y+123743X0200Y    R180 S0      
317P0V8_PEX0        VIA   -    M      A01X+040506Y+122543X0200Y    R180 S2      
017P0V8_PEX0        VIA   -    M      A18X+040506Y+122543X0260Y    R180 S2      
017P0V8_PEX0              -    MD0100PA00X+040506Y+122543                       
317P0V8_PEX0        VIA   -    MD0100PA00X+040506Y+122943X0200Y    R180 S0      
317P0V8_PEX0        VIA   -    MD0100PA00X+040506Y+123343X0200Y    R180 S0      
317P0V8_PEX0        VIA   -    MD0100PA00X+040506Y+123743X0200Y    R180 S0      
317P0V8_PEX0        VIA   -    MD0100PA00X+040106Y+122543X0200Y    R180 S0      
317P0V8_PEX0        VIA   -    MD0100PA00X+040106Y+122943X0200Y    R180 S0      
317P0V8_PEX0        VIA   -    M      A01X+040106Y+123343X0200Y    R180 S2      
017P0V8_PEX0        VIA   -    M      A18X+040106Y+123343X0260Y    R180 S2      
017P0V8_PEX0              -    MD0100PA00X+040106Y+123343                       
317P0V8_PEX0        VIA   -    MD0100PA00X+040106Y+123743X0200Y    R180 S0      
317P0V8_PEX0        VIA   -    MD0100PA00X+039706Y+122543X0200Y    R180 S0      
317P0V8_PEX0        VIA   -    MD0100PA00X+039706Y+122943X0200Y    R180 S0      
317P0V8_PEX0        VIA   -    MD0100PA00X+039706Y+123343X0200Y    R180 S0      
317P0V8_PEX0        VIA   -    MD0100PA00X+043306Y+122143X0200Y    R180 S0      
317P0V8_PEX0        VIA   -    MD0100PA00X+042906Y+122143X0200Y    R180 S0      
317P0V8_PEX0        VIA   -    MD0100PA00X+042506Y+122143X0200Y    R180 S0      
317P0V8_PEX0        VIA   -    MD0100PA00X+042106Y+122143X0200Y    R180 S0      
317P0V8_PEX0        VIA   -    MD0100PA00X+041706Y+122143X0200Y    R180 S0      
317P0V8_PEX0        VIA   -    MD0100PA00X+041306Y+122143X0200Y    R180 S0      
317P0V8_PEX0        VIA   -    MD0100PA00X+040906Y+122143X0200Y    R180 S0      
317P0V8_PEX0        VIA   -    MD0100PA00X+040506Y+122143X0200Y    R180 S0      
317P0V8_PEX0        VIA   -    MD0100PA00X+040106Y+122143X0200Y    R180 S0      
317P0V8_PEX0        VIA   -    MD0100PA00X+039706Y+122143X0200Y    R180 S0      
317P0V8_PEX0        VIA   -    MD0100PA00X+044986Y+119262X0200Y         S0      
317P0V8_PEX0        VIA   -    MD0100PA00X+044986Y+119012X0200Y         S0      
317P0V8_PEX0        VIA   -    MD0100PA00X+043093Y+119262X0200Y    R180 S0      
317P0V8_PEX0        VIA   -    MD0100PA00X+043093Y+119012X0200Y    R180 S0      
317P0V8_PEX0        VIA   -    MD0100PA00X+041747Y+119012X0200Y    R180 S0      
317P0V8_PEX0        VIA   -    MD0100PA00X+041747Y+119262X0200Y    R180 S0      
317P0V8_PEX0        VIA   -    MD0100PA00X+042293Y+119012X0200Y         S0      
317P0V8_PEX0        VIA   -    MD0100PA00X+042293Y+119262X0200Y         S0      
317P0V8_PEX0        VIA   -    MD0100PA00X+040400Y+119012X0200Y    R180 S0      
317P0V8_PEX0        VIA   -    MD0100PA00X+040400Y+119262X0200Y    R180 S0      
317P0V8_PEX0        VIA   -    MD0100PA00X+044755Y+118692X0200Y    R180 S0      
317P0V8_PEX0        VIA   -    MD0100PA00X+044755Y+118442X0200Y    R180 S0      
317P0V8_PEX0        VIA   -    MD0100PA00X+044755Y+118192X0200Y    R180 S0      
317P0V8_PEX0        VIA   -    MD0100PA00X+044755Y+117942X0200Y    R180 S0      
317P0V8_PEX0        VIA   -    MD0100PA00X+045756Y+117488X0200Y         S0      
317P0V8_PEX0        VIA   -    MD0100PA00X+045506Y+117488X0200Y         S0      
317P0V8_PEX0        VIA   -    MD0100PA00X+043929Y+117488X0200Y         S0      
317P0V8_PEX0        VIA   -    MD0100PA00X+043679Y+117488X0200Y         S0      
317P0V8_PEX0        VIA   -    MD0100PA00X+042723Y+117488X0200Y         S0      
317P0V8_PEX0        VIA   -    MD0100PA00X+042973Y+117488X0200Y         S0      
317P0V8_PEX0        VIA   -    MD0100PA00X+043325Y+117921X0200Y         S0      
317P0V8_PEX0        VIA   -    MD0100PA00X+043325Y+118171X0200Y         S0      
317P0V8_PEX0        VIA   -    MD0100PA00X+043325Y+118421X0200Y         S0      
317P0V8_PEX0        VIA   -    MD0100PA00X+043325Y+118671X0200Y         S0      
317P0V8_PEX0        VIA   -    MD0100PA00X+041146Y+117488X0200Y         S0      
317P0V8_PEX0        VIA   -    MD0100PA00X+042062Y+118692X0200Y    R180 S0      
317P0V8_PEX0        VIA   -    MD0100PA00X+042062Y+118442X0200Y    R180 S0      
317P0V8_PEX0        VIA   -    MD0100PA00X+042062Y+118192X0200Y    R180 S0      
317P0V8_PEX0        VIA   -    MD0100PA00X+042062Y+117942X0200Y    R180 S0      
317P0V8_PEX0        VIA   -    MD0100PA00X+040632Y+117921X0200Y         S0      
317P0V8_PEX0        VIA   -    MD0100PA00X+040632Y+118171X0200Y         S0      
317P0V8_PEX0        VIA   -    MD0100PA00X+040632Y+118421X0200Y         S0      
317P0V8_PEX0        VIA   -    MD0100PA00X+040632Y+118671X0200Y         S0      
317P0V8_PEX0        VIA   -    MD0100PA00X+040896Y+117488X0200Y         S0      
327P0V8_PEX0        PEX0  -AC33       A01X+026476Y+117244X0180Y         S1      
317P0V8_PEX0        VIA   -    MD0100PA00X+045756Y+117238X0200Y         S0      
317P0V8_PEX0        VIA   -    MD0100PA00X+045506Y+117238X0200Y         S0      
317P0V8_PEX0        VIA   -    MD0100PA00X+045506Y+116988X0200Y         S0      
317P0V8_PEX0        VIA   -    MD0100PA00X+045506Y+116738X0200Y         S0      
317P0V8_PEX0        VIA   -    MD0100PA00X+045506Y+116488X0200Y         S0      
317P0V8_PEX0        VIA   -    MD0100PA00X+045506Y+116238X0200Y         S0      
317P0V8_PEX0        VIA   -    MD0100PA00X+045756Y+116238X0200Y         S0      
317P0V8_PEX0        VIA   -    MD0100PA00X+046291Y+110636X0200Y         S0      
317P0V8_PEX0        VIA   -    MD0100PA00X+045756Y+116488X0200Y         S0      
317P0V8_PEX0        VIA   -    MD0100PA00X+045756Y+116738X0200Y         S0      
317P0V8_PEX0        VIA   -    MD0100PA00X+045756Y+116988X0200Y         S0      
317P0V8_PEX0        VIA   -    MD0100PA00X+043929Y+116988X0200Y         S0      
317P0V8_PEX0        VIA   -    MD0100PA00X+043929Y+117238X0200Y         S0      
317P0V8_PEX0        VIA   -    MD0100PA00X+042723Y+116488X0200Y         S0      
317P0V8_PEX0        VIA   -    MD0100PA00X+042723Y+116738X0200Y         S0      
317P0V8_PEX0        VIA   -    MD0100PA00X+042723Y+116988X0200Y         S0      
317P0V8_PEX0        VIA   -    MD0100PA00X+042723Y+117238X0200Y         S0      
317P0V8_PEX0        VIA   -    MD0100PA00X+042973Y+117238X0200Y         S0      
317P0V8_PEX0        VIA   -    MD0100PA00X+042973Y+116988X0200Y         S0      
317P0V8_PEX0        VIA   -    MD0100PA00X+042973Y+116738X0200Y         S0      
317P0V8_PEX0        VIA   -    MD0100PA00X+042973Y+116488X0200Y         S0      
317P0V8_PEX0        VIA   -    MD0100PA00X+042973Y+116238X0200Y         S0      
317P0V8_PEX0        VIA   -    MD0100PA00X+042723Y+116238X0200Y         S0      
317P0V8_PEX0        VIA   -    MD0100PA00X+042968Y+110696X0200Y         S0      
317P0V8_PEX0        VIA   -    MD0100PA00X+043929Y+116238X0200Y         S0      
317P0V8_PEX0        VIA   -    MD0100PA00X+043929Y+116488X0200Y         S0      
317P0V8_PEX0        VIA   -    MD0100PA00X+043929Y+116738X0200Y         S0      
317P0V8_PEX0        VIA   -    MD0100PA00X+043679Y+116988X0200Y         S0      
317P0V8_PEX0        VIA   -    MD0100PA00X+043679Y+117238X0200Y         S0      
317P0V8_PEX0        VIA   -    MD0100PA00X+043679Y+116238X0200Y         S0      
317P0V8_PEX0        VIA   -    MD0100PA00X+043679Y+116488X0200Y         S0      
317P0V8_PEX0        VIA   -    MD0100PA00X+043679Y+116738X0200Y         S0      
317P0V8_PEX0        VIA   -    MD0100PA00X+041146Y+117238X0200Y         S0      
317P0V8_PEX0        VIA   -    MD0100PA00X+041146Y+116988X0200Y         S0      
317P0V8_PEX0        VIA   -    MD0100PA00X+041146Y+116738X0200Y         S0      
317P0V8_PEX0        VIA   -    MD0100PA00X+041146Y+116488X0200Y         S0      
317P0V8_PEX0        VIA   -    MD0100PA00X+041146Y+116238X0200Y         S0      
317P0V8_PEX0        VIA   -    MD0100PA00X+040326Y+116083X0200Y         S0      
317P0V8_PEX0        VIA   -    MD0100PA00X+040896Y+117238X0200Y         S0      
317P0V8_PEX0        VIA   -    MD0100PA00X+040896Y+116988X0200Y         S0      
317P0V8_PEX0        VIA   -    MD0100PA00X+040896Y+116738X0200Y         S0      
317P0V8_PEX0        VIA   -    MD0100PA00X+040896Y+116488X0200Y         S0      
317P0V8_PEX0        VIA   -    MD0100PA00X+040896Y+116238X0200Y         S0      
327P0V8_PEX0        PEX0  -AG33       A01X+026476Y+115748X0180Y         S1      
327P0V8_PEX0        PEX0  -AC25       A01X+023484Y+117244X0180Y         S1      
327P0V8_PEX0        PEX0  -AC17       A01X+020492Y+117244X0180Y         S1      
327P0V8_PEX0        C1110 -1   M      A18X+019245Y+118510X0120Y0150R180 S2      
327P0V8_PEX0        PEX0  -AA15       A01X+019744Y+117992X0180Y         S1      
327P0V8_PEX0        PEX0  -Y14 M      A01X+019370Y+118366X0180Y         S1      
327P0V8_PEX0        C1130 -1   M      A18X+025093Y+116683X0120Y0150     S2      
327P0V8_PEX0        C1127 -1   M      A18X+025841Y+116683X0120Y0150     S2      
327P0V8_PEX0        PEX0  -AE29       A01X+024980Y+116496X0180Y         S1      
327P0V8_PEX0        PEX0  -AD30M      A01X+025354Y+116870X0180Y         S1      
327P0V8_PEX0        PEX0  -AC31M      A01X+025728Y+117244X0180Y         S1      
327P0V8_PEX0        PEX0  -AE31       A01X+025728Y+116496X0180Y         S1      
327P0V8_PEX0        C1128 -1   M      A18X+023695Y+116690X0120Y0150R180 S2      
327P0V8_PEX0        C1107 -1   M      A18X+024405Y+116690X0120Y0150     S2      
327P0V8_PEX0        PEX0  -AE25       A01X+023484Y+116496X0180Y         S1      
327P0V8_PEX0        PEX0  -AD26       A01X+023858Y+116870X0180Y         S1      
327P0V8_PEX0        PEX0  -AC27M      A01X+024232Y+117244X0180Y         S1      
327P0V8_PEX0        PEX0  -AE27       A01X+024232Y+116496X0180Y         S1      
327P0V8_PEX0        PEX0  -AD28M      A01X+024606Y+116870X0180Y         S1      
327P0V8_PEX0        PEX0  -AC29M      A01X+024980Y+117244X0180Y         S1      
327P0V8_PEX0        C1109 -1   M      A18X+022485Y+116683X0120Y0150     S2      
327P0V8_PEX0        C1113 -1   M      A18X+021737Y+116683X0120Y0150     S2      
327P0V8_PEX0        PEX0  -AD22M      A01X+022362Y+116870X0180Y         S1      
327P0V8_PEX0        PEX0  -AE23       A01X+022736Y+116496X0180Y         S1      
327P0V8_PEX0        PEX0  -AC21M      A01X+021988Y+117244X0180Y         S1      
327P0V8_PEX0        PEX0  -AD24       A01X+023110Y+116870X0180Y         S1      
327P0V8_PEX0        PEX0  -AC23M      A01X+022736Y+117244X0180Y         S1      
327P0V8_PEX0        C1129 -1   M      A18X+020241Y+116683X0120Y0150     S2      
327P0V8_PEX0        C1111 -1   M      A18X+020989Y+116683X0120Y0150     S2      
327P0V8_PEX0        PEX0  -AC19M      A01X+021240Y+117244X0180Y         S1      
327P0V8_PEX0        PEX0  -AE21       A01X+021988Y+116496X0180Y         S1      
327P0V8_PEX0        PEX0  -AD20M      A01X+021614Y+116870X0180Y         S1      
327P0V8_PEX0        PEX0  -AE19       A01X+021240Y+116496X0180Y         S1      
327P0V8_PEX0        PEX0  -AD18M      A01X+020866Y+116870X0180Y         S1      
327P0V8_PEX0        PEX0  -AC15M      A01X+019744Y+117244X0180Y         S1      
327P0V8_PEX0        PEX0  -AB14M      A01X+019370Y+117618X0180Y         S1      
327P0V8_PEX0        PEX0  -AD16M      A01X+020118Y+116870X0180Y         S1      
327P0V8_PEX0        PEX0  -AE17       A01X+020492Y+116496X0180Y         S1      
327P0V8_PEX0        C1124 -1   M      A18X+019493Y+116683X0120Y0150     S2      
327P0V8_PEX0        PEX0  -AF14       A01X+019370Y+116122X0180Y         S1      
327P0V8_PEX0        PEX0  -AD14M      A01X+019370Y+116870X0180Y         S1      
327P0V8_PEX0        PEX0  -AE15       A01X+019744Y+116496X0180Y         S1      
327P0V8_PEX0        PEX0  -AF28       A01X+024606Y+116122X0180Y         S1      
327P0V8_PEX0        PEX0  -AG29M      A01X+024980Y+115748X0180Y         S1      
327P0V8_PEX0        PEX0  -AF30       A01X+025354Y+116122X0180Y         S1      
327P0V8_PEX0        PEX0  -AG31M      A01X+025728Y+115748X0180Y         S1      
327P0V8_PEX0        PEX0  -AG25       A01X+023484Y+115748X0180Y         S1      
327P0V8_PEX0        PEX0  -AF26       A01X+023858Y+116122X0180Y         S1      
327P0V8_PEX0        PEX0  -AG27M      A01X+024232Y+115748X0180Y         S1      
327P0V8_PEX0        PEX0  -AF22       A01X+022362Y+116122X0180Y         S1      
327P0V8_PEX0        PEX0  -AG21M      A01X+021988Y+115748X0180Y         S1      
327P0V8_PEX0        PEX0  -AF24       A01X+023110Y+116122X0180Y         S1      
327P0V8_PEX0        PEX0  -AG23M      A01X+022736Y+115748X0180Y         S1      
327P0V8_PEX0        PEX0  -AF20       A01X+021614Y+116122X0180Y         S1      
327P0V8_PEX0        PEX0  -AG19M      A01X+021240Y+115748X0180Y         S1      
327P0V8_PEX0        PEX0  -AF18       A01X+020866Y+116122X0180Y         S1      
327P0V8_PEX0        PEX0  -AG17M      A01X+020492Y+115748X0180Y         S1      
327P0V8_PEX0        PEX0  -AJ15       A01X+019744Y+115000X0180Y         S1      
327P0V8_PEX0        PEX0  -AK14M      A01X+019370Y+114626X0180Y         S1      
327P0V8_PEX0        PEX0  -AG15M      A01X+019744Y+115748X0180Y         S1      
327P0V8_PEX0        PEX0  -AF16       A01X+020118Y+116122X0180Y         S1      
327P0V8_PEX0        PEX0  -AH14M      A01X+019370Y+115374X0180Y         S1      
317m3496            VIA   -    MD0100PA01X+154705Y+136010X0180Y         S0      
317m3496            J14   -G3   D0122PA01X+149563Y+159169X0282Y    R180 S3      
327m3496            C756  -2          A01X+154695Y+135519X0120Y0150R090 S1      
317m3497            VIA   -    MD0100PA01X+155045Y+136010X0180Y         S0      
317m3497            J14   -F3   D0122PA01X+149563Y+159681X0282Y    R180 S3      
327m3497            C757  -2          A01X+155055Y+135519X0120Y0150R090 S1      
327m3498            J23   -B44        A01X+074550Y+056203X0140Y0480R090 S1      
327m3498            C227  -2          A01X+077107Y+056138X0120Y0150R180 S1      
317m3499            VIA   -    MD0080PA01X+077795Y+113130X0160Y    R270 S0      
327m3499            J23   -A21        A01X+072739Y+047730X0140Y0480R090 S1      
317m3499            VIA   -    MD0100PA01X+071379Y+047782X0200Y         S0      
327m3499            PEX1  -AP48       A01X+077795Y+113130X0180Y         S1      
317m3500            VIA   -    MD0080PA01X+075177Y+107894X0160Y         S0      
327m3500            J23   -A66        A01X+072739Y+061400X0140Y0480R090 S1      
317m3500            VIA   -    MD0100PA01X+071379Y+061452X0200Y         S0      
327m3500            PEX1  -BH41       A01X+075177Y+107894X0180Y         S1      
327m3501            J23   -B24        A01X+074550Y+048439X0140Y0480R090 S1      
327m3501            C238  -2          A01X+077107Y+048498X0120Y0150R180 S1      
327m3502            J23   -B30        A01X+074550Y+051199X0140Y0480R090 S1      
327m3502            C235  -2          A01X+077107Y+051134X0120Y0150R180 S1      
327m3503            J23   -B36        A01X+074550Y+052616X0140Y0480R090 S1      
327m3503            C231  -2          A01X+077107Y+052551X0120Y0150R180 S1      
327m3504            J23   -B56        A01X+074550Y+059037X0140Y0480R090 S1      
327m3504            C219  -2          A01X+077107Y+058972X0120Y0150R180 S1      
327m3505            J23   -B40        A01X+074550Y+053561X0140Y0480R090 S1      
327m3505            C228  -2          A01X+078148Y+053622X0120Y0150R180 S1      
317m3506            VIA   -    MD0080PA01X+076299Y+108268X0160Y         S0      
327m3506            J23   -A56        A01X+072739Y+059037X0140Y0480R090 S1      
317m3506            VIA   -    MD0100PA01X+072109Y+058986X0200Y         S0      
327m3506            PEX1  -BG44       A01X+076299Y+108268X0180Y         S1      
327m3507            J23   -B62        A01X+074550Y+060455X0140Y0480R090 S1      
327m3507            C215  -2          A01X+077107Y+060390X0120Y0150R180 S1      
317m3508            VIA   -    MD0080PA01X+075551Y+108268X0160Y         S0      
327m3508            J23   -A62        A01X+072739Y+060455X0140Y0480R090 S1      
317m3508            VIA   -    MD0100PA01X+072109Y+060403X0200Y         S0      
327m3508            PEX1  -BG42       A01X+075551Y+108268X0180Y         S1      
317m3509            VIA   -    MD0080PA01X+075925Y+107894X0160Y         S0      
327m3509            J23   -A60        A01X+072739Y+059982X0140Y0480R090 S1      
317m3509            VIA   -    MD0100PA01X+071379Y+060034X0200Y         S0      
327m3509            PEX1  -BH43       A01X+075925Y+107894X0180Y         S1      
327m3510            J23   -B26        A01X+074550Y+048911X0140Y0480R090 S1      
327m3510            C237  -2          A01X+078148Y+048849X0120Y0150R180 S1      
327m3511            J23   -B54        A01X+074550Y+058565X0140Y0480R090 S1      
327m3511            C220  -2          A01X+078148Y+058626X0120Y0150R180 S1      
317m3512            VIA   -    MD0080PA01X+075551Y+108642X0160Y         S0      
327m3512            J23   -A63        A01X+072739Y+060691X0140Y0480R090 S1      
317m3512            VIA   -    MD0100PA01X+072109Y+060743X0200Y         S0      
327m3512            PEX1  -BF42       A01X+075551Y+108642X0180Y         S1      
327m3513            J23   -B17        A01X+074550Y+046785X0140Y0480R090 S1      
327m3513            C243  -2          A01X+077107Y+046721X0120Y0150R180 S1      
327m3514            J23   -B18        A01X+074550Y+047022X0140Y0480R090 S1      
327m3514            C242  -2          A01X+077107Y+047081X0120Y0150R180 S1      
327m3515            J23   -B45        A01X+074550Y+056439X0140Y0480R090 S1      
327m3515            C226  -2          A01X+077107Y+056498X0120Y0150R180 S1      
317m3516            VIA   -    MD0080PA01X+077795Y+108268X0160Y    R270 S0      
327m3516            J23   -A45        A01X+072739Y+056439X0140Y0480R090 S1      
317m3516            VIA   -    MD0100PA01X+072109Y+056491X0200Y         S0      
327m3516            PEX1  -BG48       A01X+077795Y+108268X0180Y         S1      
327m3517            J23   -B59        A01X+074550Y+059746X0140Y0480R090 S1      
327m3517            C217  -2          A01X+078148Y+059684X0120Y0150R180 S1      
327m3518            J23   -B57        A01X+074550Y+059274X0140Y0480R090 S1      
327m3518            C218  -2          A01X+077107Y+059332X0120Y0150R180 S1      
317m3519            VIA   -    MD0080PA01X+076673Y+107894X0160Y         S0      
327m3519            J23   -A54        A01X+072739Y+058565X0140Y0480R090 S1      
317m3519            VIA   -    MD0100PA01X+071379Y+058617X0200Y         S0      
327m3519            PEX1  -BH45       A01X+076673Y+107894X0180Y         S1      
317m3520            VIA   -    MD0080PA01X+077421Y+112008X0160Y    R270 S0      
327m3520            J23   -A30        A01X+072739Y+051199X0140Y0480R090 S1      
317m3520            VIA   -    MD0100PA01X+072109Y+051147X0200Y         S0      
327m3520            PEX1  -AU47       A01X+077421Y+112008X0180Y         S1      
327m3521            J23   -B21        A01X+074550Y+047730X0140Y0480R090 S1      
327m3521            C240  -2          A01X+078148Y+047792X0120Y0150R180 S1      
327m3522            J23   -B34        A01X+074550Y+052144X0140Y0480R090 S1      
327m3522            C232  -2          A01X+078148Y+052205X0120Y0150R180 S1      
317m3523            VIA   -    MD0080PA01X+077795Y+111634X0160Y    R270 S0      
327m3523            J23   -A34        A01X+072739Y+052144X0140Y0480R090 S1      
317m3523            VIA   -    MD0100PA01X+071379Y+052196X0200Y         S0      
327m3523            PEX1  -AV48       A01X+077795Y+111634X0180Y         S1      
327m3524            J23   -B33        A01X+074550Y+051908X0140Y0480R090 S1      
327m3524            C233  -2          A01X+078148Y+051845X0120Y0150R180 S1      
317m3525            VIA   -    MD0080PA01X+077421Y+113504X0160Y    R270 S0      
327m3525            J23   -A17        A01X+072739Y+046785X0140Y0480R090 S1      
317m3525            VIA   -    MD0100PA01X+072109Y+046734X0200Y         S0      
327m3525            PEX1  -AN47       A01X+077421Y+113504X0180Y         S1      
317m3526            VIA   -    MD0080PA01X+077047Y+108268X0160Y         S0      
327m3526            J23   -A50        A01X+072739Y+057620X0140Y0480R090 S1      
317m3526            VIA   -    MD0100PA01X+072109Y+057568X0200Y         S0      
327m3526            PEX1  -BG46       A01X+077047Y+108268X0180Y         S1      
317m3527            VIA   -    MD0080PA01X+077421Y+107520X0160Y         S0      
327m3527            J23   -A47        A01X+072739Y+056911X0140Y0480R090 S1      
317m3527            VIA   -    MD0100PA01X+071379Y+056860X0200Y         S0      
327m3527            PEX1  -BJ47       A01X+077421Y+107520X0180Y         S1      
317m3528            VIA   -    MD0080PA01X+077047Y+108642X0160Y         S0      
327m3528            J23   -A51        A01X+072739Y+057856X0140Y0480R090 S1      
317m3528            VIA   -    MD0100PA01X+072109Y+057908X0200Y         S0      
327m3528            PEX1  -BF46       A01X+077047Y+108642X0180Y         S1      
327m3529            J23   -B47        A01X+074550Y+056911X0140Y0480R090 S1      
327m3529            C225  -2          A01X+078148Y+056849X0120Y0150R180 S1      
317m3530            VIA   -    MD0080PA01X+075925Y+107520X0160Y         S0      
327m3530            J23   -A59        A01X+072739Y+059746X0140Y0480R090 S1      
317m3530            VIA   -    MD0100PA01X+071379Y+059694X0200Y         S0      
327m3530            PEX1  -BJ43       A01X+075925Y+107520X0180Y         S1      
317m3531            VIA   -    MD0080PA01X+078169Y+110886X0160Y    R270 S0      
327m3531            J23   -A39        A01X+072739Y+053325X0140Y0480R090 S1      
317m3531            VIA   -    MD0100PA01X+071379Y+053273X0200Y         S0      
327m3531            PEX1  -AY49       A01X+078169Y+110886X0180Y         S1      
317m3532            VIA   -    MD0080PA01X+076673Y+107520X0160Y         S0      
327m3532            J23   -A53        A01X+072739Y+058329X0140Y0480R090 S1      
317m3532            VIA   -    MD0100PA01X+071379Y+058277X0200Y         S0      
327m3532            PEX1  -BJ45       A01X+076673Y+107520X0180Y         S1      
317m3533            VIA   -    MD0080PA01X+077047Y+112008X0160Y    R270 S0      
327m3533            J23   -A31        A01X+072739Y+051435X0140Y0480R090 S1      
317m3533            VIA   -    MD0100PA01X+072109Y+051487X0200Y         S0      
327m3533            PEX1  -AU46       A01X+077047Y+112008X0180Y         S1      
317m3534            VIA   -    MD0080PA01X+077795Y+110886X0160Y    R270 S0      
327m3534            J23   -A40        A01X+072739Y+053561X0140Y0480R090 S1      
317m3534            VIA   -    MD0100PA01X+071379Y+053613X0200Y         S0      
327m3534            PEX1  -AY48       A01X+077795Y+110886X0180Y         S1      
317m3535            VIA   -    MD0080PA01X+076299Y+108642X0160Y         S0      
327m3535            J23   -A57        A01X+072739Y+059274X0140Y0480R090 S1      
317m3535            VIA   -    MD0100PA01X+072109Y+059326X0200Y         S0      
327m3535            PEX1  -BF44       A01X+076299Y+108642X0180Y         S1      
327m3536            J23   -B65        A01X+074550Y+061163X0140Y0480R090 S1      
327m3536            C213  -2          A01X+078148Y+061101X0120Y0150R180 S1      
317m3537            VIA   -    MD0080PA01X+077421Y+107894X0160Y         S0      
327m3537            J23   -A48        A01X+072739Y+057148X0140Y0480R090 S1      
317m3537            VIA   -    MD0100PA01X+071379Y+057200X0200Y         S0      
327m3537            PEX1  -BH47       A01X+077421Y+107894X0180Y         S1      
317m3538            VIA   -    MD0080PA01X+078169Y+111634X0160Y    R270 S0      
327m3538            J23   -A33        A01X+072739Y+051908X0140Y0480R090 S1      
317m3538            VIA   -    MD0100PA01X+071379Y+051856X0200Y         S0      
327m3538            PEX1  -AV49       A01X+078169Y+111634X0180Y         S1      
327m3539            J23   -B20        A01X+074550Y+047494X0140Y0480R090 S1      
327m3539            C241  -2          A01X+078148Y+047432X0120Y0150R180 S1      
327m3540            J23   -B31        A01X+074550Y+051435X0140Y0480R090 S1      
327m3540            C234  -2          A01X+077107Y+051494X0120Y0150R180 S1      
327m3541            J23   -B27        A01X+074550Y+049148X0140Y0480R090 S1      
327m3541            C236  -2          A01X+078148Y+049209X0120Y0150R180 S1      
317m3542            VIA   -    MD0080PA01X+075177Y+107520X0160Y         S0      
327m3542            J23   -A65        A01X+072739Y+061163X0140Y0480R090 S1      
317m3542            VIA   -    MD0100PA01X+071379Y+061112X0200Y         S0      
327m3542            PEX1  -BJ41       A01X+075177Y+107520X0180Y         S1      
327m3543            J23   -B63        A01X+074550Y+060691X0140Y0480R090 S1      
327m3543            C214  -2          A01X+077107Y+060750X0120Y0150R180 S1      
317m3544            VIA   -    MD0080PA01X+077795Y+112382X0160Y    R270 S0      
327m3544            J23   -A27        A01X+072739Y+049148X0140Y0480R090 S1      
317m3544            VIA   -    MD0100PA01X+071379Y+049200X0200Y         S0      
327m3544            PEX1  -AT48       A01X+077795Y+112382X0180Y         S1      
327m3545            J23   -B39        A01X+074550Y+053325X0140Y0480R090 S1      
327m3545            C229  -2          A01X+078148Y+053262X0120Y0150R180 S1      
317m3546            VIA   -    MD0080PA01X+077421Y+112756X0160Y    R270 S0      
327m3546            J23   -A23        A01X+072739Y+048203X0140Y0480R090 S1      
317m3546            VIA   -    MD0100PA01X+072109Y+048151X0200Y         S0      
327m3546            PEX1  -AR47       A01X+077421Y+112756X0180Y         S1      
317m3547            VIA   -    MD0080PA01X+078169Y+112382X0160Y    R270 S0      
327m3547            J23   -A26        A01X+072739Y+048911X0140Y0480R090 S1      
317m3547            VIA   -    MD0100PA01X+071379Y+048860X0200Y         S0      
327m3547            PEX1  -AT49       A01X+078169Y+112382X0180Y         S1      
317m3548            VIA   -    MD0080PA01X+078169Y+113130X0160Y    R270 S0      
327m3548            J23   -A20        A01X+072739Y+047494X0140Y0480R090 S1      
317m3548            VIA   -    MD0100PA01X+071379Y+047442X0200Y         S0      
327m3548            PEX1  -AP49       A01X+078169Y+113130X0180Y         S1      
317m3549            VIA   -    MD0080PA01X+077047Y+111260X0160Y    R270 S0      
327m3549            J23   -A37        A01X+072739Y+052852X0140Y0480R090 S1      
317m3549            VIA   -    MD0100PA01X+072109Y+052904X0200Y         S0      
327m3549            PEX1  -AW46       A01X+077047Y+111260X0180Y         S1      
317m3550            VIA   -    MD0080PA01X+077047Y+113504X0160Y    R270 S0      
327m3550            J23   -A18        A01X+072739Y+047022X0140Y0480R090 S1      
317m3550            VIA   -    MD0100PA01X+072109Y+047074X0200Y         S0      
327m3550            PEX1  -AN46       A01X+077047Y+113504X0180Y         S1      
317m3551            VIA   -    MD0080PA01X+078169Y+108268X0160Y    R270 S0      
327m3551            J23   -A44        A01X+072739Y+056203X0140Y0480R090 S1      
317m3551            VIA   -    MD0100PA01X+072109Y+056151X0200Y         S0      
327m3551            PEX1  -BG49       A01X+078169Y+108268X0180Y         S1      
327m3552            J23   -B48        A01X+074550Y+057148X0140Y0480R090 S1      
327m3552            C224  -2          A01X+078148Y+057209X0120Y0150R180 S1      
327m3553            J23   -B53        A01X+074550Y+058329X0140Y0480R090 S1      
327m3553            C221  -2          A01X+078148Y+058266X0120Y0150R180 S1      
327m3554            J23   -B51        A01X+074550Y+057856X0140Y0480R090 S1      
327m3554            C222  -2          A01X+077107Y+057915X0120Y0150R180 S1      
327m3555            J23   -B66        A01X+074550Y+061400X0140Y0480R090 S1      
327m3555            C212  -2          A01X+078148Y+061461X0120Y0150R180 S1      
327m3556            J23   -B37        A01X+074550Y+052852X0140Y0480R090 S1      
327m3556            C230  -2          A01X+077107Y+052911X0120Y0150R180 S1      
327m3557            J23   -B50        A01X+074550Y+057620X0140Y0480R090 S1      
327m3557            C223  -2          A01X+077107Y+057555X0120Y0150R180 S1      
327m3558            J23   -B60        A01X+074550Y+059982X0140Y0480R090 S1      
327m3558            C216  -2          A01X+078148Y+060044X0120Y0150R180 S1      
317m3559            VIA   -    MD0080PA01X+077421Y+111260X0160Y    R270 S0      
327m3559            J23   -A36        A01X+072739Y+052616X0140Y0480R090 S1      
317m3559            VIA   -    MD0100PA01X+072109Y+052564X0200Y         S0      
327m3559            PEX1  -AW47       A01X+077421Y+111260X0180Y         S1      
327m3560            J23   -B23        A01X+074550Y+048203X0140Y0480R090 S1      
327m3560            C239  -2          A01X+077107Y+048138X0120Y0150R180 S1      
317m3561            VIA   -    MD0080PA01X+077047Y+112756X0160Y    R270 S0      
327m3561            J23   -A24        A01X+072739Y+048439X0140Y0480R090 S1      
317m3561            VIA   -    MD0100PA01X+072109Y+048491X0200Y         S0      
327m3561            PEX1  -AR46       A01X+077047Y+112756X0180Y         S1      
327NIC0_BIF1_N      VIA   -    M      A01X+015898Y+055937X0300Y         S1      
327NIC0_BIF1_N      R31   -1          A01X+014726Y+055856X0198Y0197R180 S1      
327NIC0_BIF1_N      R32   -1   M      A01X+015111Y+055856X0198Y0197     S1      
327NIC0_BIF1_N      J20   -B8         A01X+018127Y+055892X0140Y0480R270 S1      
317m3562            VIA   -    MD0100PA00X+117918Y+045388X0200Y         S0      
327m3562            J25   -A11        A01X+118448Y+045368X0140Y0480R090 S1      
317m3562            VIA   -    M      A01X+122994Y+034794X0200Y    R180 S2      
017m3562            VIA   -    M      A18X+122994Y+034794X0260Y    R180 S2      
017m3562                  -    MD0100PA00X+122994Y+034794                       
327m3562            R301  -1          A01X+123159Y+034547X0198Y0197R270 S1      
327NIC0_DATA_OUT    VIA   -    M      A01X+015824Y+061607X0300Y         S1      
327NIC0_DATA_OUT    R13   -1          A01X+015358Y+061560X0198Y0197R180 S1      
327NIC0_DATA_OUT    J20   -OB5        A01X+018127Y+061402X0140Y0480R270 S1      
327m3563            VIA   -    M      A01X+116699Y+040072X0300Y    R180 S1      
327m3563            R276  -1          A01X+114801Y+040072X0198Y0197R180 S1      
327m3563            J25   -OA7        A01X+118448Y+039622X0140Y0480R090 S1      
317m3564            VIA   -    MD0080PA01X+022362Y+108642X0160Y    R270 S0      
327m3564            PEX0  -BF22       A01X+022362Y+108642X0180Y         S1      
327m3564            J33   -A24        A01X+034907Y+012831X0150Y0500R090 S1      
317m3564            VIA   -    MD0100PA01X+034277Y+012883X0200Y         S0      
327m3565            J44   -B20        A01X+163608Y+011886X0150Y0500R090 S1      
327m3565            C719  -2          A01X+165538Y+011824X0120Y0150R180 S1      
317NIC5_DATA_OUT    VIA   -    M      A01X+121217Y+039150X0200Y         S2      
017NIC5_DATA_OUT    VIA   -    M      A18X+121217Y+039150X0260Y         S2      
017NIC5_DATA_OUT          -    MD0100PA00X+121217Y+039150                       
327NIC5_DATA_OUT    J25   -OB5        A01X+120259Y+039150X0140Y0480R090 S1      
327NIC5_DATA_OUT    R268  -1          A18X+121788Y+038591X0198Y0197R180 S2      
327P3V3_SSD7        R892  -1          A01X+079637Y+023613X0198Y0197R270 S1      
317P3V3_SSD7        VIA   -    MD0100PA00X+079637Y+023871X0200Y    R090 S0      
327P3V3_SSD7        PU61  -1          A01X+078638Y+021324X0110Y0240     S1      
327P3V3_SSD7        PU61  -2          A01X+078835Y+021324X0110Y0240     S1      
327P3V3_SSD7        PU61  -3          A01X+079032Y+021324X0110Y0240     S1      
327P3V3_SSD7        PU61  -4          A01X+079229Y+021324X0110Y0240     S1      
327P3V3_SSD7        PU61  -5          A01X+079426Y+021324X0110Y0240     S1      
327P3V3_SSD7        VIA   -           A18X+078974Y+019873X0260Y         S2      
327P3V3_SSD7        PC537 -1          A01X+078992Y+020064X0400Y0500     S1      
327P3V3_SSD7        PC536 -1          A01X+078885Y+020686X0198Y0197R180 S1      
327P3V3_SSD7        PD67  -C          A01X+079470Y+018984X0670Y0990R090 S1      
317P3V3_SSD7        VIA   -    MD0100PA00X+079676Y+020205X0200Y    R090 S0      
317P3V3_SSD7        VIA   -    MD0100PA00X+079376Y+020175X0200Y    R090 S0      
317P3V3_SSD7        VIA   -    MD0100PA00X+079232Y+021051X0200Y    R180 S0      
317P3V3_SSD7        VIA   -    MD0100PA00X+078982Y+021051X0200Y    R180 S0      
317P3V3_SSD7        VIA   -    MD0100PA00X+079159Y+020681X0200Y    R180 S0      
317P3V3_SSD7        VIA   -    MD0100PA00X+079409Y+020681X0200Y    R180 S0      
317P3V3_SSD7        VIA   -    MD0100PA00X+079376Y+019925X0200Y    R090 S0      
317P3V3_SSD7        VIA   -    MD0100PA00X+079224Y+019518X0200Y    R180 S0      
317P3V3_SSD7        VIA   -    MD0100PA00X+078974Y+019518X0200Y    R180 S0      
317P3V3_SSD7        VIA   -    MD0100PA00X+079474Y+019518X0200Y    R180 S0      
317P3V3_SSD7        VIA   -    MD0100PA00X+079724Y+019518X0200Y    R180 S0      
317P3V3_SSD7        VIA   -    M      A01X+079676Y+019925X0200Y    R090 S2      
017P3V3_SSD7        VIA   -    M      A18X+079676Y+019925X0260Y    R090 S2      
017P3V3_SSD7              -    MD0100PA00X+079676Y+019925                       
327P3V3_SSD7        R6075 -1          A01X+073601Y+014754X0198Y0197     S1      
317P3V3_SSD7        VIA   -    MD0100PA00X+073323Y+014754X0200Y         S0      
327P3V3_SSD7        R5745 -1          A01X+085034Y+010824X0198Y0197R270 S1      
317P3V3_SSD7        VIA   -    MD0100PA00X+084777Y+010619X0200Y    R090 S0      
327P3V3_SSD7        R430  -1          A01X+084083Y+010135X0198Y0197R270 S1      
317P3V3_SSD7        VIA   -    MD0100PA00X+084083Y+010378X0200Y    R270 S0      
327P3V3_SSD7        PU126 -6_7        A01X+077660Y+011762X0295Y0354R270 S1      
317P3V3_SSD7        VIA   -    MD0100PA00X+078114Y+011659X0200Y         S0      
317P3V3_SSD7        VIA   -    MD0100PA00X+078114Y+011959X0200Y         S0      
327P3V3_SSD7        PC933 -1   M      A01X+078541Y+011967X0400Y0500R090 S1      
327P3V3_SSD7        R5672 -2          A01X+078659Y+013484X0198Y0197     S1      
327P3V3_SSD7        C972  -2   M      A01X+083475Y+009855X0198Y0197R270 S1      
317P3V3_SSD7        VIA   -    MD0100PA00X+083728Y+009855X0200Y    R090 S0      
327P3V3_SSD7        J37   -B11        A01X+082427Y+009760X0150Y0500R090 S1      
327P3V3_SSD7        R431  -1          A01X+079320Y+009767X0198Y0197     S1      
317P3V3_SSD7        VIA   -    M      A01X+079076Y+009767X0200Y         S2      
017P3V3_SSD7        VIA   -    M      A18X+079076Y+009767X0260Y         S2      
017P3V3_SSD7              -    MD0100PA00X+079076Y+009767                       
327P3V3_SSD7        R1678 -1          A01X+085888Y+008058X0198Y0197R180 S1      
317P3V3_SSD7        VIA   -    MD0100PA00X+086130Y+008058X0200Y         S0      
327P3V3_SSD7        R1677 -1          A01X+085888Y+006858X0198Y0197R180 S1      
317P3V3_SSD7        VIA   -    MD0100PA00X+086128Y+006858X0200Y         S0      
327P3V3_SSD7        C2726 -2   M      A01X+086506Y+005801X0198Y0197R180 S1      
327P3V3_SSD7        U133  -1          A01X+086480Y+006472X0240Y0460R180 S1      
317P3V3_SSD7        VIA   -    MD0100PA00X+086506Y+005551X0200Y         S0      
317m3566            J7    -B2   D0122PA01X+114051Y+161650X0282Y    R180 S3      
317m3566            VIA   -    MD0080PA01X+105925Y+119114X0160Y         S0      
327m3566            PEX2  -V1         A01X+105925Y+119114X0180Y         S1      
317m3567            VIA   -    MD0080PA01X+156122Y+107520X0160Y    R270 S0      
327m3567            J43   -A26        A01X+151561Y+013303X0150Y0500R090 S1      
317m3567            VIA   -    MD0100PA01X+150201Y+013252X0200Y         S0      
327m3567            PEX3  -BJ13       A01X+156122Y+107520X0180Y         S1      
327P3V3_SSD6        R891  -1          A01X+069401Y+023613X0198Y0197R270 S1      
317P3V3_SSD6        VIA   -    MD0100PA00X+069401Y+023871X0200Y    R090 S0      
327P3V3_SSD6        PU58  -1          A01X+068402Y+021324X0110Y0240     S1      
327P3V3_SSD6        PU58  -2          A01X+068599Y+021324X0110Y0240     S1      
327P3V3_SSD6        PU58  -3          A01X+068796Y+021324X0110Y0240     S1      
327P3V3_SSD6        PU58  -4          A01X+068992Y+021324X0110Y0240     S1      
327P3V3_SSD6        PU58  -5          A01X+069189Y+021324X0110Y0240     S1      
327P3V3_SSD6        VIA   -           A18X+068738Y+019873X0260Y         S2      
327P3V3_SSD6        PC527 -1          A01X+068756Y+020064X0400Y0500     S1      
327P3V3_SSD6        PC526 -1          A01X+068648Y+020686X0198Y0197R180 S1      
327P3V3_SSD6        PD64  -C          A01X+069234Y+018984X0670Y0990R090 S1      
317P3V3_SSD6        VIA   -    MD0100PA00X+069173Y+020681X0200Y    R180 S0      
317P3V3_SSD6        VIA   -    MD0100PA00X+069440Y+020205X0200Y    R090 S0      
317P3V3_SSD6        VIA   -    MD0100PA00X+068996Y+021051X0200Y    R180 S0      
317P3V3_SSD6        VIA   -    MD0100PA00X+068746Y+021051X0200Y    R180 S0      
317P3V3_SSD6        VIA   -    MD0100PA00X+068923Y+020681X0200Y    R180 S0      
317P3V3_SSD6        VIA   -    MD0100PA00X+069140Y+020175X0200Y    R090 S0      
317P3V3_SSD6        VIA   -    MD0100PA00X+069238Y+019518X0200Y    R180 S0      
317P3V3_SSD6        VIA   -    MD0100PA00X+069488Y+019518X0200Y    R180 S0      
317P3V3_SSD6        VIA   -    M      A01X+069440Y+019925X0200Y    R090 S2      
017P3V3_SSD6        VIA   -    M      A18X+069440Y+019925X0260Y    R090 S2      
017P3V3_SSD6              -    MD0100PA00X+069440Y+019925                       
317P3V3_SSD6        VIA   -    MD0100PA00X+068988Y+019518X0200Y    R180 S0      
317P3V3_SSD6        VIA   -    MD0100PA00X+068738Y+019518X0200Y    R180 S0      
317P3V3_SSD6        VIA   -    MD0100PA00X+069140Y+019925X0200Y    R090 S0      
327P3V3_SSD6        R6074 -1          A01X+063365Y+014754X0198Y0197     S1      
317P3V3_SSD6        VIA   -    MD0100PA00X+063087Y+014754X0200Y         S0      
327P3V3_SSD6        R427  -1          A01X+073847Y+010135X0198Y0197R270 S1      
317P3V3_SSD6        VIA   -    MD0100PA00X+073847Y+010378X0200Y    R270 S0      
327P3V3_SSD6        R5743 -1          A01X+074798Y+010824X0198Y0197R270 S1      
317P3V3_SSD6        VIA   -    MD0100PA00X+074541Y+010619X0200Y    R090 S0      
317P3V3_SSD6        VIA   -    MD0100PA00X+067878Y+011659X0200Y         S0      
317P3V3_SSD6        VIA   -    MD0100PA00X+067878Y+011959X0200Y         S0      
327P3V3_SSD6        PU125 -6_7        A01X+067424Y+011762X0295Y0354R270 S1      
327P3V3_SSD6        PC931 -1   M      A01X+068305Y+011967X0400Y0500R090 S1      
327P3V3_SSD6        R5675 -2          A01X+068423Y+013484X0198Y0197     S1      
327P3V3_SSD6        C971  -2   M      A01X+073239Y+009855X0198Y0197R270 S1      
317P3V3_SSD6        VIA   -    MD0100PA00X+073492Y+009855X0200Y    R090 S0      
327P3V3_SSD6        J36   -B11        A01X+072191Y+009760X0150Y0500R090 S1      
327P3V3_SSD6        R429  -1          A01X+069083Y+009767X0198Y0197     S1      
317P3V3_SSD6        VIA   -    M      A01X+068840Y+009767X0200Y         S2      
017P3V3_SSD6        VIA   -    M      A18X+068840Y+009767X0260Y         S2      
017P3V3_SSD6              -    MD0100PA00X+068840Y+009767                       
327P3V3_SSD6        R1675 -1          A01X+075652Y+008058X0198Y0197R180 S1      
317P3V3_SSD6        VIA   -    MD0100PA00X+075894Y+008058X0200Y         S0      
327P3V3_SSD6        R1674 -1          A01X+075652Y+006858X0198Y0197R180 S1      
317P3V3_SSD6        VIA   -    MD0100PA00X+075892Y+006858X0200Y         S0      
327P3V3_SSD6        C2724 -2   M      A01X+076270Y+005801X0198Y0197R180 S1      
327P3V3_SSD6        U132  -1          A01X+076244Y+006472X0240Y0460R180 S1      
317P3V3_SSD6        VIA   -    MD0100PA00X+076270Y+005551X0200Y         S0      
317m3568            VIA   -    MD0080PA01X+155748Y+108642X0160Y    R270 S0      
327m3568            J42   -A18        A01X+141325Y+011413X0150Y0500R090 S1      
317m3568            VIA   -    MD0100PA01X+140695Y+011466X0200Y         S0      
327m3568            PEX3  -BF12       A01X+155748Y+108642X0180Y         S1      
327NCSI_NIC5_TXD0   VIA   -    M      A01X+116577Y+040872X0300Y    R180 S1      
327NCSI_NIC5_TXD0   R273  -1          A01X+114801Y+040872X0198Y0197R180 S1      
327NCSI_NIC5_TXD0   J25   -OA9        A01X+118448Y+040094X0140Y0480R090 S1      
327PU_CLKREQ6       J36   -A11        A01X+070380Y+009760X0150Y0500R090 S1      
317PU_CLKREQ6       VIA   -    M      A01X+069725Y+009767X0200Y         S2      
017PU_CLKREQ6       VIA   -    M      A18X+069725Y+009767X0260Y         S2      
017PU_CLKREQ6             -    MD0100PA00X+069725Y+009767                       
327PU_CLKREQ6       R429  -2          A01X+069398Y+009767X0198Y0197     S1      
327m3569            J42   -B17        A01X+143136Y+011177X0150Y0500R090 S1      
327m3569            C705  -2          A01X+144026Y+011112X0120Y0150R180 S1      
327m3570            J37   -B9         A01X+082427Y+009287X0150Y0500R090 S1      
317m3570            VIA   -    M      A01X+082900Y+009287X0200Y         S2      
017m3570            VIA   -    M      A18X+082900Y+009287X0260Y         S2      
017m3570                  -    MD0100PA00X+082900Y+009287                       
327m3570            R432  -2          A01X+084483Y+009820X0198Y0197R270 S1      
327m3570            R430  -2   M      A01X+084083Y+009820X0198Y0197R270 S1      
317m3571            VIA   -    MD0080PA01X+020492Y+107894X0160Y    R270 S0      
327m3571            J32   -A27        A01X+024671Y+013539X0150Y0500R090 S1      
317m3571            VIA   -    MD0100PA01X+023311Y+013592X0200Y         S0      
327m3571            PEX0  -BH17       A01X+020492Y+107894X0180Y         S1      
317m3572            VIA   -    MD0080PA01X+157618Y+107894X0160Y    R270 S0      
327m3572            J44   -A27        A01X+161797Y+013539X0150Y0500R090 S1      
317m3572            VIA   -    MD0100PA01X+160437Y+013592X0200Y         S0      
327m3572            PEX3  -BH17       A01X+157618Y+107894X0180Y         S1      
327PRSNTB3_NIC5_N   VIA   -    M      A01X+122493Y+062291X0300Y    R180 S1      
327PRSNTB3_NIC5_N   J25   -B70        A01X+120259Y+062344X0140Y0480R090 S1      
327PRSNTB3_NIC5_N   R297  -2          A01X+122968Y+062691X0198Y0197R180 S1      
327PRSNTB3_NIC5_N   R263  -1   M      A01X+122968Y+062291X0198Y0197     S1      
327m3573            J36   -B9         A01X+072191Y+009287X0150Y0500R090 S1      
317m3573            VIA   -    M      A01X+072664Y+009287X0200Y         S2      
017m3573            VIA   -    M      A18X+072664Y+009287X0260Y         S2      
017m3573                  -    MD0100PA00X+072664Y+009287                       
327m3573            R428  -2          A01X+074247Y+009820X0198Y0197R270 S1      
327m3573            R427  -2   M      A01X+073847Y+009820X0198Y0197R270 S1      
317m3574            VIA   -    MD0080PA01X+020866Y+108642X0160Y    R270 S0      
327m3574            J32   -A24        A01X+024671Y+012831X0150Y0500R090 S1      
317m3574            VIA   -    MD0100PA01X+024041Y+012883X0200Y         S0      
327m3574            PEX0  -BF18       A01X+020866Y+108642X0180Y         S1      
317m3575            VIA   -    MD0100PA01X+105811Y+138430X0180Y         S0      
317m3575            J7    -I1   D0122PA01X+113185Y+158146X0282Y    R180 S3      
327m3575            C614  -2          A01X+105821Y+137939X0120Y0150R090 S1      
327m3576            J44   -B24        A01X+163608Y+012831X0150Y0500R090 S1      
327m3576            C716  -2          A01X+164498Y+012890X0120Y0150R180 S1      
327NCSI_NIC5_TXD1   VIA   -    M      A01X+115657Y+040472X0300Y    R180 S1      
327NCSI_NIC5_TXD1   R274  -1          A01X+114801Y+040472X0198Y0197R180 S1      
327NCSI_NIC5_TXD1   J25   -OA8        A01X+118448Y+039858X0140Y0480R090 S1      
327PU_CLKREQ7       J37   -A11        A01X+080616Y+009760X0150Y0500R090 S1      
317PU_CLKREQ7       VIA   -    M      A01X+079962Y+009767X0200Y         S2      
017PU_CLKREQ7       VIA   -    M      A18X+079962Y+009767X0260Y         S2      
017PU_CLKREQ7             -    MD0100PA00X+079962Y+009767                       
327PU_CLKREQ7       R431  -2          A01X+079635Y+009767X0198Y0197     S1      
317m3577            J7    -C5   D0122PA01X+116650Y+161217X0282Y    R180 S3      
317m3577            VIA   -    MD0080PA01X+106673Y+120236X0160Y         S0      
327m3577            PEX2  -R3         A01X+106673Y+120236X0180Y         S1      
327m3578            J43   -B17        A01X+153372Y+011177X0150Y0500R090 S1      
327m3578            C713  -2          A01X+154262Y+011112X0120Y0150R180 S1      
327PRSNTB0_NIC5_N   VIA   -    M      A01X+122484Y+054034X0300Y    R180 S1      
327PRSNTB0_NIC5_N   J25   -B42        A01X+120259Y+054034X0140Y0480R090 S1      
327PRSNTB0_NIC5_N   R294  -2          A01X+122968Y+054591X0198Y0197R180 S1      
327PRSNTB0_NIC5_N   R260  -1   M      A01X+122968Y+054191X0198Y0197     S1      
327m3579            J45   -B17        A01X+173844Y+011177X0150Y0500R090 S1      
327m3579            C729  -2          A01X+174734Y+011112X0120Y0150R180 S1      
327PU_CLKREQ14      J44   -A11        A01X+161797Y+009760X0150Y0500R090 S1      
317PU_CLKREQ14      VIA   -    M      A01X+161143Y+009767X0200Y         S2      
017PU_CLKREQ14      VIA   -    M      A18X+161143Y+009767X0260Y         S2      
017PU_CLKREQ14            -    MD0100PA00X+161143Y+009767                       
327PU_CLKREQ14      R453  -2          A01X+160816Y+009767X0198Y0197     S1      
317m3580            VIA   -    MD0100PA01X+107035Y+140850X0180Y         S0      
317m3580            J7    -I3   D0122PA01X+114917Y+158146X0282Y    R180 S3      
327m3580            C610  -2          A01X+107045Y+140359X0120Y0150R090 S1      
327m3581            J42   -B20        A01X+143136Y+011886X0150Y0500R090 S1      
327m3581            C703  -2          A01X+145066Y+011824X0120Y0150R180 S1      
317m3582            VIA   -    M      A01X+120987Y+038205X0200Y         S2      
017m3582            VIA   -    M      A18X+120987Y+038205X0260Y         S2      
017m3582                  -    MD0100PA00X+120987Y+038205                       
327m3582            R259  -1          A18X+119175Y+038450X0198Y0197     S2      
327m3582            R277  -1   M      A18X+119510Y+038450X0198Y0197R180 S2      
327m3582            J25   -OB1        A01X+120259Y+038205X0140Y0480R090 S1      
327PU_CLKREQ15      J45   -A11        A01X+172033Y+009760X0150Y0500R090 S1      
317PU_CLKREQ15      VIA   -    M      A01X+171379Y+009767X0200Y         S2      
017PU_CLKREQ15      VIA   -    M      A18X+171379Y+009767X0260Y         S2      
017PU_CLKREQ15            -    MD0100PA00X+171379Y+009767                       
327PU_CLKREQ15      R456  -2          A01X+171052Y+009767X0198Y0197     S1      
317m3583            J7    -B8   D0122PA01X+119248Y+161650X0282Y    R180 S3      
317m3583            VIA   -    MD0080PA01X+105925Y+121358X0160Y         S0      
327m3583            PEX2  -M1         A01X+105925Y+121358X0180Y         S1      
317m3584            VIA   -    MD0080PA01X+159862Y+107894X0160Y    R270 S0      
327m3584            J45   -A21        A01X+172033Y+012122X0150Y0500R090 S1      
317m3584            VIA   -    MD0100PA01X+170673Y+012174X0200Y         S0      
327m3584            PEX3  -BH23       A01X+159862Y+107894X0180Y         S1      
327NIC5_SLOT_ID1    VIA   -    M      A01X+115913Y+039386X0300Y    R180 S1      
327NIC5_SLOT_ID1    R282  -1          A01X+114801Y+039672X0198Y0197R180 S1      
327NIC5_SLOT_ID1    R283  -1   M      A01X+114801Y+039272X0198Y0197R180 S1      
327NIC5_SLOT_ID1    J25   -OA6        A01X+118448Y+039386X0140Y0480R090 S1      
327m3585            J44   -B9         A01X+163608Y+009287X0150Y0500R090 S1      
317m3585            VIA   -    M      A01X+164081Y+009287X0200Y         S2      
017m3585            VIA   -    M      A18X+164081Y+009287X0260Y         S2      
017m3585                  -    MD0100PA00X+164081Y+009287                       
327m3585            R452  -2          A01X+165664Y+009820X0198Y0197R270 S1      
327m3585            R451  -2   M      A01X+165264Y+009820X0198Y0197R270 S1      
317m3586            VIA   -    MD0100PA01X+107035Y+136010X0180Y         S0      
317m3586            J7    -H2   D0122PA01X+114051Y+158579X0282Y    R180 S3      
327m3586            C612  -2          A01X+107045Y+135519X0120Y0150R090 S1      
317m3587            VIA   -    MD0080PA01X+156870Y+107520X0160Y    R270 S0      
327m3587            J43   -A20        A01X+151561Y+011886X0150Y0500R090 S1      
317m3587            VIA   -    MD0100PA01X+150201Y+011834X0200Y         S0      
327m3587            PEX3  -BJ15       A01X+156870Y+107520X0180Y         S1      
327m3588            U33   -1          A18X+118976Y+045163X0240Y0240R270 S2      
327m3588            R258  -1          A18X+119640Y+046324X0198Y0197     S2      
317m3588            VIA   -    M      A01X+119640Y+045857X0200Y         S2      
017m3588            VIA   -    M      A18X+119640Y+045857X0260Y         S2      
017m3588                  -    MD0100PA00X+119640Y+045857                       
327m3588            J25   -B12        A01X+120259Y+045604X0140Y0480R090 S1      
327m3589            J45   -B9         A01X+173844Y+009287X0150Y0500R090 S1      
317m3589            VIA   -    M      A01X+174318Y+009287X0200Y         S2      
017m3589            VIA   -    M      A18X+174318Y+009287X0260Y         S2      
017m3589                  -    MD0100PA00X+174318Y+009287                       
327m3589            R455  -2          A01X+175901Y+009820X0198Y0197R270 S1      
327m3589            R454  -2   M      A01X+175501Y+009820X0198Y0197R270 S1      
327m3590            J21   -B26        A01X+028842Y+048911X0140Y0480R090 S1      
327m3590            C26   -2          A01X+032439Y+048849X0120Y0150R180 S1      
327m3591            J44   -B26        A01X+163608Y+013303X0150Y0500R090 S1      
327m3591            C715  -2          A01X+165538Y+013241X0120Y0150R180 S1      
317m3592            VIA   -    M      A01X+121217Y+040900X0200Y         S2      
017m3592            VIA   -    M      A18X+121217Y+040900X0260Y         S2      
017m3592                  -    MD0100PA00X+121217Y+040900                       
327m3592            J25   -OB14       A01X+120259Y+041276X0140Y0480R090 S1      
327m3592            R270  -1          A18X+121788Y+040992X0198Y0197R180 S2      
327PRSNT_SSD6_N     J36   -A12        A01X+070380Y+009996X0150Y0500R090 S1      
317PRSNT_SSD6_N     VIA   -    M      A01X+069686Y+010341X0200Y         S2      
017PRSNT_SSD6_N     VIA   -    M      A18X+069686Y+010341X0260Y         S2      
017PRSNT_SSD6_N           -    MD0100PA00X+069686Y+010341                       
327PRSNT_SSD6_N     R4065 -2          A01X+069378Y+010341X0198Y0197R270 S1      
327m3593            J21   -B53        A01X+028842Y+058329X0140Y0480R090 S1      
327m3593            C10   -2          A01X+032439Y+058266X0120Y0150R180 S1      
317m3594            J7    -C1   D0122PA01X+113185Y+161217X0282Y    R180 S3      
317m3594            VIA   -    MD0080PA01X+106673Y+118740X0160Y         S0      
327m3594            PEX2  -W3         A01X+106673Y+118740X0180Y         S1      
327m3595            J43   -B18        A01X+153372Y+011413X0150Y0500R090 S1      
327m3595            C712  -2          A01X+154262Y+011472X0120Y0150R180 S1      
327m3596            J21   -B21        A01X+028842Y+047730X0140Y0480R090 S1      
327m3596            C29   -2          A01X+032439Y+047792X0120Y0150R180 S1      
317m3597            VIA   -    MD0080PA01X+157618Y+107520X0160Y    R270 S0      
327m3597            J44   -A26        A01X+161797Y+013303X0150Y0500R090 S1      
317m3597            VIA   -    MD0100PA01X+160437Y+013252X0200Y         S0      
327m3597            PEX3  -BJ17       A01X+157618Y+107520X0180Y         S1      
317NIC5_DATA_IN     VIA   -    M      A01X+121317Y+038650X0200Y         S2      
017NIC5_DATA_IN     VIA   -    M      A18X+121317Y+038650X0260Y         S2      
017NIC5_DATA_IN           -    MD0100PA00X+121317Y+038650                       
327NIC5_DATA_IN     J25   -OB4        A01X+120259Y+038913X0140Y0480R090 S1      
327NIC5_DATA_IN     R267  -1          A18X+121788Y+038191X0198Y0197R180 S2      
317m3598            VIA   -    MD0100PA01X+025670Y+058277X0200Y         S0      
327m3598            J21   -A53        A01X+027030Y+058329X0140Y0480R090 S1      
317m3598            VIA   -    MD0080PA01X+030964Y+107520X0160Y         S0      
327m3598            PEX0  -BJ45       A01X+030964Y+107520X0180Y         S1      
327m3599            J43   -B24        A01X+153372Y+012831X0150Y0500R090 S1      
327m3599            C708  -2          A01X+154262Y+012890X0120Y0150R180 S1      
327m3600            VIA   -    M      A01X+066417Y+068408X0300Y         S1      
327m3600            U21   -1          A01X+065844Y+068201X0220Y0530R180 S1      
327m3600            R153  -1   M      A01X+066199Y+068969X0198Y0197     S1      
327m3600            Q3    -6          A01X+066177Y+069480X0170Y0240R180 S1      
327m3601            VIA   -    M      A18X+120267Y+038800X0260Y         S2      
317m3601            VIA   -    MD0100PA00X+120669Y+038441X0200Y         S0      
327m3601            R257  -1          A18X+119825Y+038800X0198Y0197     S2      
327m3601            J25   -OB2        A01X+120259Y+038441X0140Y0480R090 S1      
317m3602            VIA   -    MD0080PA01X+032087Y+113130X0160Y    R270 S0      
327m3602            J21   -A21        A01X+027030Y+047730X0140Y0480R090 S1      
317m3602            VIA   -    MD0100PA01X+025670Y+047782X0200Y         S0      
327m3602            PEX0  -AP48       A01X+032087Y+113130X0180Y         S1      
317m3603            J7    -B6   D0122PA01X+117516Y+161650X0282Y    R180 S3      
317m3603            VIA   -    MD0080PA01X+105925Y+120610X0160Y         S0      
327m3603            PEX2  -P1         A01X+105925Y+120610X0180Y         S1      
317m3604            VIA   -    MD0080PA01X+159114Y+107894X0160Y    R270 S0      
327m3604            J45   -A27        A01X+172033Y+013539X0150Y0500R090 S1      
317m3604            VIA   -    MD0100PA01X+170673Y+013592X0200Y         S0      
327m3604            PEX3  -BH21       A01X+159114Y+107894X0180Y         S1      
317RST_HP_NIC2_N    VIA   -    M      A01X+065096Y+066815X0200Y         S2      
017RST_HP_NIC2_N    VIA   -    M      A18X+065096Y+066815X0260Y         S2      
017RST_HP_NIC2_N          -    MD0100PA00X+065096Y+066815                       
327RST_HP_NIC2_N    U20   -2          A01X+064393Y+065572X0160Y0360R270 S1      
327RST_HP_NIC2_N    U21   -4          A01X+065096Y+067236X0220Y0530R180 S1      
327P3V3_SSD0        R5652 -2          A01X+003484Y+028927X0198Y0197     S1      
317P3V3_SSD0        VIA   -    MD0100PA00X+003484Y+029176X0200Y         S0      
317P3V3_SSD0        VIA   -    MD0100PA00X+000704Y+027237X0200Y         S0      
327P3V3_SSD0        R5874 -1          A01X+000974Y+027237X0198Y0197     S1      
317P3V3_SSD0        VIA   -    MD0100PA00X+003220Y+023871X0200Y    R090 S0      
327P3V3_SSD0        R886  -1          A01X+003220Y+023613X0198Y0197R270 S1      
327P3V3_SSD0        PU54  -1          A01X+002221Y+021324X0110Y0240     S1      
327P3V3_SSD0        PU54  -2          A01X+002418Y+021324X0110Y0240     S1      
327P3V3_SSD0        PU54  -3          A01X+002615Y+021324X0110Y0240     S1      
327P3V3_SSD0        PU54  -4          A01X+002811Y+021324X0110Y0240     S1      
327P3V3_SSD0        PU54  -5          A01X+003008Y+021324X0110Y0240     S1      
327P3V3_SSD0        PC501 -1          A01X+002574Y+020064X0400Y0500     S1      
327P3V3_SSD0        PC500 -1          A01X+002467Y+020686X0198Y0197R180 S1      
327P3V3_SSD0        PD60  -C          A01X+003053Y+018984X0670Y0990R090 S1      
317P3V3_SSD0        VIA   -    MD0100PA00X+002742Y+020681X0200Y    R180 S0      
317P3V3_SSD0        VIA   -    MD0100PA00X+002958Y+020175X0200Y    R090 S0      
317P3V3_SSD0        VIA   -    MD0100PA00X+002815Y+021051X0200Y    R180 S0      
317P3V3_SSD0        VIA   -    MD0100PA00X+002565Y+021051X0200Y    R180 S0      
317P3V3_SSD0        VIA   -    MD0100PA00X+003258Y+020205X0200Y    R090 S0      
317P3V3_SSD0        VIA   -    MD0100PA00X+002992Y+020681X0200Y    R180 S0      
317P3V3_SSD0        VIA   -    M      A01X+003258Y+019925X0200Y    R090 S2      
017P3V3_SSD0        VIA   -    M      A18X+003258Y+019925X0260Y    R090 S2      
017P3V3_SSD0              -    MD0100PA00X+003258Y+019925                       
317P3V3_SSD0        VIA   -    MD0100PA00X+002958Y+019925X0200Y    R090 S0      
317P3V3_SSD0        VIA   -    MD0100PA00X+003307Y+019518X0200Y    R180 S0      
317P3V3_SSD0        VIA   -    MD0100PA00X+002557Y+019518X0200Y    R180 S0      
317P3V3_SSD0        VIA   -    MD0100PA00X+002807Y+019518X0200Y    R180 S0      
317P3V3_SSD0        VIA   -    MD0100PA00X+003057Y+019518X0200Y    R180 S0      
327P3V3_SSD0        PC671 -1          A01X+002720Y+016215X0400Y0500R090 S1      
327P3V3_SSD0        PU81  -6_7        A01X+001840Y+016010X0295Y0354R270 S1      
317P3V3_SSD0        VIA   -    MD0100PA00X+002294Y+015907X0200Y         S0      
317P3V3_SSD0        VIA   -    MD0100PA00X+002294Y+016207X0200Y         S0      
317P3V3_SSD0        VIA   -    MD0100PA00X+007666Y+010378X0200Y    R270 S0      
327P3V3_SSD0        R409  -1          A01X+007666Y+010135X0198Y0197R270 S1      
317P3V3_SSD0        VIA   -    MD0100PA00X+000800Y+010250X0200Y         S0      
327P3V3_SSD0        R1632 -1          A01X+000630Y+009974X0198Y0197R270 S1      
327P3V3_SSD0        U126  -1          A01X+000846Y+011171X0240Y0460R180 S1      
327P3V3_SSD0        C2712 -2   M      A01X+000621Y+010500X0198Y0197R180 S1      
317P3V3_SSD0        VIA   -    MD0100PA00X+001830Y+010214X0200Y         S0      
327P3V3_SSD0        R1633 -1          A01X+001830Y+009974X0198Y0197R270 S1      
327P3V3_SSD0        J30   -B11        A01X+006010Y+009760X0150Y0500R090 S1      
317P3V3_SSD0        VIA   -    MD0100PA00X+007311Y+009855X0200Y    R090 S0      
327P3V3_SSD0        C965  -2   M      A01X+007058Y+009855X0198Y0197R270 S1      
317P3V3_SSD0        VIA   -    M      A01X+002659Y+009767X0200Y         S2      
017P3V3_SSD0        VIA   -    M      A18X+002659Y+009767X0260Y         S2      
017P3V3_SSD0              -    MD0100PA00X+002659Y+009767                       
327P3V3_SSD0        R410  -1          A01X+002902Y+009767X0198Y0197     S1      
317P3V3_SSD0        VIA   -    MD0100PA00X+000879Y+008842X0200Y         S0      
327P3V3_SSD0        R5731 -1          A01X+000879Y+008550X0198Y0197R270 S1      
327m3605            J21   -B23        A01X+028842Y+048203X0140Y0480R090 S1      
327m3605            C28   -2          A01X+031399Y+048138X0120Y0150R180 S1      
317m3606            VIA   -    MD0100PA01X+107919Y+138430X0180Y         S0      
317m3606            J7    -I4   D0122PA01X+115783Y+158067X0282Y    R180 S3      
327m3606            C607  -2          A01X+107909Y+137939X0120Y0150R090 S1      
327m3607            J43   -B23        A01X+153372Y+012594X0150Y0500R090 S1      
327m3607            C709  -2          A01X+154262Y+012530X0120Y0150R180 S1      
317NCSI_NIC5_RXD0   VIA   -    M      A01X+121017Y+040350X0200Y         S2      
017NCSI_NIC5_RXD0   VIA   -    M      A18X+121017Y+040350X0260Y         S2      
017NCSI_NIC5_RXD0         -    MD0100PA00X+121017Y+040350                       
327NCSI_NIC5_RXD0   J25   -OB9        A01X+120259Y+040094X0140Y0480R090 S1      
327NCSI_NIC5_RXD0   R271  -1          A18X+121788Y+040592X0198Y0197R180 S2      
327P12V_SSD15       VIA   -           A18X+175825Y+008228X0260Y         S2      
327P12V_SSD15       VIA   -           A18X+175075Y+008228X0260Y         S2      
327P12V_SSD15       J45   -B1         A01X+173844Y+007398X0150Y0500R090 S1      
327P12V_SSD15       J45   -B2         A01X+173844Y+007634X0150Y0500R090 S1      
327P12V_SSD15       J45   -B3         A01X+173844Y+007870X0150Y0500R090 S1      
327P12V_SSD15       J45   -B4         A01X+173844Y+008106X0150Y0500R090 S1      
327P12V_SSD15       J45   -B5         A01X+173844Y+008342X0150Y0500R090 S1      
327P12V_SSD15       J45   -B6         A01X+173844Y+008579X0150Y0500R090 S1      
327P12V_SSD15       R679  -1          A01X+175206Y+017300X0198Y0197R090 S1      
327P12V_SSD15       R670  -1          A01X+174129Y+017069X1150Y1380R090 S1      
327P12V_SSD15       C3977 -1          A01X+175974Y+008845X0198Y0197R090 S1      
327P12V_SSD15       C3978 -1          A01X+175173Y+008845X0198Y0197R090 S1      
327P12V_SSD15       C3983 -1          A01X+175573Y+008845X0198Y0197R090 S1      
327P12V_SSD15       C3979 -1          A01X+174773Y+008845X0198Y0197R090 S1      
327P12V_SSD15       C3981 -1          A01X+175924Y+008014X0198Y0197     S1      
327P12V_SSD15       C3982 -1          A01X+175924Y+007614X0198Y0197     S1      
327P12V_SSD15       C3980 -1          A01X+175924Y+008414X0198Y0197     S1      
327P12V_SSD15       VIA   -           A18X+174513Y+016945X0260Y         S2      
317P12V_SSD15       VIA   -    MD0100PA00X+175192Y+017049X0200Y         S0      
317P12V_SSD15       VIA   -    MD0100PA00X+175192Y+016799X0200Y         S0      
327P12V_SSD15       VIA   -           A18X+173763Y+016945X0260Y         S2      
317P12V_SSD15       VIA   -    MD0100PA00X+175192Y+016539X0200Y         S0      
317P12V_SSD15       VIA   -    MD0100PA00X+175192Y+016279X0200Y         S0      
317P12V_SSD15       VIA   -    MD0100PA00X+174482Y+016237X0200Y    R090 S0      
317P12V_SSD15       VIA   -    MD0100PA00X+174222Y+016237X0200Y    R090 S0      
317P12V_SSD15       VIA   -    MD0100PA00X+174313Y+007774X0200Y         S0      
317P12V_SSD15       VIA   -    MD0100PA00X+174313Y+008034X0200Y         S0      
317P12V_SSD15       VIA   -    MD0100PA00X+174313Y+007514X0200Y         S0      
317P12V_SSD15       VIA   -    MD0100PA00X+174313Y+008294X0200Y         S0      
317P12V_SSD15       VIA   -    MD0100PA00X+174313Y+008554X0200Y         S0      
317m3608            VIA   -    MD0080PA01X+032087Y+108268X0160Y    R270 S0      
327m3608            PEX0  -BG48       A01X+032087Y+108268X0180Y         S1      
327m3608            J21   -A45        A01X+027030Y+056439X0140Y0480R090 S1      
317m3608            VIA   -    MD0100PA01X+026400Y+056491X0200Y         S0      
317m3609            VIA   -    MD0100PA01X+109483Y+136010X0180Y         S0      
317m3609            J7    -I5   D0122PA01X+116650Y+158146X0282Y    R180 S3      
327m3609            C606  -2          A01X+109493Y+135519X0120Y0150R090 S1      
317m3610            VIA   -    MD0080PA01X+158740Y+108642X0160Y    R270 S0      
327m3610            PEX3  -BF20       A01X+158740Y+108642X0180Y         S1      
327m3610            J44   -A18        A01X+161797Y+011413X0150Y0500R090 S1      
317m3610            VIA   -    MD0100PA01X+161167Y+011466X0200Y         S0      
327m3611            VIA   -    M      A01X+115600Y+038072X0300Y    R180 S1      
327m3611            J25   -OA1        A01X+118448Y+038205X0140Y0480R090 S1      
327m3611            R302  -1          A01X+114801Y+038072X0198Y0197R180 S1      
327P12V_SSD14       VIA   -           A18X+165421Y+007690X0260Y         S2      
327P12V_SSD14       VIA   -           A18X+164671Y+007690X0260Y         S2      
327P12V_SSD14       J44   -B1         A01X+163608Y+007398X0150Y0500R090 S1      
327P12V_SSD14       J44   -B2         A01X+163608Y+007634X0150Y0500R090 S1      
327P12V_SSD14       J44   -B3         A01X+163608Y+007870X0150Y0500R090 S1      
327P12V_SSD14       J44   -B4         A01X+163608Y+008106X0150Y0500R090 S1      
327P12V_SSD14       J44   -B5         A01X+163608Y+008342X0150Y0500R090 S1      
327P12V_SSD14       J44   -B6         A01X+163608Y+008579X0150Y0500R090 S1      
327P12V_SSD14       C3972 -1          A01X+165336Y+008845X0198Y0197R090 S1      
327P12V_SSD14       C3970 -1          A01X+165737Y+008845X0198Y0197R090 S1      
327P12V_SSD14       C3976 -1          A01X+164536Y+008845X0198Y0197R090 S1      
327P12V_SSD14       C3971 -1          A01X+164936Y+008845X0198Y0197R090 S1      
327P12V_SSD14       C3973 -1          A01X+165688Y+008414X0198Y0197     S1      
327P12V_SSD14       C3974 -1          A01X+165688Y+008014X0198Y0197     S1      
327P12V_SSD14       C3975 -1          A01X+165688Y+007614X0198Y0197     S1      
327P12V_SSD14       R668  -1          A01X+164970Y+017300X0198Y0197R090 S1      
327P12V_SSD14       R661  -1          A01X+163893Y+017069X1150Y1380R090 S1      
317P12V_SSD14       VIA   -    MD0100PA00X+164956Y+017049X0200Y         S0      
317P12V_SSD14       VIA   -    MD0100PA00X+164956Y+016799X0200Y         S0      
327P12V_SSD14       VIA   -           A18X+164276Y+016945X0260Y         S2      
327P12V_SSD14       VIA   -           A18X+163526Y+016945X0260Y         S2      
317P12V_SSD14       VIA   -    MD0100PA00X+164956Y+016539X0200Y         S0      
317P12V_SSD14       VIA   -    MD0100PA00X+164956Y+016279X0200Y         S0      
317P12V_SSD14       VIA   -    MD0100PA00X+164246Y+016237X0200Y    R090 S0      
317P12V_SSD14       VIA   -    MD0100PA00X+163986Y+016237X0200Y    R090 S0      
317P12V_SSD14       VIA   -    MD0100PA00X+164077Y+007774X0200Y         S0      
317P12V_SSD14       VIA   -    MD0100PA00X+164077Y+008034X0200Y         S0      
317P12V_SSD14       VIA   -    MD0100PA00X+164077Y+007514X0200Y         S0      
317P12V_SSD14       VIA   -    MD0100PA00X+164077Y+008294X0200Y         S0      
317P12V_SSD14       VIA   -    MD0100PA00X+164077Y+008554X0200Y         S0      
327m3612            J21   -B62        A01X+028842Y+060455X0140Y0480R090 S1      
327m3612            C4    -2          A01X+031399Y+060390X0120Y0150R180 S1      
317m3613            J7    -C7   D0122PA01X+118382Y+161217X0282Y    R180 S3      
317m3613            VIA   -    MD0080PA01X+106673Y+120984X0160Y         S0      
327m3613            PEX2  -N3         A01X+106673Y+120984X0180Y         S1      
327m3614            J43   -B20        A01X+153372Y+011886X0150Y0500R090 S1      
327m3614            C711  -2          A01X+155302Y+011824X0120Y0150R180 S1      
317NIC5_CLK         VIA   -    M      A01X+120653Y+039386X0200Y         S2      
017NIC5_CLK         VIA   -    M      A18X+120653Y+039386X0260Y         S2      
017NIC5_CLK               -    MD0100PA00X+120653Y+039386                       
327NIC5_CLK         J25   -OB6        A01X+120259Y+039386X0140Y0480R090 S1      
327NIC5_CLK         R269  -1          A18X+121788Y+038991X0198Y0197R180 S2      
327P12V_SSD13       VIA   -           A18X+155252Y+007690X0260Y         S2      
327P12V_SSD13       VIA   -           A18X+154502Y+007690X0260Y         S2      
327P12V_SSD13       J43   -B1         A01X+153372Y+007398X0150Y0500R090 S1      
327P12V_SSD13       J43   -B2         A01X+153372Y+007634X0150Y0500R090 S1      
327P12V_SSD13       J43   -B3         A01X+153372Y+007870X0150Y0500R090 S1      
327P12V_SSD13       J43   -B4         A01X+153372Y+008106X0150Y0500R090 S1      
327P12V_SSD13       J43   -B5         A01X+153372Y+008342X0150Y0500R090 S1      
327P12V_SSD13       J43   -B6         A01X+153372Y+008579X0150Y0500R090 S1      
327P12V_SSD13       R657  -1          A01X+154733Y+017300X0198Y0197R090 S1      
327P12V_SSD13       R649  -1          A01X+153657Y+017069X1150Y1380R090 S1      
327P12V_SSD13       C3963 -1          A01X+155501Y+008845X0198Y0197R090 S1      
327P12V_SSD13       C3969 -1          A01X+155100Y+008845X0198Y0197R090 S1      
327P12V_SSD13       C3966 -1          A01X+154700Y+008845X0198Y0197R090 S1      
327P12V_SSD13       C3964 -1          A01X+154300Y+008845X0198Y0197R090 S1      
327P12V_SSD13       C3965 -1          A01X+155452Y+008414X0198Y0197     S1      
327P12V_SSD13       C3967 -1          A01X+155452Y+007614X0198Y0197     S1      
327P12V_SSD13       C3968 -1          A01X+155452Y+008014X0198Y0197     S1      
327P12V_SSD13       VIA   -           A18X+154040Y+016945X0260Y         S2      
317P12V_SSD13       VIA   -    MD0100PA00X+154720Y+017049X0200Y         S0      
317P12V_SSD13       VIA   -    MD0100PA00X+154720Y+016799X0200Y         S0      
327P12V_SSD13       VIA   -           A18X+153290Y+016945X0260Y         S2      
317P12V_SSD13       VIA   -    MD0100PA00X+154720Y+016539X0200Y         S0      
317P12V_SSD13       VIA   -    MD0100PA00X+154720Y+016279X0200Y         S0      
317P12V_SSD13       VIA   -    MD0100PA00X+153750Y+016237X0200Y    R090 S0      
317P12V_SSD13       VIA   -    MD0100PA00X+154010Y+016237X0200Y    R090 S0      
317P12V_SSD13       VIA   -    MD0100PA00X+153841Y+007774X0200Y         S0      
317P12V_SSD13       VIA   -    MD0100PA00X+153841Y+008034X0200Y         S0      
317P12V_SSD13       VIA   -    MD0100PA00X+153841Y+007514X0200Y         S0      
317P12V_SSD13       VIA   -    MD0100PA00X+153841Y+008294X0200Y         S0      
317P12V_SSD13       VIA   -    MD0100PA00X+153841Y+008554X0200Y         S0      
327m3615            J21   -B56        A01X+028842Y+059037X0140Y0480R090 S1      
327m3615            C8    -2          A01X+031399Y+058972X0120Y0150R180 S1      
327m3616            J43   -B26        A01X+153372Y+013303X0150Y0500R090 S1      
327m3616            C707  -2          A01X+155302Y+013241X0120Y0150R180 S1      
327PRSNTB1_NIC5_N   VIA   -    M      A01X+117026Y+054271X0300Y    R180 S1      
327PRSNTB1_NIC5_N   R295  -2          A01X+116563Y+054671X0198Y0197     S1      
327PRSNTB1_NIC5_N   R261  -1   M      A01X+116563Y+054271X0198Y0197R180 S1      
327PRSNTB1_NIC5_N   J25   -A42        A01X+118448Y+054034X0140Y0480R090 S1      
327P12V_SSD12       VIA   -           A18X+145016Y+007690X0260Y         S2      
327P12V_SSD12       VIA   -           A18X+144266Y+007690X0260Y         S2      
327P12V_SSD12       J42   -B1         A01X+143136Y+007398X0150Y0500R090 S1      
327P12V_SSD12       J42   -B2         A01X+143136Y+007634X0150Y0500R090 S1      
327P12V_SSD12       J42   -B3         A01X+143136Y+007870X0150Y0500R090 S1      
327P12V_SSD12       J42   -B4         A01X+143136Y+008106X0150Y0500R090 S1      
327P12V_SSD12       J42   -B5         A01X+143136Y+008342X0150Y0500R090 S1      
327P12V_SSD12       J42   -B6         A01X+143136Y+008579X0150Y0500R090 S1      
327P12V_SSD12       C3956 -1          A01X+145265Y+008845X0198Y0197R090 S1      
327P12V_SSD12       C3957 -1          A01X+144464Y+008845X0198Y0197R090 S1      
327P12V_SSD12       C3959 -1          A01X+144064Y+008845X0198Y0197R090 S1      
327P12V_SSD12       C3962 -1          A01X+144864Y+008845X0198Y0197R090 S1      
327P12V_SSD12       C3961 -1          A01X+145216Y+008414X0198Y0197     S1      
327P12V_SSD12       C3958 -1          A01X+145216Y+007614X0198Y0197     S1      
327P12V_SSD12       C3960 -1          A01X+145216Y+008014X0198Y0197     S1      
327P12V_SSD12       R646  -1          A01X+144497Y+017300X0198Y0197R090 S1      
327P12V_SSD12       R638  -1          A01X+143420Y+017069X1150Y1380R090 S1      
327P12V_SSD12       VIA   -           A18X+143804Y+016945X0260Y         S2      
317P12V_SSD12       VIA   -    MD0100PA00X+144484Y+016799X0200Y         S0      
317P12V_SSD12       VIA   -    MD0100PA00X+144484Y+017049X0200Y         S0      
327P12V_SSD12       VIA   -           A18X+143054Y+016945X0260Y         S2      
317P12V_SSD12       VIA   -    MD0100PA00X+144484Y+016539X0200Y         S0      
317P12V_SSD12       VIA   -    MD0100PA00X+144484Y+016279X0200Y         S0      
317P12V_SSD12       VIA   -    MD0100PA00X+143774Y+016237X0200Y    R090 S0      
317P12V_SSD12       VIA   -    MD0100PA00X+143514Y+016237X0200Y    R090 S0      
317P12V_SSD12       VIA   -    MD0100PA00X+143604Y+007999X0200Y         S0      
317P12V_SSD12       VIA   -    MD0100PA00X+143604Y+008259X0200Y         S0      
317P12V_SSD12       VIA   -    MD0100PA00X+143604Y+008519X0200Y         S0      
317P12V_SSD12       VIA   -    MD0100PA00X+143604Y+007479X0200Y         S0      
317P12V_SSD12       VIA   -    MD0100PA00X+143604Y+007739X0200Y         S0      
317m3617            VIA   -    MD0080PA01X+031712Y+112756X0160Y    R270 S0      
327m3617            PEX0  -AR47       A01X+031712Y+112756X0180Y         S1      
327m3617            J21   -A23        A01X+027030Y+048203X0140Y0480R090 S1      
317m3617            VIA   -    MD0100PA01X+026400Y+048151X0200Y         S0      
317m3618            VIA   -    MD0080PA01X+157244Y+108268X0160Y    R270 S0      
327m3618            PEX3  -BG16       A01X+157244Y+108268X0180Y         S1      
327m3618            J43   -A17        A01X+151561Y+011177X0150Y0500R090 S1      
317m3618            VIA   -    MD0100PA01X+150931Y+011126X0200Y         S0      
317PRSNTB2_NIC5_N   VIA   -    M      A01X+117614Y+045846X0200Y         S2      
017PRSNTB2_NIC5_N   VIA   -    M      A18X+117614Y+045846X0260Y         S2      
017PRSNTB2_NIC5_N         -    MD0100PA00X+117614Y+045846                       
327PRSNTB2_NIC5_N   R296  -2          A01X+116645Y+046286X0198Y0197     S1      
327PRSNTB2_NIC5_N   R262  -1   M      A01X+116645Y+045886X0198Y0197R180 S1      
327PRSNTB2_NIC5_N   J25   -A12        A01X+118448Y+045604X0140Y0480R090 S1      
327P12V_SSD11       VIA   -           A18X+129847Y+007824X0260Y         S2      
327P12V_SSD11       VIA   -           A18X+129097Y+007824X0260Y         S2      
327P12V_SSD11       J41   -B1         A01X+128136Y+007398X0150Y0500R090 S1      
327P12V_SSD11       J41   -B2         A01X+128136Y+007634X0150Y0500R090 S1      
327P12V_SSD11       J41   -B3         A01X+128136Y+007870X0150Y0500R090 S1      
327P12V_SSD11       J41   -B4         A01X+128136Y+008106X0150Y0500R090 S1      
327P12V_SSD11       J41   -B5         A01X+128136Y+008342X0150Y0500R090 S1      
327P12V_SSD11       J41   -B6         A01X+128136Y+008579X0150Y0500R090 S1      
327P12V_SSD11       C3951 -1          A01X+129864Y+008845X0198Y0197R090 S1      
327P12V_SSD11       C3953 -1          A01X+129464Y+008845X0198Y0197R090 S1      
327P12V_SSD11       C3949 -1          A01X+130265Y+008845X0198Y0197R090 S1      
327P12V_SSD11       C3952 -1          A01X+129064Y+008845X0198Y0197R090 S1      
327P12V_SSD11       C3950 -1          A01X+130215Y+008414X0198Y0197     S1      
327P12V_SSD11       C3954 -1          A01X+130215Y+007614X0198Y0197     S1      
327P12V_SSD11       C3955 -1          A01X+130215Y+008014X0198Y0197     S1      
327P12V_SSD11       R635  -1          A01X+129497Y+017300X0198Y0197R090 S1      
327P12V_SSD11       R626  -1          A01X+128420Y+017069X1150Y1380R090 S1      
317P12V_SSD11       VIA   -    MD0100PA00X+129484Y+017049X0200Y         S0      
317P12V_SSD11       VIA   -    MD0100PA00X+129484Y+016799X0200Y         S0      
327P12V_SSD11       VIA   -           A18X+128804Y+016945X0260Y         S2      
327P12V_SSD11       VIA   -           A18X+128054Y+016945X0260Y         S2      
317P12V_SSD11       VIA   -    MD0100PA00X+129484Y+016539X0200Y         S0      
317P12V_SSD11       VIA   -    MD0100PA00X+128774Y+016237X0200Y    R090 S0      
317P12V_SSD11       VIA   -    MD0100PA00X+129484Y+016279X0200Y         S0      
317P12V_SSD11       VIA   -    MD0100PA00X+128514Y+016237X0200Y    R090 S0      
317P12V_SSD11       VIA   -    MD0100PA00X+128604Y+007774X0200Y         S0      
317P12V_SSD11       VIA   -    MD0100PA00X+128604Y+008034X0200Y         S0      
317P12V_SSD11       VIA   -    MD0100PA00X+128604Y+007514X0200Y         S0      
317P12V_SSD11       VIA   -    MD0100PA00X+128604Y+008294X0200Y         S0      
317P12V_SSD11       VIA   -    MD0100PA00X+128604Y+008554X0200Y         S0      
327m3619            J21   -B31        A01X+028842Y+051435X0140Y0480R090 S1      
327m3619            C23   -2          A01X+031399Y+051494X0120Y0150R180 S1      
317m3620            VIA   -    MD0100PA01X+105471Y+138430X0180Y         S0      
317m3620            J7    -J1   D0122PA01X+113185Y+157634X0282Y    R180 S3      
327m3620            C613  -2          A01X+105461Y+137939X0120Y0150R090 S1      
317m3621            VIA   -    MD0080PA01X+157992Y+108642X0160Y    R270 S0      
327m3621            J44   -A24        A01X+161797Y+012831X0150Y0500R090 S1      
317m3621            VIA   -    MD0100PA01X+161167Y+012883X0200Y         S0      
327m3621            PEX3  -BF18       A01X+157992Y+108642X0180Y         S1      
327m3622            VIA   -    M      A01X+116031Y+038788X0300Y    R180 S1      
327m3622            R256  -2          A01X+114801Y+038872X0198Y0197     S1      
327m3622            J25   -OA4        A01X+118448Y+038913X0140Y0480R090 S1      
327P12V_SSD10       VIA   -           A18X+119746Y+008094X0260Y         S2      
327P12V_SSD10       VIA   -           A18X+118996Y+008094X0260Y         S2      
327P12V_SSD10       J40   -B1         A01X+117900Y+007398X0150Y0500R090 S1      
327P12V_SSD10       J40   -B2         A01X+117900Y+007634X0150Y0500R090 S1      
327P12V_SSD10       J40   -B3         A01X+117900Y+007870X0150Y0500R090 S1      
327P12V_SSD10       J40   -B4         A01X+117900Y+008106X0150Y0500R090 S1      
327P12V_SSD10       J40   -B5         A01X+117900Y+008342X0150Y0500R090 S1      
327P12V_SSD10       J40   -B6         A01X+117900Y+008579X0150Y0500R090 S1      
327P12V_SSD10       R624  -1          A01X+119261Y+017300X0198Y0197R090 S1      
327P12V_SSD10       R615  -1          A01X+118184Y+017069X1150Y1380R090 S1      
327P12V_SSD10       C3943 -1          A01X+119628Y+008845X0198Y0197R090 S1      
327P12V_SSD10       C3942 -1          A01X+120029Y+008845X0198Y0197R090 S1      
327P12V_SSD10       C3947 -1          A01X+119228Y+008845X0198Y0197R090 S1      
327P12V_SSD10       C3945 -1          A01X+118828Y+008845X0198Y0197R090 S1      
327P12V_SSD10       C3946 -1          A01X+119979Y+008414X0198Y0197     S1      
327P12V_SSD10       C3944 -1          A01X+119979Y+007614X0198Y0197     S1      
327P12V_SSD10       C3948 -1          A01X+119979Y+008014X0198Y0197     S1      
317P12V_SSD10       VIA   -    MD0100PA00X+119248Y+017049X0200Y         S0      
317P12V_SSD10       VIA   -    MD0100PA00X+119248Y+016799X0200Y         S0      
327P12V_SSD10       VIA   -           A18X+118568Y+016945X0260Y         S2      
327P12V_SSD10       VIA   -           A18X+117818Y+016945X0260Y         S2      
317P12V_SSD10       VIA   -    MD0100PA00X+119248Y+016279X0200Y         S0      
317P12V_SSD10       VIA   -    MD0100PA00X+119248Y+016539X0200Y         S0      
317P12V_SSD10       VIA   -    MD0100PA00X+118538Y+016237X0200Y         S0      
317P12V_SSD10       VIA   -    MD0100PA00X+118278Y+016237X0200Y         S0      
317P12V_SSD10       VIA   -    MD0100PA00X+118368Y+007739X0200Y         S0      
317P12V_SSD10       VIA   -    MD0100PA00X+118368Y+007999X0200Y         S0      
317P12V_SSD10       VIA   -    MD0100PA00X+118368Y+007479X0200Y         S0      
317P12V_SSD10       VIA   -    MD0100PA00X+118368Y+008259X0200Y         S0      
317P12V_SSD10       VIA   -    MD0100PA00X+118368Y+008519X0200Y         S0      
327PRSNT_SSD15_N    J45   -A12        A01X+172033Y+009996X0150Y0500R090 S1      
317PRSNT_SSD15_N    VIA   -    M      A01X+171339Y+010341X0200Y         S2      
017PRSNT_SSD15_N    VIA   -    M      A18X+171339Y+010341X0260Y         S2      
017PRSNT_SSD15_N          -    MD0100PA00X+171339Y+010341                       
327PRSNT_SSD15_N    R4083 -2          A01X+171032Y+010341X0198Y0197R270 S1      
317m3623            VIA   -    MD0080PA01X+032087Y+112382X0160Y    R270 S0      
327m3623            J21   -A27        A01X+027030Y+049148X0140Y0480R090 S1      
317m3623            VIA   -    MD0100PA01X+025670Y+049200X0200Y         S0      
327m3623            PEX0  -AT48       A01X+032087Y+112382X0180Y         S1      
317m3624            VIA   -    MD0100PA01X+106695Y+140850X0180Y         S0      
317m3624            J7    -J3   D0122PA01X+114917Y+157634X0282Y    R180 S3      
327m3624            C609  -2          A01X+106685Y+140359X0120Y0150R090 S1      
317m3625            VIA   -    MD0080PA01X+155374Y+107520X0160Y    R270 S0      
327m3625            J42   -A20        A01X+141325Y+011886X0150Y0500R090 S1      
317m3625            VIA   -    MD0100PA01X+139965Y+011834X0200Y         S0      
327m3625            PEX3  -BJ11       A01X+155374Y+107520X0180Y         S1      
317m3626            VIA   -    MD0100PA01X+166376Y+140850X0180Y         S0      
317m3626            J9    -I7   D0122PA01X+170350Y+158146X0282Y    R180 S3      
327m3626            C813  -2          A01X+166386Y+140359X0120Y0150R090 S1      
327m3627            VIA   -    M      A01X+115673Y+041272X0300Y    R180 S1      
327m3627            R275  -1          A01X+114801Y+041272X0198Y0197R180 S1      
327m3627            J25   -OA14       A01X+118448Y+041276X0140Y0480R090 S1      
327P12V_SSD9        VIA   -           A18X+109341Y+007892X0260Y         S2      
327P12V_SSD9        VIA   -           A18X+108591Y+007892X0260Y         S2      
327P12V_SSD9        J39   -B1         A01X+107663Y+007398X0150Y0500R090 S1      
327P12V_SSD9        J39   -B2         A01X+107663Y+007634X0150Y0500R090 S1      
327P12V_SSD9        J39   -B3         A01X+107663Y+007870X0150Y0500R090 S1      
327P12V_SSD9        J39   -B4         A01X+107663Y+008106X0150Y0500R090 S1      
327P12V_SSD9        J39   -B5         A01X+107663Y+008342X0150Y0500R090 S1      
327P12V_SSD9        J39   -B6         A01X+107663Y+008579X0150Y0500R090 S1      
327P12V_SSD9        R613  -1          A01X+109025Y+017300X0198Y0197R090 S1      
327P12V_SSD9        R605  -1          A01X+107948Y+017069X1150Y1380R090 S1      
327P12V_SSD9        C3937 -1          A01X+109392Y+008845X0198Y0197R090 S1      
327P12V_SSD9        C3935 -1          A01X+109792Y+008845X0198Y0197R090 S1      
327P12V_SSD9        C3940 -1          A01X+108592Y+008845X0198Y0197R090 S1      
327P12V_SSD9        C3941 -1          A01X+108992Y+008845X0198Y0197R090 S1      
327P12V_SSD9        C3936 -1          A01X+109743Y+007614X0198Y0197     S1      
327P12V_SSD9        C3939 -1          A01X+109743Y+008014X0198Y0197     S1      
327P12V_SSD9        C3938 -1          A01X+109743Y+008414X0198Y0197     S1      
327P12V_SSD9        VIA   -           A18X+108332Y+016945X0260Y         S2      
317P12V_SSD9        VIA   -    MD0100PA00X+109011Y+016799X0200Y         S0      
317P12V_SSD9        VIA   -    MD0100PA00X+109011Y+017049X0200Y         S0      
327P12V_SSD9        VIA   -           A18X+107582Y+016945X0260Y         S2      
317P12V_SSD9        VIA   -    MD0100PA00X+108041Y+016237X0200Y    R090 S0      
317P12V_SSD9        VIA   -    MD0100PA00X+109011Y+016279X0200Y         S0      
317P12V_SSD9        VIA   -    MD0100PA00X+109011Y+016539X0200Y         S0      
317P12V_SSD9        VIA   -    MD0100PA00X+108301Y+016237X0200Y    R090 S0      
317P12V_SSD9        VIA   -    MD0100PA00X+108132Y+007479X0200Y         S0      
317P12V_SSD9        VIA   -    MD0100PA00X+108132Y+007739X0200Y         S0      
317P12V_SSD9        VIA   -    MD0100PA00X+108132Y+007999X0200Y         S0      
317P12V_SSD9        VIA   -    MD0100PA00X+108132Y+008259X0200Y         S0      
317P12V_SSD9        VIA   -    MD0100PA00X+108132Y+008519X0200Y         S0      
327PRSNT_SSD7_N     J37   -A12        A01X+080616Y+009996X0150Y0500R090 S1      
317PRSNT_SSD7_N     VIA   -    M      A01X+079922Y+010341X0200Y         S2      
017PRSNT_SSD7_N     VIA   -    M      A18X+079922Y+010341X0260Y         S2      
017PRSNT_SSD7_N           -    MD0100PA00X+079922Y+010341                       
327PRSNT_SSD7_N     R4067 -2          A01X+079614Y+010341X0198Y0197R270 S1      
327m3628            J21   -B47        A01X+028842Y+056911X0140Y0480R090 S1      
327m3628            C14   -2          A01X+032439Y+056849X0120Y0150R180 S1      
327m3629            J45   -B24        A01X+173844Y+012831X0150Y0500R090 S1      
327m3629            C724  -2          A01X+174734Y+012890X0120Y0150R180 S1      
317m3630            VIA   -    MD0100PA01X+162364Y+138430X0180Y         S0      
317m3630            J9    -I2   D0122PA01X+166020Y+158067X0282Y    R180 S3      
327m3630            C822  -2          A01X+162354Y+137939X0120Y0150R090 S1      
327m3631            VIA   -    M      A01X+116736Y+039150X0300Y    R180 S1      
327m3631            R256  -1          A01X+114486Y+038872X0198Y0197     S1      
327m3631            J25   -OA5        A01X+118448Y+039150X0140Y0480R090 S1      
327P12V_SSD8        VIA   -           A18X+098624Y+007892X0260Y         S2      
327P12V_SSD8        VIA   -           A18X+099374Y+007892X0260Y         S2      
327P12V_SSD8        J38   -B1         A01X+097427Y+007398X0150Y0500R090 S1      
327P12V_SSD8        J38   -B2         A01X+097427Y+007634X0150Y0500R090 S1      
327P12V_SSD8        J38   -B3         A01X+097427Y+007870X0150Y0500R090 S1      
327P12V_SSD8        J38   -B4         A01X+097427Y+008106X0150Y0500R090 S1      
327P12V_SSD8        J38   -B5         A01X+097427Y+008342X0150Y0500R090 S1      
327P12V_SSD8        J38   -B6         A01X+097427Y+008579X0150Y0500R090 S1      
327P12V_SSD8        R602  -1          A01X+098788Y+017300X0198Y0197R090 S1      
327P12V_SSD8        R593  -1          A01X+097712Y+017069X1150Y1380R090 S1      
327P12V_SSD8        C3928 -1          A01X+099556Y+008845X0198Y0197R090 S1      
327P12V_SSD8        C3931 -1          A01X+098355Y+008845X0198Y0197R090 S1      
327P12V_SSD8        C3933 -1          A01X+098755Y+008845X0198Y0197R090 S1      
327P12V_SSD8        C3934 -1          A01X+099155Y+008845X0198Y0197R090 S1      
327P12V_SSD8        C3929 -1          A01X+099507Y+008414X0198Y0197     S1      
327P12V_SSD8        C3930 -1          A01X+099507Y+007614X0198Y0197     S1      
327P12V_SSD8        C3932 -1          A01X+099507Y+008014X0198Y0197     S1      
317P12V_SSD8        VIA   -    MD0100PA00X+098775Y+017049X0200Y         S0      
317P12V_SSD8        VIA   -    MD0100PA00X+098775Y+016799X0200Y         S0      
327P12V_SSD8        VIA   -           A18X+097345Y+016945X0260Y         S2      
327P12V_SSD8        VIA   -           A18X+098095Y+016945X0260Y         S2      
317P12V_SSD8        VIA   -    MD0100PA00X+098775Y+016539X0200Y         S0      
317P12V_SSD8        VIA   -    MD0100PA00X+098775Y+016279X0200Y         S0      
317P12V_SSD8        VIA   -    MD0100PA00X+098065Y+016237X0200Y    R090 S0      
317P12V_SSD8        VIA   -    MD0100PA00X+097805Y+016237X0200Y    R090 S0      
317P12V_SSD8        VIA   -    MD0100PA00X+097896Y+007999X0200Y         S0      
317P12V_SSD8        VIA   -    MD0100PA00X+097896Y+007479X0200Y         S0      
317P12V_SSD8        VIA   -    MD0100PA00X+097896Y+007739X0200Y         S0      
317P12V_SSD8        VIA   -    MD0100PA00X+097896Y+008259X0200Y         S0      
317P12V_SSD8        VIA   -    MD0100PA00X+097896Y+008519X0200Y         S0      
317m3632            VIA   -    MD0100PA01X+025670Y+059694X0200Y         S0      
327m3632            J21   -A59        A01X+027030Y+059746X0140Y0480R090 S1      
317m3632            VIA   -    MD0080PA01X+030216Y+107520X0160Y         S0      
327m3632            PEX0  -BJ43       A01X+030216Y+107520X0180Y         S1      
317m3633            VIA   -    MD0080PA01X+155000Y+108268X0160Y    R270 S0      
327m3633            PEX3  -BG10       A01X+155000Y+108268X0180Y         S1      
327m3633            J42   -A23        A01X+141325Y+012594X0150Y0500R090 S1      
317m3633            VIA   -    MD0100PA01X+140695Y+012543X0200Y         S0      
317m3634            J9    -D1   D0122PA01X+165154Y+160705X0282Y    R180 S3      
317m3634            VIA   -    MD0080PA01X+152756Y+118740X0160Y         S0      
327m3634            PEX3  -W4         A01X+152756Y+118740X0180Y         S1      
327NIC5_LD_N        R266  -1          A18X+121788Y+037791X0198Y0197R180 S2      
317NIC5_LD_N        VIA   -    M      A01X+121317Y+037791X0200Y         S2      
017NIC5_LD_N        VIA   -    M      A18X+121317Y+037791X0260Y         S2      
017NIC5_LD_N              -    MD0100PA00X+121317Y+037791                       
327NIC5_LD_N        J25   -OB3        A01X+120259Y+038677X0140Y0480R090 S1      
327P12V_SSD7        VIA   -           A18X+084206Y+008026X0260Y         S2      
327P12V_SSD7        VIA   -           A18X+083456Y+008026X0260Y         S2      
327P12V_SSD7        J37   -B1         A01X+082427Y+007398X0150Y0500R090 S1      
327P12V_SSD7        J37   -B2         A01X+082427Y+007634X0150Y0500R090 S1      
327P12V_SSD7        J37   -B3         A01X+082427Y+007870X0150Y0500R090 S1      
327P12V_SSD7        J37   -B4         A01X+082427Y+008106X0150Y0500R090 S1      
327P12V_SSD7        J37   -B5         A01X+082427Y+008342X0150Y0500R090 S1      
327P12V_SSD7        J37   -B6         A01X+082427Y+008579X0150Y0500R090 S1      
327P12V_SSD7        R591  -1          A01X+083788Y+017300X0198Y0197R090 S1      
327P12V_SSD7        R583  -1          A01X+082712Y+017069X1150Y1380R090 S1      
327P12V_SSD7        C3924 -1          A01X+083355Y+008845X0198Y0197R090 S1      
327P12V_SSD7        C3926 -1          A01X+083755Y+008845X0198Y0197R090 S1      
327P12V_SSD7        C3921 -1          A01X+084556Y+008845X0198Y0197R090 S1      
327P12V_SSD7        C3923 -1          A01X+084155Y+008845X0198Y0197R090 S1      
327P12V_SSD7        C3927 -1          A01X+084507Y+007614X0198Y0197     S1      
327P12V_SSD7        C3922 -1          A01X+084507Y+008014X0198Y0197     S1      
327P12V_SSD7        C3925 -1          A01X+084507Y+008414X0198Y0197     S1      
317P12V_SSD7        VIA   -    MD0100PA00X+083775Y+016799X0200Y         S0      
317P12V_SSD7        VIA   -    MD0100PA00X+083775Y+017049X0200Y         S0      
327P12V_SSD7        VIA   -           A18X+083095Y+016945X0260Y         S2      
327P12V_SSD7        VIA   -           A18X+082345Y+016945X0260Y         S2      
317P12V_SSD7        VIA   -    MD0100PA00X+083775Y+016279X0200Y         S0      
317P12V_SSD7        VIA   -    MD0100PA00X+083775Y+016539X0200Y         S0      
317P12V_SSD7        VIA   -    MD0100PA00X+082805Y+016237X0200Y    R090 S0      
317P12V_SSD7        VIA   -    MD0100PA00X+083065Y+016237X0200Y    R090 S0      
317P12V_SSD7        VIA   -    MD0100PA00X+082896Y+008259X0200Y         S0      
317P12V_SSD7        VIA   -    MD0100PA00X+082896Y+008519X0200Y         S0      
317P12V_SSD7        VIA   -    MD0100PA00X+082896Y+007479X0200Y         S0      
317P12V_SSD7        VIA   -    MD0100PA00X+082896Y+007739X0200Y         S0      
317P12V_SSD7        VIA   -    MD0100PA00X+082896Y+007999X0200Y         S0      
327PRSNT_SSD14_N    J44   -A12        A01X+161797Y+009996X0150Y0500R090 S1      
317PRSNT_SSD14_N    VIA   -    M      A01X+161103Y+010341X0200Y         S2      
017PRSNT_SSD14_N    VIA   -    M      A18X+161103Y+010341X0260Y         S2      
017PRSNT_SSD14_N          -    MD0100PA00X+161103Y+010341                       
327PRSNT_SSD14_N    R4081 -2          A01X+160796Y+010341X0198Y0197R270 S1      
327m3635            J21   -B63        A01X+028842Y+060691X0140Y0480R090 S1      
327m3635            C3    -2          A01X+031399Y+060750X0120Y0150R180 S1      
317m3636            VIA   -    MD0080PA01X+118642Y+107894X0160Y         S0      
327m3636            PEX2  -BH35       A01X+118642Y+107894X0180Y         S1      
327m3636            J24   -A34        A01X+111355Y+048408X0140Y0480R270 S1      
317m3636            VIA   -    MD0100PA01X+112715Y+048355X0200Y    R180 S0      
317m3637            VIA   -    MD0080PA01X+156496Y+108642X0160Y    R270 S0      
327m3637            J43   -A24        A01X+151561Y+012831X0150Y0500R090 S1      
317m3637            VIA   -    MD0100PA01X+150931Y+012883X0200Y         S0      
327m3637            PEX3  -BF14       A01X+156496Y+108642X0180Y         S1      
317m3638            J9    -N4   D0122PA01X+167752Y+151413X0282Y    R180 S3      
317m3638            VIA   -    MD0080PA01X+152382Y+125472X0160Y         S0      
327m3638            PEX3  -A3         A01X+152382Y+125472X0180Y         S1      
327NIC5_BIF0_N      J25   -B7         A01X+120259Y+044423X0140Y0480R090 S1      
317NIC5_BIF0_N      VIA   -    M      A01X+119296Y+043516X0200Y         S2      
017NIC5_BIF0_N      VIA   -    M      A18X+119296Y+043516X0260Y         S2      
017NIC5_BIF0_N            -    MD0100PA00X+119296Y+043516                       
327NIC5_BIF0_N      R284  -1          A18X+115826Y+042703X0198Y0197     S2      
327NIC5_BIF0_N      R285  -1   M      A18X+116214Y+042702X0198Y0197R180 S2      
327P12V_SSD6        VIA   -           A18X+073734Y+008127X0260Y         S2      
327P12V_SSD6        VIA   -           A18X+072984Y+008127X0260Y         S2      
327P12V_SSD6        J36   -B1         A01X+072191Y+007398X0150Y0500R090 S1      
327P12V_SSD6        J36   -B2         A01X+072191Y+007634X0150Y0500R090 S1      
327P12V_SSD6        J36   -B3         A01X+072191Y+007870X0150Y0500R090 S1      
327P12V_SSD6        J36   -B4         A01X+072191Y+008106X0150Y0500R090 S1      
327P12V_SSD6        J36   -B5         A01X+072191Y+008342X0150Y0500R090 S1      
327P12V_SSD6        J36   -B6         A01X+072191Y+008579X0150Y0500R090 S1      
327P12V_SSD6        R580  -1          A01X+073552Y+017300X0198Y0197R090 S1      
327P12V_SSD6        R573  -1          A01X+072476Y+017069X1150Y1380R090 S1      
327P12V_SSD6        C3914 -1          A01X+074320Y+008845X0198Y0197R090 S1      
327P12V_SSD6        C3920 -1          A01X+073919Y+008845X0198Y0197R090 S1      
327P12V_SSD6        C3915 -1          A01X+073519Y+008845X0198Y0197R090 S1      
327P12V_SSD6        C3917 -1          A01X+073119Y+008845X0198Y0197R090 S1      
327P12V_SSD6        C3918 -1          A01X+074271Y+008414X0198Y0197     S1      
327P12V_SSD6        C3916 -1          A01X+074271Y+007614X0198Y0197     S1      
327P12V_SSD6        C3919 -1          A01X+074271Y+008014X0198Y0197     S1      
317P12V_SSD6        VIA   -    MD0100PA00X+073539Y+016799X0200Y         S0      
317P12V_SSD6        VIA   -    MD0100PA00X+073539Y+017049X0200Y         S0      
327P12V_SSD6        VIA   -           A18X+072859Y+016945X0260Y         S2      
327P12V_SSD6        VIA   -           A18X+072109Y+016945X0260Y         S2      
317P12V_SSD6        VIA   -    MD0100PA00X+073539Y+016279X0200Y         S0      
317P12V_SSD6        VIA   -    MD0100PA00X+073539Y+016539X0200Y         S0      
317P12V_SSD6        VIA   -    MD0100PA00X+072569Y+016237X0200Y    R090 S0      
317P12V_SSD6        VIA   -    MD0100PA00X+072829Y+016237X0200Y    R090 S0      
317P12V_SSD6        VIA   -    MD0100PA00X+072660Y+008259X0200Y         S0      
317P12V_SSD6        VIA   -    MD0100PA00X+072660Y+008519X0200Y         S0      
317P12V_SSD6        VIA   -    MD0100PA00X+072660Y+007999X0200Y         S0      
317P12V_SSD6        VIA   -    MD0100PA00X+072660Y+007739X0200Y         S0      
317P12V_SSD6        VIA   -    MD0100PA00X+072660Y+007479X0200Y         S0      
317m3639            VIA   -    MD0080PA01X+032087Y+111634X0160Y    R270 S0      
327m3639            J21   -A34        A01X+027030Y+052144X0140Y0480R090 S1      
317m3639            VIA   -    MD0100PA01X+025670Y+052196X0200Y         S0      
327m3639            PEX0  -AV48       A01X+032087Y+111634X0180Y         S1      
327m3640            J24   -B34        A01X+109544Y+048408X0140Y0480R270 S1      
327m3640            C465  -2          A01X+105947Y+048346X0120Y0150     S1      
317m3641            VIA   -    MD0080PA01X+158740Y+108268X0160Y    R270 S0      
327m3641            PEX3  -BG20       A01X+158740Y+108268X0180Y         S1      
327m3641            J44   -A17        A01X+161797Y+011177X0150Y0500R090 S1      
317m3641            VIA   -    MD0100PA01X+161167Y+011126X0200Y         S0      
317m3642            VIA   -    MD0100PA01X+170932Y+140850X0180Y         S0      
317m3642            J9    -V5   D0122PA01X+168618Y+147398X0282Y    R180 S3      
327m3642            C800  -2          A01X+170922Y+140359X0120Y0150R090 S1      
327NIC2_DATA_OUT    VIA   -    M      A01X+061533Y+061607X0300Y         S1      
327NIC2_DATA_OUT    R115  -1          A01X+061066Y+061560X0198Y0197R180 S1      
327NIC2_DATA_OUT    J22   -OB5        A01X+063836Y+061402X0140Y0480R270 S1      
327NIC5_BIF1_N      J25   -B8         A01X+120259Y+044660X0140Y0480R090 S1      
317NIC5_BIF1_N      VIA   -    M      A01X+119270Y+044049X0200Y         S2      
017NIC5_BIF1_N      VIA   -    M      A18X+119270Y+044049X0260Y         S2      
017NIC5_BIF1_N            -    MD0100PA00X+119270Y+044049                       
327NIC5_BIF1_N      R286  -1          A18X+115826Y+043103X0198Y0197     S2      
327NIC5_BIF1_N      R287  -1   M      A18X+116211Y+043103X0198Y0197R180 S2      
327P12V_SSD5        VIA   -           A18X+063565Y+008161X0260Y         S2      
327P12V_SSD5        VIA   -           A18X+062815Y+008161X0260Y         S2      
327P12V_SSD5        J35   -B1         A01X+061955Y+007398X0150Y0500R090 S1      
327P12V_SSD5        J35   -B2         A01X+061955Y+007634X0150Y0500R090 S1      
327P12V_SSD5        J35   -B3         A01X+061955Y+007870X0150Y0500R090 S1      
327P12V_SSD5        J35   -B4         A01X+061955Y+008106X0150Y0500R090 S1      
327P12V_SSD5        J35   -B5         A01X+061955Y+008342X0150Y0500R090 S1      
327P12V_SSD5        J35   -B6         A01X+061955Y+008579X0150Y0500R090 S1      
327P12V_SSD5        R569  -1          A01X+063316Y+017300X0198Y0197R090 S1      
327P12V_SSD5        R562  -1          A01X+062239Y+017069X1150Y1380R090 S1      
327P12V_SSD5        C3907 -1          A01X+064084Y+008845X0198Y0197R090 S1      
327P12V_SSD5        C3910 -1          A01X+063283Y+008845X0198Y0197R090 S1      
327P12V_SSD5        C3913 -1          A01X+063683Y+008845X0198Y0197R090 S1      
327P12V_SSD5        C3911 -1          A01X+062883Y+008845X0198Y0197R090 S1      
327P12V_SSD5        C3912 -1          A01X+064034Y+007614X0198Y0197     S1      
327P12V_SSD5        C3909 -1          A01X+064034Y+008414X0198Y0197     S1      
327P12V_SSD5        C3908 -1          A01X+064034Y+008014X0198Y0197     S1      
327P12V_SSD5        VIA   -           A18X+062623Y+016945X0260Y         S2      
317P12V_SSD5        VIA   -    MD0100PA00X+063303Y+016799X0200Y         S0      
317P12V_SSD5        VIA   -    MD0100PA00X+063303Y+017049X0200Y         S0      
327P12V_SSD5        VIA   -           A18X+061873Y+016945X0260Y         S2      
317P12V_SSD5        VIA   -    MD0100PA00X+063303Y+016279X0200Y         S0      
317P12V_SSD5        VIA   -    MD0100PA00X+063303Y+016539X0200Y         S0      
317P12V_SSD5        VIA   -    MD0100PA00X+062333Y+016237X0200Y    R090 S0      
317P12V_SSD5        VIA   -    MD0100PA00X+062593Y+016237X0200Y    R090 S0      
317P12V_SSD5        VIA   -    MD0100PA00X+062073Y+016237X0200Y    R090 S0      
317P12V_SSD5        VIA   -    MD0100PA00X+062423Y+007999X0200Y         S0      
317P12V_SSD5        VIA   -    MD0100PA00X+062423Y+007739X0200Y         S0      
317P12V_SSD5        VIA   -    MD0100PA00X+062423Y+008519X0200Y         S0      
317P12V_SSD5        VIA   -    MD0100PA00X+062423Y+008259X0200Y         S0      
317P12V_SSD5        VIA   -    MD0100PA00X+062423Y+007479X0200Y         S0      
327m3643            J21   -B18        A01X+028842Y+047022X0140Y0480R090 S1      
327m3643            C31   -2          A01X+031399Y+047081X0120Y0150R180 S1      
327m3644            J24   -B27        A01X+109544Y+051404X0140Y0480R270 S1      
327m3644            C461  -2          A01X+105947Y+051342X0120Y0150     S1      
317m3645            J7    -C8   D0122PA01X+119248Y+161138X0282Y    R180 S3      
317m3645            VIA   -    MD0080PA01X+106299Y+121358X0160Y         S0      
327m3645            PEX2  -M2         A01X+106299Y+121358X0180Y         S1      
327m3646            J44   -B27        A01X+163608Y+013539X0150Y0500R090 S1      
327m3646            C714  -2          A01X+165538Y+013601X0120Y0150R180 S1      
317m3647            J9    -C8   D0122PA01X+171216Y+161138X0282Y    R180 S3      
317m3647            VIA   -    MD0080PA01X+152008Y+121358X0160Y         S0      
327m3647            PEX3  -M2         A01X+152008Y+121358X0180Y         S1      
327NCSI_NIC2_RXD0   VIA   -    M      A01X+061528Y+059632X0300Y         S1      
327NCSI_NIC2_RXD0   J22   -OB9        A01X+063836Y+060457X0140Y0480R270 S1      
327NCSI_NIC2_RXD0   R118  -1          A01X+061063Y+059559X0198Y0197R180 S1      
327P12V_SSD4        VIA   -           A18X+052848Y+007959X0260Y         S2      
327P12V_SSD4        VIA   -           A18X+053598Y+007959X0260Y         S2      
327P12V_SSD4        J34   -B1         A01X+051718Y+007398X0150Y0500R090 S1      
327P12V_SSD4        J34   -B2         A01X+051718Y+007634X0150Y0500R090 S1      
327P12V_SSD4        J34   -B3         A01X+051718Y+007870X0150Y0500R090 S1      
327P12V_SSD4        J34   -B4         A01X+051718Y+008106X0150Y0500R090 S1      
327P12V_SSD4        J34   -B5         A01X+051718Y+008342X0150Y0500R090 S1      
327P12V_SSD4        J34   -B6         A01X+051718Y+008579X0150Y0500R090 S1      
327P12V_SSD4        C3900 -1          A01X+053848Y+008845X0198Y0197R090 S1      
327P12V_SSD4        C3903 -1          A01X+053047Y+008845X0198Y0197R090 S1      
327P12V_SSD4        C3902 -1          A01X+053447Y+008845X0198Y0197R090 S1      
327P12V_SSD4        C3904 -1          A01X+052647Y+008845X0198Y0197R090 S1      
327P12V_SSD4        C3906 -1          A01X+053798Y+008014X0198Y0197     S1      
327P12V_SSD4        C3905 -1          A01X+053798Y+007614X0198Y0197     S1      
327P12V_SSD4        C3901 -1          A01X+053798Y+008414X0198Y0197     S1      
327P12V_SSD4        R558  -1          A01X+053080Y+017300X0198Y0197R090 S1      
327P12V_SSD4        R551  -1          A01X+052003Y+017069X1150Y1380R090 S1      
317P12V_SSD4        VIA   -    MD0100PA00X+053066Y+016799X0200Y         S0      
317P12V_SSD4        VIA   -    MD0100PA00X+053066Y+017049X0200Y         S0      
327P12V_SSD4        VIA   -           A18X+051637Y+016945X0260Y         S2      
327P12V_SSD4        VIA   -           A18X+052387Y+016945X0260Y         S2      
317P12V_SSD4        VIA   -    MD0100PA00X+053066Y+016539X0200Y         S0      
317P12V_SSD4        VIA   -    MD0100PA00X+053066Y+016279X0200Y         S0      
317P12V_SSD4        VIA   -    MD0100PA00X+052356Y+016237X0200Y    R090 S0      
317P12V_SSD4        VIA   -    MD0100PA00X+052096Y+016237X0200Y    R090 S0      
317P12V_SSD4        VIA   -    MD0100PA00X+052187Y+007999X0200Y         S0      
317P12V_SSD4        VIA   -    MD0100PA00X+052187Y+007739X0200Y         S0      
317P12V_SSD4        VIA   -    MD0100PA00X+052187Y+007479X0200Y         S0      
317P12V_SSD4        VIA   -    MD0100PA00X+052187Y+008519X0200Y         S0      
317P12V_SSD4        VIA   -    MD0100PA00X+052187Y+008259X0200Y         S0      
327m3648            J21   -B51        A01X+028842Y+057856X0140Y0480R090 S1      
327m3648            C11   -2          A01X+031399Y+057915X0120Y0150R180 S1      
317m3649            VIA   -    MD0080PA01X+119764Y+108642X0160Y         S0      
327m3649            PEX2  -BF38       A01X+119764Y+108642X0180Y         S1      
317m3649            VIA   -    MD0100PA01X+111985Y+052060X0200Y    R180 S0      
327m3649            J24   -A24        A01X+111355Y+052112X0140Y0480R270 S1      
317m3650            VIA   -    MD0080PA01X+156496Y+108268X0160Y    R270 S0      
327m3650            J43   -A23        A01X+151561Y+012594X0150Y0500R090 S1      
317m3650            VIA   -    MD0100PA01X+150931Y+012543X0200Y         S0      
327m3650            PEX3  -BG14       A01X+156496Y+108268X0180Y         S1      
317m3651            J9    -O4   D0122PA01X+167752Y+150902X0282Y    R180 S3      
317m3651            VIA   -    MD0080PA01X+152382Y+125098X0160Y         S0      
327m3651            PEX3  -B3         A01X+152382Y+125098X0180Y         S1      
327NIC2_SLOT_ID0    VIA   -    M      A01X+061531Y+060619X0300Y         S1      
327NIC2_SLOT_ID0    J22   -OB7        A01X+063836Y+060929X0140Y0480R270 S1      
327NIC2_SLOT_ID0    R128  -1          A01X+061063Y+060759X0198Y0197R180 S1      
327NIC2_SLOT_ID0    R127  -1   M      A01X+061066Y+060360X0198Y0197R180 S1      
317m3652            VIA   -    MD0100PA00X+119269Y+044996X0200Y         S0      
327m3652            J25   -B10        A01X+120259Y+045132X0140Y0480R090 S1      
327m3652            R300  -1          A01X+123559Y+034547X0198Y0197R270 S1      
317m3652            VIA   -    M      A01X+123559Y+034802X0200Y    R180 S2      
017m3652            VIA   -    M      A18X+123559Y+034802X0260Y    R180 S2      
017m3652                  -    MD0100PA00X+123559Y+034802                       
317m3653            VIA   -    MD0080PA01X+031712Y+112008X0160Y    R270 S0      
327m3653            J21   -A30        A01X+027030Y+051199X0140Y0480R090 S1      
317m3653            VIA   -    MD0100PA01X+026400Y+051147X0200Y         S0      
327m3653            PEX0  -AU47       A01X+031712Y+112008X0180Y         S1      
317m3654            VIA   -    MD0100PA01X+051384Y+138430X0180Y         S0      
327m3654            C2271 -2          A01X+051374Y+137939X0120Y0150R090 S1      
317m3654            J12   -F2   D0122PA01X+046500Y+159602X0282Y    R180 S3      
317m3655            VIA   -    MD0080PA01X+118268Y+108268X0160Y         S0      
327m3655            PEX2  -BG34       A01X+118268Y+108268X0180Y         S1      
317m3655            VIA   -    MD0100PA01X+111985Y+047987X0200Y    R180 S0      
327m3655            J24   -A36        A01X+111355Y+047935X0140Y0480R270 S1      
317m3656            VIA   -    MD0100PA01X+109483Y+140850X0180Y         S0      
317m3656            J7    -H6   D0122PA01X+117516Y+158579X0282Y    R180 S3      
327m3656            C604  -2          A01X+109493Y+140359X0120Y0150R090 S1      
317m3657            VIA   -    MD0080PA01X+159488Y+108642X0160Y    R270 S0      
327m3657            PEX3  -BF22       A01X+159488Y+108642X0180Y         S1      
327m3657            J45   -A24        A01X+172033Y+012831X0150Y0500R090 S1      
317m3657            VIA   -    MD0100PA01X+171403Y+012883X0200Y         S0      
317m3658            VIA   -    MD0100PA01X+173720Y+136010X0180Y         S0      
317m3658            J9    -U7   D0122PA01X+170350Y+147910X0282Y    R180 S3      
327m3658            C797  -2          A01X+173730Y+135519X0120Y0150R090 S1      
327NIC2_BIF1_N      VIA   -    M      A01X+061607Y+055937X0300Y         S1      
327NIC2_BIF1_N      R133  -1          A01X+060435Y+055856X0198Y0197R180 S1      
327NIC2_BIF1_N      R134  -1   M      A01X+060820Y+055856X0198Y0197     S1      
327NIC2_BIF1_N      J22   -B8         A01X+063836Y+055892X0140Y0480R270 S1      
327m3659            VIA   -    M      A01X+116618Y+038472X0300Y    R180 S1      
327m3659            R303  -1          A01X+114801Y+038472X0198Y0197R180 S1      
327m3659            J25   -OA2        A01X+118448Y+038441X0140Y0480R090 S1      
317m3660            VIA   -    MD0100PA01X+026400Y+060403X0200Y         S0      
327m3660            J21   -A62        A01X+027030Y+060455X0140Y0480R090 S1      
317m3660            VIA   -    MD0080PA01X+029842Y+108268X0160Y         S0      
327m3660            PEX0  -BG42       A01X+029842Y+108268X0180Y         S1      
317m3661            VIA   -    MD0080PA01X+116772Y+108268X0160Y         S0      
327m3661            PEX2  -BG30       A01X+116772Y+108268X0180Y         S1      
317m3661            VIA   -    MD0100PA01X+111985Y+042983X0200Y    R180 S0      
327m3661            J24   -A50        A01X+111355Y+042931X0140Y0480R270 S1      
317m3662            J7    -D5   D0122PA01X+116650Y+160705X0282Y    R180 S3      
317m3662            VIA   -    MD0080PA01X+107047Y+120236X0160Y         S0      
327m3662            PEX2  -R4         A01X+107047Y+120236X0180Y         S1      
317m3663            VIA   -    MD0080PA01X+155000Y+108642X0160Y    R270 S0      
327m3663            PEX3  -BF10       A01X+155000Y+108642X0180Y         S1      
327m3663            J42   -A24        A01X+141325Y+012831X0150Y0500R090 S1      
317m3663            VIA   -    MD0100PA01X+140695Y+012883X0200Y         S0      
317m3664            VIA   -    MD0100PA01X+166036Y+136010X0180Y         S0      
317m3664            J9    -I6   D0122PA01X+169484Y+158067X0282Y    R180 S3      
327m3664            C814  -2          A01X+166026Y+135519X0120Y0150R090 S1      
327m3665            VIA   -    M      A01X+067077Y+055460X0300Y         S1      
327m3665            J22   -A9         A01X+065647Y+055656X0140Y0480R270 S1      
327m3665            R139  -1          A01X+068411Y+054970X0198Y0197     S1      
317NIC5_SLOT_ID0    VIA   -    M      A01X+121326Y+039791X0200Y         S2      
017NIC5_SLOT_ID0    VIA   -    M      A18X+121326Y+039791X0260Y         S2      
017NIC5_SLOT_ID0          -    MD0100PA00X+121326Y+039791                       
327NIC5_SLOT_ID0    J25   -OB7        A01X+120259Y+039622X0140Y0480R090 S1      
327NIC5_SLOT_ID0    R281  -1          A18X+121788Y+039392X0198Y0197R180 S2      
327NIC5_SLOT_ID0    R280  -1   M      A18X+121788Y+039791X0198Y0197R180 S2      
327m3666            J21   -B45        A01X+028842Y+056439X0140Y0480R090 S1      
327m3666            C15   -2          A01X+031399Y+056498X0120Y0150R180 S1      
317m3667            VIA   -    MD0080PA01X+120138Y+107520X0160Y         S0      
327m3667            PEX2  -BJ39       A01X+120138Y+107520X0180Y         S1      
327m3667            J24   -A20        A01X+111355Y+053057X0140Y0480R270 S1      
317m3667            VIA   -    MD0100PA01X+112715Y+053109X0200Y    R180 S0      
317m3668            VIA   -    MD0080PA01X+156122Y+107894X0160Y    R270 S0      
327m3668            J43   -A27        A01X+151561Y+013539X0150Y0500R090 S1      
317m3668            VIA   -    MD0100PA01X+150201Y+013592X0200Y         S0      
327m3668            PEX3  -BH13       A01X+156122Y+107894X0180Y         S1      
317m3669            J9    -N6   D0122PA01X+169484Y+151413X0282Y    R180 S3      
317m3669            VIA   -    MD0080PA01X+153130Y+125472X0160Y         S0      
327m3669            PEX3  -A5         A01X+153130Y+125472X0180Y         S1      
317m3670            VIA   -    M      A01X+117670Y+045111X0200Y         S2      
017m3670            VIA   -    M      A18X+117670Y+045111X0260Y         S2      
017m3670                  -    MD0100PA00X+117670Y+045111                       
327m3670            R292  -1          A01X+116645Y+045387X0198Y0197R180 S1      
327m3670            J25   -A9         A01X+118448Y+044896X0140Y0480R090 S1      
327P12V_SSD0        VIA   -           A18X+006961Y+013536X0260Y         S2      
327P12V_SSD0        VIA   -           A18X+007066Y+011778X0260Y         S2      
327P12V_SSD0        VIA   -           A18X+008327Y+015784X0260Y         S2      
327P12V_SSD0        J30   -B1         A01X+006010Y+007398X0150Y0500R090 S1      
327P12V_SSD0        J30   -B2         A01X+006010Y+007634X0150Y0500R090 S1      
327P12V_SSD0        J30   -B3         A01X+006010Y+007870X0150Y0500R090 S1      
327P12V_SSD0        J30   -B4         A01X+006010Y+008106X0150Y0500R090 S1      
327P12V_SSD0        J30   -B5         A01X+006010Y+008342X0150Y0500R090 S1      
327P12V_SSD0        J30   -B6         A01X+006010Y+008579X0150Y0500R090 S1      
327P12V_SSD0        C3876 -1          A01X+007338Y+008845X0198Y0197R090 S1      
327P12V_SSD0        C3878 -1          A01X+006938Y+008845X0198Y0197R090 S1      
327P12V_SSD0        C3875 -1          A01X+002597Y+005530X0198Y0197R180 S1      
327P12V_SSD0        C3874 -1          A01X+002988Y+006753X0198Y0197R180 S1      
327P12V_SSD0        C3873 -1          A01X+002988Y+006353X0198Y0197R180 S1      
327P12V_SSD0        C3872 -1          A01X+002988Y+005953X0198Y0197R180 S1      
317P12V_SSD0        VIA   -    MD0100PA00X+003235Y+006356X0200Y         S0      
317P12V_SSD0        VIA   -    MD0100PA00X+003235Y+005956X0200Y         S0      
317P12V_SSD0        VIA   -    MD0100PA00X+002844Y+005534X0200Y         S0      
317P12V_SSD0        VIA   -    MD0100PA00X+003235Y+006756X0200Y         S0      
327P12V_SSD0        C3877 -1          A01X+002597Y+005130X0198Y0197R180 S1      
327P12V_SSD0        VIA   -           A18X+005928Y+016945X0260Y         S2      
327P12V_SSD0        VIA   -           A18X+006678Y+016945X0260Y         S2      
317P12V_SSD0        VIA   -    MD0100PA00X+006478Y+007739X0200Y         S0      
317P12V_SSD0        VIA   -    MD0100PA00X+006478Y+007479X0200Y         S0      
317P12V_SSD0        VIA   -    MD0100PA00X+006478Y+008519X0200Y         S0      
317P12V_SSD0        VIA   -    MD0100PA00X+006478Y+008259X0200Y         S0      
317P12V_SSD0        VIA   -    MD0100PA00X+006478Y+007999X0200Y         S0      
327P12V_SSD0        R514  -1          A01X+007371Y+017300X0198Y0197R090 S1      
317P12V_SSD0        VIA   -    MD0100PA00X+007358Y+016799X0200Y         S0      
317P12V_SSD0        VIA   -    MD0100PA00X+007358Y+017049X0200Y         S0      
317P12V_SSD0        VIA   -    MD0100PA00X+007358Y+016279X0200Y         S0      
317P12V_SSD0        VIA   -    MD0100PA00X+007358Y+016539X0200Y         S0      
327P12V_SSD0        R506  -1          A01X+006294Y+017069X1150Y1380R090 S1      
317P12V_SSD0        VIA   -    MD0100PA00X+006388Y+016237X0200Y    R090 S0      
317P12V_SSD0        VIA   -    MD0100PA00X+006648Y+016237X0200Y    R090 S0      
327m3671            J21   -B60        A01X+028842Y+059982X0140Y0480R090 S1      
327m3671            C5    -2          A01X+032439Y+060044X0120Y0150R180 S1      
317m3672            VIA   -    MD0080PA01X+115275Y+108268X0160Y         S0      
327m3672            PEX2  -BG26       A01X+115276Y+108268X0180Y         S1      
317m3672            VIA   -    MD0100PA01X+111985Y+040148X0200Y    R180 S0      
327m3672            J24   -A62        A01X+111355Y+040096X0140Y0480R270 S1      
327m3673            J42   -B26        A01X+143136Y+013303X0150Y0500R090 S1      
327m3673            C699  -2          A01X+145066Y+013241X0120Y0150R180 S1      
317m3674            VIA   -    MD0100PA01X+165152Y+138430X0180Y         S0      
317m3674            J9    -I5   D0122PA01X+168618Y+158146X0282Y    R180 S3      
327m3674            C817  -2          A01X+165162Y+137939X0120Y0150R090 S1      
317m3675            VIA   -    M      A01X+066618Y+061632X0200Y         S2      
017m3675            VIA   -    M      A18X+066618Y+061632X0260Y         S2      
017m3675                  -    MD0100PA00X+066618Y+061632                       
327m3675            R103  -1          A18X+065061Y+061840X0198Y0197R180 S2      
327m3675            J22   -OA5        A01X+065647Y+061402X0140Y0480R270 S1      
317NCSI_NIC5_RXD1   VIA   -    M      A01X+120817Y+039858X0200Y         S2      
017NCSI_NIC5_RXD1   VIA   -    M      A18X+120817Y+039858X0260Y         S2      
017NCSI_NIC5_RXD1         -    MD0100PA00X+120817Y+039858                       
327NCSI_NIC5_RXD1   J25   -OB8        A01X+120259Y+039858X0140Y0480R090 S1      
327NCSI_NIC5_RXD1   R272  -1          A18X+121788Y+040192X0198Y0197R180 S2      
327m3676            J21   -B34        A01X+028842Y+052144X0140Y0480R090 S1      
327m3676            C21   -2          A01X+032439Y+052205X0120Y0150R180 S1      
327m3677            J24   -B65        A01X+109544Y+039388X0140Y0480R270 S1      
327m3677            C486  -2          A01X+106987Y+039450X0120Y0150     S1      
317m3678            VIA   -    MD0080PA01X+158366Y+107894X0160Y    R270 S0      
327m3678            J44   -A21        A01X+161797Y+012122X0150Y0500R090 S1      
317m3678            VIA   -    MD0100PA01X+160437Y+012174X0200Y         S0      
327m3678            PEX3  -BH19       A01X+158366Y+107894X0180Y         S1      
317m3679            J9    -O1   D0122PA01X+165154Y+150980X0282Y    R180 S3      
317m3679            VIA   -    MD0080PA01X+152382Y+121732X0160Y         S0      
327m3679            PEX3  -L3         A01X+152382Y+121732X0180Y         S1      
327m3680            VIA   -    M      A01X+061611Y+059139X0300Y         S1      
327m3680            J22   -OB14       A01X+063836Y+059276X0140Y0480R270 S1      
327m3680            R117  -1          A01X+061063Y+059159X0198Y0197R180 S1      
327m3681            J21   -B59        A01X+028842Y+059746X0140Y0480R090 S1      
327m3681            C6    -2          A01X+032439Y+059684X0120Y0150R180 S1      
327m3682            J24   -B40        A01X+109544Y+046990X0140Y0480R270 S1      
327m3682            C469  -2          A01X+105947Y+046929X0120Y0150     S1      
317m3683            J7    -D7   D0122PA01X+118382Y+160705X0282Y    R180 S3      
317m3683            VIA   -    MD0080PA01X+107047Y+120984X0160Y         S0      
327m3683            PEX2  -N4         A01X+107047Y+120984X0180Y         S1      
327m3684            J45   -B18        A01X+173844Y+011413X0150Y0500R090 S1      
327m3684            C728  -2          A01X+174734Y+011472X0120Y0150R180 S1      
317m3685            VIA   -    MD0100PA01X+161140Y+136010X0180Y         S0      
317m3685            J9    -J1   D0122PA01X+165154Y+157634X0282Y    R180 S3      
327m3685            C824  -2          A01X+161130Y+135519X0120Y0150R090 S1      
327m3686            J21   -B33        A01X+028842Y+051908X0140Y0480R090 S1      
327m3686            C22   -2          A01X+032439Y+051845X0120Y0150R180 S1      
327m3687            J24   -B26        A01X+109544Y+051640X0140Y0480R270 S1      
327m3687            C462  -2          A01X+105947Y+051702X0120Y0150     S1      
317m3688            VIA   -    MD0080PA01X+157992Y+108268X0160Y    R270 S0      
327m3688            J44   -A23        A01X+161797Y+012594X0150Y0500R090 S1      
317m3688            VIA   -    MD0100PA01X+161167Y+012543X0200Y         S0      
327m3688            PEX3  -BG18       A01X+157992Y+108268X0180Y         S1      
317m3689            J9    -O7   D0122PA01X+170350Y+150980X0282Y    R180 S3      
317m3689            VIA   -    MD0080PA01X+153504Y+124724X0160Y         S0      
327m3689            PEX3  -C6         A01X+153504Y+124724X0180Y         S1      
327NIC2_CLK         VIA   -    M      A01X+061614Y+061113X0300Y         S1      
327NIC2_CLK         R116  -1          A01X+061066Y+061160X0198Y0197R180 S1      
327NIC2_CLK         J22   -OB6        A01X+063836Y+061165X0140Y0480R270 S1      
327m3690            J21   -B66        A01X+028842Y+061400X0140Y0480R090 S1      
327m3690            C1    -2          A01X+032439Y+061461X0120Y0150R180 S1      
317m3691            VIA   -    MD0080PA01X+118642Y+107520X0160Y         S0      
327m3691            PEX2  -BJ35       A01X+118642Y+107520X0180Y         S1      
327m3691            J24   -A33        A01X+111355Y+048644X0140Y0480R270 S1      
317m3691            VIA   -    MD0100PA01X+112715Y+048695X0200Y    R180 S0      
327m3692            J45   -B20        A01X+173844Y+011886X0150Y0500R090 S1      
327m3692            C727  -2          A01X+175775Y+011824X0120Y0150R180 S1      
317m3693            J9    -D7   D0122PA01X+170350Y+160705X0282Y    R180 S3      
317m3693            VIA   -    MD0080PA01X+152756Y+120984X0160Y         S0      
327m3693            PEX3  -N4         A01X+152756Y+120984X0180Y         S1      
317m3694            VIA   -    M      A01X+066055Y+061840X0200Y         S2      
017m3694            VIA   -    M      A18X+066055Y+061840X0260Y         S2      
017m3694                  -    MD0100PA00X+066055Y+061840                       
327m3694            R103  -2          A18X+065376Y+061840X0198Y0197R180 S2      
327m3694            J22   -OA4        A01X+065647Y+061638X0140Y0480R270 S1      
317m3695            VIA   -    MD0100PA01X+026400Y+057908X0200Y         S0      
327m3695            J21   -A51        A01X+027030Y+057856X0140Y0480R090 S1      
317m3695            VIA   -    MD0080PA01X+031338Y+108642X0160Y         S0      
327m3695            PEX0  -BF46       A01X+031338Y+108642X0180Y         S1      
317m3696            VIA   -    MD0080PA01X+117146Y+107894X0160Y         S0      
327m3696            PEX2  -BH31       A01X+117146Y+107894X0180Y         S1      
327m3696            J24   -A48        A01X+111355Y+043404X0140Y0480R270 S1      
317m3696            VIA   -    MD0100PA01X+112715Y+043352X0200Y    R180 S0      
317m3697            J7    -C6   D0122PA01X+117516Y+161138X0282Y    R180 S3      
317m3697            VIA   -    MD0080PA01X+106299Y+120610X0160Y         S0      
327m3697            PEX2  -P2         A01X+106299Y+120610X0180Y         S1      
327m3698            J44   -B21        A01X+163608Y+012122X0150Y0500R090 S1      
327m3698            C718  -2          A01X+165538Y+012184X0120Y0150R180 S1      
317m3699            VIA   -    MD0100PA01X+167600Y+138430X0180Y         S0      
317m3699            J9    -H8   D0122PA01X+171216Y+158579X0282Y    R180 S3      
327m3699            C811  -2          A01X+167610Y+137939X0120Y0150R090 S1      
327PRSNTB3_NIC2_N   VIA   -    M      A01X+061602Y+038260X0300Y         S1      
327PRSNTB3_NIC2_N   J22   -B70        A01X+063836Y+038207X0140Y0480R270 S1      
327PRSNTB3_NIC2_N   R144  -2          A01X+061126Y+037860X0198Y0197     S1      
327PRSNTB3_NIC2_N   R110  -1   M      A01X+061126Y+038260X0198Y0197R180 S1      
327m3700            J21   -B36        A01X+028842Y+052616X0140Y0480R090 S1      
327m3700            C20   -2          A01X+031399Y+052551X0120Y0150R180 S1      
327m3701            J24   -B21        A01X+109544Y+052821X0140Y0480R270 S1      
327m3701            C457  -2          A01X+105947Y+052759X0120Y0150     S1      
317m3702            J7    -D3   D0122PA01X+114917Y+160705X0282Y    R180 S3      
317m3702            VIA   -    MD0080PA01X+107047Y+119488X0160Y         S0      
327m3702            PEX2  -U4         A01X+107047Y+119488X0180Y         S1      
317m3703            VIA   -    MD0080PA01X+155374Y+107894X0160Y    R270 S0      
327m3703            J42   -A21        A01X+141325Y+012122X0150Y0500R090 S1      
317m3703            VIA   -    MD0100PA01X+139965Y+012174X0200Y         S0      
327m3703            PEX3  -BH11       A01X+155374Y+107894X0180Y         S1      
317m3704            J9    -O5   D0122PA01X+168618Y+150980X0282Y    R180 S3      
317m3704            VIA   -    MD0080PA01X+152756Y+124724X0160Y         S0      
327m3704            PEX3  -C4         A01X+152756Y+124724X0180Y         S1      
327m3705            VIA   -    M      A01X+061611Y+063089X0300Y         S1      
327m3705            J22   -OB2        A01X+063836Y+062110X0140Y0480R270 S1      
327m3705            R104  -1          A01X+061066Y+062760X0198Y0197R180 S1      
317m3706            VIA   -    MD0100PA01X+025670Y+056860X0200Y         S0      
327m3706            J21   -A47        A01X+027030Y+056911X0140Y0480R090 S1      
317m3706            VIA   -    MD0080PA01X+031712Y+107520X0160Y         S0      
327m3706            PEX0  -BJ47       A01X+031712Y+107520X0180Y         S1      
327m3707            J24   -B59        A01X+109544Y+040805X0140Y0480R270 S1      
327m3707            C482  -2          A01X+106987Y+040867X0120Y0150     S1      
317m3708            VIA   -    MD0100PA01X+110367Y+138430X0180Y         S0      
317m3708            J7    -J7   D0122PA01X+118382Y+157634X0282Y    R180 S3      
327m3708            C601  -2          A01X+110357Y+137939X0120Y0150R090 S1      
317m3709            VIA   -    MD0080PA01X+159114Y+107520X0160Y    R270 S0      
327m3709            J45   -A26        A01X+172033Y+013303X0150Y0500R090 S1      
317m3709            VIA   -    MD0100PA01X+170673Y+013252X0200Y         S0      
327m3709            PEX3  -BJ21       A01X+159114Y+107520X0180Y         S1      
317m3710            VIA   -    MD0100PA01X+172156Y+138430X0180Y         S0      
317m3710            J9    -U6   D0122PA01X+169484Y+147831X0282Y    R180 S3      
327m3710            C798  -2          A01X+172146Y+137939X0120Y0150R090 S1      
327NIC2_BIF0_N      VIA   -    M      A01X+061607Y+056437X0300Y         S1      
327NIC2_BIF0_N      R131  -1          A01X+060435Y+056256X0198Y0197R180 S1      
327NIC2_BIF0_N      R132  -1   M      A01X+060823Y+056257X0198Y0197     S1      
327NIC2_BIF0_N      J22   -B7         A01X+063836Y+056128X0140Y0480R270 S1      
317m3711            VIA   -    MD0100PA01X+026400Y+060743X0200Y         S0      
327m3711            J21   -A63        A01X+027030Y+060691X0140Y0480R090 S1      
317m3711            VIA   -    MD0080PA01X+029842Y+108642X0160Y         S0      
327m3711            PEX0  -BF42       A01X+029842Y+108642X0180Y         S1      
317m3712            VIA   -    MD0080PA01X+116023Y+108268X0160Y         S0      
327m3712            PEX2  -BG28       A01X+116024Y+108268X0180Y         S1      
317m3712            VIA   -    MD0100PA01X+111985Y+041566X0200Y    R180 S0      
327m3712            J24   -A56        A01X+111355Y+041514X0140Y0480R270 S1      
317m3713            VIA   -    MD0100PA01X+109143Y+140850X0180Y         S0      
317m3713            J7    -I6   D0122PA01X+117516Y+158067X0282Y    R180 S3      
327m3713            C603  -2          A01X+109133Y+140359X0120Y0150R090 S1      
327m3714            J42   -B21        A01X+143136Y+012122X0150Y0500R090 S1      
327m3714            C702  -2          A01X+145066Y+012184X0120Y0150R180 S1      
317m3715            J9    -P5   D0122PA01X+168618Y+150468X0282Y    R180 S3      
317m3715            VIA   -    MD0080PA01X+152756Y+124350X0160Y         S0      
327m3715            PEX3  -D4         A01X+152756Y+124350X0180Y         S1      
317m3716            VIA   -    MD0100PA01X+026400Y+057568X0200Y         S0      
327m3716            J21   -A50        A01X+027030Y+057620X0140Y0480R090 S1      
317m3716            VIA   -    MD0080PA01X+031338Y+108268X0160Y         S0      
327m3716            PEX0  -BG46       A01X+031338Y+108268X0180Y         S1      
317m3717            VIA   -    MD0080PA01X+120138Y+107894X0160Y         S0      
327m3717            PEX2  -BH39       A01X+120138Y+107894X0180Y         S1      
327m3717            J24   -A21        A01X+111355Y+052821X0140Y0480R270 S1      
317m3717            VIA   -    MD0100PA01X+112715Y+052769X0200Y    R180 S0      
317m3718            VIA   -    MD0080PA01X+155748Y+108268X0160Y    R270 S0      
327m3718            PEX3  -BG12       A01X+155748Y+108268X0180Y         S1      
327m3718            J42   -A17        A01X+141325Y+011177X0150Y0500R090 S1      
317m3718            VIA   -    MD0100PA01X+140695Y+011126X0200Y         S0      
317m3719            VIA   -    MD0100PA01X+172496Y+138430X0180Y         S0      
317m3719            J9    -T6   D0122PA01X+169484Y+148343X0282Y    R180 S3      
327m3719            C799  -2          A01X+172506Y+137939X0120Y0150R090 S1      
327m3720            J21   -B24        A01X+028842Y+048439X0140Y0480R090 S1      
327m3720            C27   -2          A01X+031399Y+048498X0120Y0150R180 S1      
327m3721            J24   -B47        A01X+109544Y+043640X0140Y0480R270 S1      
327m3721            C474  -2          A01X+106987Y+043702X0120Y0150     S1      
327m3722            J42   -B27        A01X+143136Y+013539X0150Y0500R090 S1      
327m3722            C698  -2          A01X+145066Y+013601X0120Y0150R180 S1      
317m3723            J9    -C2   D0122PA01X+166020Y+161138X0282Y    R180 S3      
317m3723            VIA   -    MD0080PA01X+152008Y+119114X0160Y         S0      
327m3723            PEX3  -V2         A01X+152008Y+119114X0180Y         S1      
317m3724            VIA   -    MD0080PA01X+031338Y+111260X0160Y    R270 S0      
327m3724            J21   -A37        A01X+027030Y+052852X0140Y0480R090 S1      
317m3724            VIA   -    MD0100PA01X+026400Y+052904X0200Y         S0      
327m3724            PEX0  -AW46       A01X+031338Y+111260X0180Y         S1      
317m3725            VIA   -    MD0100PA01X+052608Y+136010X0180Y         S0      
317m3725            J12   -G3   D0122PA01X+047366Y+159169X0282Y    R180 S3      
327m3725            C2269 -2          A01X+052598Y+135519X0120Y0150R090 S1      
327m3726            J24   -B45        A01X+109544Y+044112X0140Y0480R270 S1      
327m3726            C471  -2          A01X+105947Y+044053X0120Y0150     S1      
327m3727            J45   -B26        A01X+173844Y+013303X0150Y0500R090 S1      
327m3727            C723  -2          A01X+175775Y+013241X0120Y0150R180 S1      
317m3728            J9    -O6   D0122PA01X+169484Y+150902X0282Y    R180 S3      
317m3728            VIA   -    MD0080PA01X+153130Y+125098X0160Y         S0      
327m3728            PEX3  -B5         A01X+153130Y+125098X0180Y         S1      
327PRSNTB0_NIC2_N   VIA   -    M      A01X+061611Y+046518X0300Y         S1      
327PRSNTB0_NIC2_N   R141  -2          A01X+061126Y+045960X0198Y0197     S1      
327PRSNTB0_NIC2_N   J22   -B42        A01X+063836Y+046518X0140Y0480R270 S1      
327PRSNTB0_NIC2_N   R108  -1   M      A01X+061126Y+046360X0198Y0197R180 S1      
317m3729            VIA   -    MD0080PA01X+032461Y+113130X0160Y    R270 S0      
327m3729            J21   -A20        A01X+027030Y+047494X0140Y0480R090 S1      
317m3729            VIA   -    MD0100PA01X+025670Y+047442X0200Y         S0      
327m3729            PEX0  -AP49       A01X+032461Y+113130X0180Y         S1      
317m3730            VIA   -    MD0100PA01X+051724Y+138430X0180Y         S0      
317m3730            J12   -E2   D0122PA01X+046500Y+160114X0282Y    R180 S3      
327m3730            C2272 -2          A01X+051734Y+137939X0120Y0150R090 S1      
327m3731            J24   -B24        A01X+109544Y+052112X0140Y0480R270 S1      
327m3731            C459  -2          A01X+106987Y+052053X0120Y0150     S1      
327m3732            J44   -B23        A01X+163608Y+012594X0150Y0500R090 S1      
327m3732            C717  -2          A01X+164498Y+012530X0120Y0150R180 S1      
317m3733            VIA   -    MD0100PA01X+168484Y+140850X0180Y         S0      
317m3733            J9    -U2   D0122PA01X+166020Y+147831X0282Y    R180 S3      
327m3733            C807  -2          A01X+168474Y+140359X0120Y0150R090 S1      
327m3734            VIA   -    M      A01X+067109Y+062540X0300Y         S1      
327m3734            J22   -OA1        A01X+065647Y+062346X0140Y0480R270 S1      
327m3734            R149  -1          A01X+067591Y+062540X0198Y0197     S1      
327m3735            J21   -B65        A01X+028842Y+061163X0140Y0480R090 S1      
327m3735            C2    -2          A01X+032439Y+061101X0120Y0150R180 S1      
327m3736            J24   -B54        A01X+109544Y+041986X0140Y0480R270 S1      
327m3736            C477  -2          A01X+106987Y+041925X0120Y0150     S1      
327m3737            J45   -B27        A01X+173844Y+013539X0150Y0500R090 S1      
327m3737            C722  -2          A01X+175775Y+013601X0120Y0150R180 S1      
317m3738            J9    -D3   D0122PA01X+166886Y+160705X0282Y    R180 S3      
317m3738            VIA   -    MD0080PA01X+152756Y+119488X0160Y         S0      
327m3738            PEX3  -U4         A01X+152756Y+119488X0180Y         S1      
327m3739            J21   -B40        A01X+028842Y+053561X0140Y0480R090 S1      
327m3739            C17   -2          A01X+032439Y+053622X0120Y0150R180 S1      
327m3740            J24   -B36        A01X+109544Y+047935X0140Y0480R270 S1      
327m3740            C468  -2          A01X+106987Y+048000X0120Y0150     S1      
327m3741            J45   -B23        A01X+173844Y+012594X0150Y0500R090 S1      
327m3741            C725  -2          A01X+174734Y+012530X0120Y0150R180 S1      
317m3742            VIA   -    MD0100PA01X+163928Y+140850X0180Y         S0      
317m3742            J9    -H4   D0122PA01X+167752Y+158579X0282Y    R180 S3      
327m3742            C819  -2          A01X+163938Y+140359X0120Y0150R090 S1      
317m3743            VIA   -    M      A01X+066559Y+059550X0200Y         S2      
017m3743            VIA   -    M      A18X+066559Y+059550X0260Y         S2      
017m3743                  -    MD0100PA00X+066559Y+059550                       
327m3743            J22   -OA14       A01X+065647Y+059276X0140Y0480R270 S1      
327m3743            R122  -1          A18X+065376Y+059440X0198Y0197     S2      
317RST_HP_NIC7_N    VIA   -    M      A01X+166898Y+033956X0200Y         S2      
017RST_HP_NIC7_N    VIA   -    M      A18X+166898Y+033956X0260Y         S2      
017RST_HP_NIC7_N          -    MD0100PA00X+166898Y+033956                       
327RST_HP_NIC7_N    U45   -2          A01X+167454Y+034488X0160Y0360R270 S1      
327RST_HP_NIC7_N    U46   -4          A01X+168189Y+033632X0220Y0530R090 S1      
317m3744            VIA   -    MD0080PA01X+032461Y+111634X0160Y    R270 S0      
327m3744            J21   -A33        A01X+027030Y+051908X0140Y0480R090 S1      
317m3744            VIA   -    MD0100PA01X+025670Y+051856X0200Y         S0      
327m3744            PEX0  -AV49       A01X+032461Y+111634X0180Y         S1      
317m3745            VIA   -    MD0100PA01X+052948Y+136010X0180Y         S0      
317m3745            J12   -F3   D0122PA01X+047366Y+159681X0282Y    R180 S3      
327m3745            C2270 -2          A01X+052958Y+135519X0120Y0150R090 S1      
327m3746            J24   -B50        A01X+109544Y+042931X0140Y0480R270 S1      
327m3746            C476  -2          A01X+105947Y+042996X0120Y0150     S1      
317m3747            VIA   -    MD0100PA01X+127929Y+138430X0180Y         S0      
317m3747            J13   -G7   D0122PA01X+135705Y+159169X0282Y    R180 S3      
327m3747            C537  -2          A01X+127919Y+137939X0120Y0150R090 S1      
317m3748            VIA   -    MD0080PA01X+159862Y+107520X0160Y    R270 S0      
327m3748            J45   -A20        A01X+172033Y+011886X0150Y0500R090 S1      
317m3748            VIA   -    MD0100PA01X+170673Y+011834X0200Y         S0      
327m3748            PEX3  -BJ23       A01X+159862Y+107520X0180Y         S1      
317m3749            VIA   -    MD0100PA01X+162704Y+138430X0180Y         S0      
317m3749            J9    -H2   D0122PA01X+166020Y+158579X0282Y    R180 S3      
327m3749            C823  -2          A01X+162714Y+137939X0120Y0150R090 S1      
317NCSI_NIC2_TXD0   VIA   -    M      A01X+066509Y+060457X0200Y         S2      
017NCSI_NIC2_TXD0   VIA   -    M      A18X+066509Y+060457X0260Y         S2      
017NCSI_NIC2_TXD0         -    MD0100PA00X+066509Y+060457                       
327NCSI_NIC2_TXD0   R120  -1          A18X+065376Y+059840X0198Y0197     S2      
327NCSI_NIC2_TXD0   J22   -OA9        A01X+065647Y+060457X0140Y0480R270 S1      
317m3750            VIA   -    M      A01X+168352Y+032452X0200Y         S2      
017m3750            VIA   -    M      A18X+168352Y+032452X0260Y         S2      
017m3750                  -    MD0100PA00X+168352Y+032452                       
327m3750            U46   -1          A01X+169153Y+032884X0220Y0530R090 S1      
327m3750            Q8    -6          A01X+167857Y+032185X0170Y0240R270 S1      
327m3750            R408  -1   M      A01X+168352Y+032189X0198Y0197R270 S1      
327P3V3_SSD15       PU68  -1          A01X+170056Y+021324X0110Y0240     S1      
327P3V3_SSD15       PU68  -2          A01X+170252Y+021324X0110Y0240     S1      
327P3V3_SSD15       PU68  -3          A01X+170449Y+021324X0110Y0240     S1      
327P3V3_SSD15       PU68  -4          A01X+170646Y+021324X0110Y0240     S1      
327P3V3_SSD15       PU68  -5          A01X+170843Y+021324X0110Y0240     S1      
327P3V3_SSD15       VIA   -           A18X+170391Y+019873X0260Y         S2      
317P3V3_SSD15       VIA   -    MD0100PA00X+171055Y+023871X0200Y    R090 S0      
327P3V3_SSD15       R900  -1          A01X+171055Y+023613X0198Y0197R270 S1      
327P3V3_SSD15       PC584 -1          A01X+170409Y+020064X0400Y0500     S1      
327P3V3_SSD15       PC587 -1          A01X+170302Y+020686X0198Y0197R180 S1      
327P3V3_SSD15       PD74  -C          A01X+170888Y+018984X0670Y0990R090 S1      
317P3V3_SSD15       VIA   -    MD0100PA00X+171093Y+020205X0200Y    R090 S0      
317P3V3_SSD15       VIA   -    MD0100PA00X+170827Y+020681X0200Y    R180 S0      
317P3V3_SSD15       VIA   -    MD0100PA00X+170577Y+020681X0200Y    R180 S0      
317P3V3_SSD15       VIA   -    MD0100PA00X+170399Y+021051X0200Y    R180 S0      
317P3V3_SSD15       VIA   -    MD0100PA00X+170649Y+021051X0200Y    R180 S0      
317P3V3_SSD15       VIA   -    MD0100PA00X+170793Y+020175X0200Y    R090 S0      
317P3V3_SSD15       VIA   -    MD0100PA00X+171141Y+019518X0200Y    R180 S0      
317P3V3_SSD15       VIA   -    MD0100PA00X+170793Y+019925X0200Y    R090 S0      
317P3V3_SSD15       VIA   -    MD0100PA00X+170391Y+019518X0200Y    R180 S0      
317P3V3_SSD15       VIA   -    MD0100PA00X+170641Y+019518X0200Y    R180 S0      
317P3V3_SSD15       VIA   -    M      A01X+171093Y+019925X0200Y    R090 S2      
017P3V3_SSD15       VIA   -    M      A18X+171093Y+019925X0260Y    R090 S2      
017P3V3_SSD15             -    MD0100PA00X+171093Y+019925                       
317P3V3_SSD15       VIA   -    MD0100PA00X+170891Y+019518X0200Y    R180 S0      
317P3V3_SSD15       VIA   -    MD0100PA00X+164741Y+014754X0200Y         S0      
327P3V3_SSD15       R6123 -1          A01X+165018Y+014754X0198Y0197     S1      
317P3V3_SSD15       VIA   -    MD0100PA00X+176194Y+010619X0200Y    R090 S0      
327P3V3_SSD15       R5749 -1          A01X+176451Y+010824X0198Y0197R270 S1      
317P3V3_SSD15       VIA   -    MD0100PA00X+175501Y+010378X0200Y    R270 S0      
327P3V3_SSD15       R454  -1          A01X+175501Y+010135X0198Y0197R270 S1      
327P3V3_SSD15       PC976 -1   M      A01X+169958Y+011967X0400Y0500R090 S1      
327P3V3_SSD15       R5704 -2          A01X+170076Y+013484X0198Y0197     S1      
327P3V3_SSD15       PU134 -6_7        A01X+169078Y+011762X0295Y0354R270 S1      
317P3V3_SSD15       VIA   -    MD0100PA00X+169532Y+011959X0200Y         S0      
317P3V3_SSD15       VIA   -    MD0100PA00X+169532Y+011659X0200Y         S0      
327P3V3_SSD15       J45   -B11        A01X+173844Y+009760X0150Y0500R090 S1      
317P3V3_SSD15       VIA   -    MD0100PA00X+175146Y+009855X0200Y    R090 S0      
327P3V3_SSD15       C980  -2   M      A01X+174892Y+009855X0198Y0197R270 S1      
317P3V3_SSD15       VIA   -    M      A01X+170493Y+009767X0200Y         S2      
017P3V3_SSD15       VIA   -    M      A18X+170493Y+009767X0260Y         S2      
017P3V3_SSD15             -    MD0100PA00X+170493Y+009767                       
327P3V3_SSD15       R456  -1          A01X+170737Y+009767X0198Y0197     S1      
317P3V3_SSD15       VIA   -    MD0100PA00X+177547Y+008058X0200Y         S0      
327P3V3_SSD15       R1734 -1          A01X+177306Y+008058X0198Y0197R180 S1      
317P3V3_SSD15       VIA   -    MD0100PA00X+177546Y+006858X0200Y         S0      
327P3V3_SSD15       R1733 -1          A01X+177306Y+006858X0198Y0197R180 S1      
317P3V3_SSD15       VIA   -    MD0100PA00X+177923Y+005551X0200Y         S0      
327P3V3_SSD15       U141  -1          A01X+177898Y+006472X0240Y0460R180 S1      
327P3V3_SSD15       C2742 -2   M      A01X+177923Y+005801X0198Y0197R180 S1      
317m3751            VIA   -    MD0080PA01X+031712Y+111260X0160Y    R270 S0      
327m3751            J21   -A36        A01X+027030Y+052616X0140Y0480R090 S1      
317m3751            VIA   -    MD0100PA01X+026400Y+052564X0200Y         S0      
327m3751            PEX0  -AW47       A01X+031712Y+111260X0180Y         S1      
317m3752            VIA   -    MD0080PA01X+115275Y+108642X0160Y         S0      
327m3752            PEX2  -BF26       A01X+115276Y+108642X0180Y         S1      
327m3752            J24   -A63        A01X+111355Y+039860X0140Y0480R270 S1      
317m3752            VIA   -    MD0100PA01X+111985Y+039808X0200Y    R180 S0      
327m3753            J45   -B21        A01X+173844Y+012122X0150Y0500R090 S1      
327m3753            C726  -2          A01X+175775Y+012184X0120Y0150R180 S1      
317m3754            J9    -D5   D0122PA01X+168618Y+160705X0282Y    R180 S3      
317m3754            VIA   -    MD0080PA01X+152756Y+120236X0160Y         S0      
327m3754            PEX3  -R4         A01X+152756Y+120236X0180Y         S1      
317NCSI_NIC2_TXD1   VIA   -    M      A01X+066059Y+060693X0200Y         S2      
017NCSI_NIC2_TXD1   VIA   -    M      A18X+066059Y+060693X0260Y         S2      
017NCSI_NIC2_TXD1         -    MD0100PA00X+066059Y+060693                       
327NCSI_NIC2_TXD1   R121  -1          A18X+065376Y+060240X0198Y0197     S2      
327NCSI_NIC2_TXD1   J22   -OA8        A01X+065647Y+060693X0140Y0480R270 S1      
327P3V3_SSD14       R899  -1          A01X+160818Y+023613X0198Y0197R270 S1      
317P3V3_SSD14       VIA   -    MD0100PA00X+160818Y+023871X0200Y    R090 S0      
327P3V3_SSD14       PU67  -1          A01X+159819Y+021324X0110Y0240     S1      
327P3V3_SSD14       PU67  -2          A01X+160016Y+021324X0110Y0240     S1      
327P3V3_SSD14       PU67  -3          A01X+160213Y+021324X0110Y0240     S1      
327P3V3_SSD14       PU67  -4          A01X+160410Y+021324X0110Y0240     S1      
327P3V3_SSD14       PU67  -5          A01X+160607Y+021324X0110Y0240     S1      
327P3V3_SSD14       VIA   -           A18X+160155Y+019873X0260Y         S2      
327P3V3_SSD14       PC575 -1          A01X+160173Y+020064X0400Y0500     S1      
327P3V3_SSD14       PC574 -1          A01X+160066Y+020686X0198Y0197R180 S1      
327P3V3_SSD14       PD73  -C          A01X+160651Y+018984X0670Y0990R090 S1      
317P3V3_SSD14       VIA   -    MD0100PA00X+160557Y+020175X0200Y    R090 S0      
317P3V3_SSD14       VIA   -    MD0100PA00X+160857Y+020205X0200Y    R090 S0      
317P3V3_SSD14       VIA   -    MD0100PA00X+160413Y+021051X0200Y    R180 S0      
317P3V3_SSD14       VIA   -    MD0100PA00X+160163Y+021051X0200Y    R180 S0      
317P3V3_SSD14       VIA   -    MD0100PA00X+160590Y+020681X0200Y    R180 S0      
317P3V3_SSD14       VIA   -    MD0100PA00X+160340Y+020681X0200Y    R180 S0      
317P3V3_SSD14       VIA   -    M      A01X+160857Y+019925X0200Y    R090 S2      
017P3V3_SSD14       VIA   -    M      A18X+160857Y+019925X0260Y    R090 S2      
017P3V3_SSD14             -    MD0100PA00X+160857Y+019925                       
317P3V3_SSD14       VIA   -    MD0100PA00X+160905Y+019518X0200Y    R180 S0      
317P3V3_SSD14       VIA   -    MD0100PA00X+160655Y+019518X0200Y    R180 S0      
317P3V3_SSD14       VIA   -    MD0100PA00X+160155Y+019518X0200Y    R180 S0      
317P3V3_SSD14       VIA   -    MD0100PA00X+160557Y+019925X0200Y    R090 S0      
317P3V3_SSD14       VIA   -    MD0100PA00X+160405Y+019518X0200Y    R180 S0      
327P3V3_SSD14       R6122 -1          A01X+154782Y+014754X0198Y0197     S1      
317P3V3_SSD14       VIA   -    MD0100PA00X+154504Y+014754X0200Y         S0      
327P3V3_SSD14       R5747 -1          A01X+166215Y+010824X0198Y0197R270 S1      
317P3V3_SSD14       VIA   -    MD0100PA00X+165958Y+010619X0200Y    R090 S0      
327P3V3_SSD14       R451  -1          A01X+165264Y+010135X0198Y0197R270 S1      
317P3V3_SSD14       VIA   -    MD0100PA00X+165264Y+010378X0200Y    R270 S0      
317P3V3_SSD14       VIA   -    MD0100PA00X+159296Y+011659X0200Y         S0      
317P3V3_SSD14       VIA   -    MD0100PA00X+159296Y+011959X0200Y         S0      
327P3V3_SSD14       PU133 -6_7        A01X+158842Y+011762X0295Y0354R270 S1      
327P3V3_SSD14       PC972 -1   M      A01X+159722Y+011967X0400Y0500R090 S1      
327P3V3_SSD14       R5707 -2          A01X+159840Y+013484X0198Y0197     S1      
327P3V3_SSD14       C979  -2   M      A01X+164656Y+009855X0198Y0197R270 S1      
317P3V3_SSD14       VIA   -    MD0100PA00X+164909Y+009855X0200Y    R090 S0      
327P3V3_SSD14       J44   -B11        A01X+163608Y+009760X0150Y0500R090 S1      
327P3V3_SSD14       R453  -1          A01X+160501Y+009767X0198Y0197     S1      
317P3V3_SSD14       VIA   -    M      A01X+160257Y+009767X0200Y         S2      
017P3V3_SSD14       VIA   -    M      A18X+160257Y+009767X0260Y         S2      
017P3V3_SSD14             -    MD0100PA00X+160257Y+009767                       
327P3V3_SSD14       R1731 -1          A01X+167070Y+008058X0198Y0197R180 S1      
317P3V3_SSD14       VIA   -    MD0100PA00X+167311Y+008058X0200Y         S0      
327P3V3_SSD14       R1730 -1          A01X+167070Y+006858X0198Y0197R180 S1      
317P3V3_SSD14       VIA   -    MD0100PA00X+167310Y+006858X0200Y         S0      
327P3V3_SSD14       C2740 -2   M      A01X+167687Y+005801X0198Y0197R180 S1      
327P3V3_SSD14       U140  -1          A01X+167662Y+006472X0240Y0460R180 S1      
317P3V3_SSD14       VIA   -    MD0100PA00X+167687Y+005551X0200Y         S0      
317m3755            VIA   -    MD0080PA01X+032087Y+110886X0160Y    R270 S0      
327m3755            PEX0  -AY48       A01X+032087Y+110886X0180Y         S1      
327m3755            J21   -A40        A01X+027030Y+053561X0140Y0480R090 S1      
317m3755            VIA   -    MD0100PA01X+025670Y+053613X0200Y         S0      
317m3756            VIA   -    MD0080PA01X+120512Y+108642X0160Y         S0      
327m3756            PEX2  -BF40       A01X+120512Y+108642X0180Y         S1      
317m3756            VIA   -    MD0100PA01X+111985Y+053478X0200Y    R180 S0      
327m3756            J24   -A18        A01X+111355Y+053530X0140Y0480R270 S1      
317m3757            VIA   -    MD0080PA01X+159488Y+108268X0160Y    R270 S0      
327m3757            J45   -A23        A01X+172033Y+012594X0150Y0500R090 S1      
317m3757            VIA   -    MD0100PA01X+171403Y+012543X0200Y         S0      
327m3757            PEX3  -BG22       A01X+159488Y+108268X0180Y         S1      
317m3758            VIA   -    MD0100PA01X+163588Y+136010X0180Y         S0      
317m3758            J9    -J3   D0122PA01X+166886Y+157634X0282Y    R180 S3      
327m3758            C820  -2          A01X+163578Y+135519X0120Y0150R090 S1      
317m3759            VIA   -    M      A01X+066624Y+061007X0200Y         S2      
017m3759            VIA   -    M      A18X+066624Y+061007X0260Y         S2      
017m3759                  -    MD0100PA00X+066624Y+061007                       
327m3759            R123  -1          A18X+065376Y+060640X0198Y0197     S2      
327m3759            J22   -OA7        A01X+065647Y+060929X0140Y0480R270 S1      
317m3760            VIA   -    MD0100PA01X+025670Y+058617X0200Y         S0      
327m3760            J21   -A54        A01X+027030Y+058565X0140Y0480R090 S1      
317m3760            VIA   -    MD0080PA01X+030964Y+107894X0160Y         S0      
327m3760            PEX0  -BH45       A01X+030964Y+107894X0180Y         S1      
317m3761            VIA   -    MD0080PA01X+117146Y+107520X0160Y         S0      
327m3761            PEX2  -BJ31       A01X+117146Y+107520X0180Y         S1      
317m3761            VIA   -    MD0100PA01X+112715Y+043692X0200Y    R180 S0      
327m3761            J24   -A47        A01X+111355Y+043640X0140Y0480R270 S1      
317m3762            VIA   -    MD0080PA01X+160236Y+108642X0160Y    R270 S0      
327m3762            PEX3  -BF24       A01X+160236Y+108642X0180Y         S1      
327m3762            J45   -A18        A01X+172033Y+011413X0150Y0500R090 S1      
317m3762            VIA   -    MD0100PA01X+171403Y+011466X0200Y         S0      
317m3763            VIA   -    MD0100PA01X+173380Y+140850X0180Y         S0      
317m3763            J9    -U8   D0122PA01X+171216Y+147831X0282Y    R180 S3      
327m3763            C794  -2          A01X+173370Y+140359X0120Y0150R090 S1      
327PRSNTB2_NIC2_N   VIA   -    M      A01X+067075Y+054947X0300Y         S1      
327PRSNTB2_NIC2_N   J22   -A12        A01X+065647Y+054947X0140Y0480R270 S1      
327PRSNTB2_NIC2_N   R143  -2          A01X+067551Y+054580X0198Y0197R180 S1      
327PRSNTB2_NIC2_N   R109  -1   M      A01X+067551Y+054980X0198Y0197     S1      
327m3764            J21   -B57        A01X+028842Y+059274X0140Y0480R090 S1      
327m3764            C7    -2          A01X+031399Y+059332X0120Y0150R180 S1      
317m3765            J12   -H4   D0122PA01X+048232Y+158579X0282Y    R180 S3      
317m3765            VIA   -    MD0080PA01X+063957Y+125472X0160Y         S0      
327m3765            PEX1  -A11        A01X+063957Y+125472X0180Y         S1      
317m3766            VIA   -    MD0080PA01X+119390Y+107894X0160Y         S0      
327m3766            PEX2  -BH37       A01X+119390Y+107894X0180Y         S1      
317m3766            VIA   -    MD0100PA01X+112715Y+051352X0200Y    R180 S0      
327m3766            J24   -A27        A01X+111355Y+051404X0140Y0480R270 S1      
317m3767            VIA   -    MD0080PA01X+160236Y+108268X0160Y    R270 S0      
327m3767            J45   -A17        A01X+172033Y+011177X0150Y0500R090 S1      
317m3767            VIA   -    MD0100PA01X+171403Y+011126X0200Y         S0      
327m3767            PEX3  -BG24       A01X+160236Y+108268X0180Y         S1      
317m3768            VIA   -    MD0100PA01X+170048Y+138430X0180Y         S0      
317m3768            J9    -U3   D0122PA01X+166886Y+147910X0282Y    R180 S3      
327m3768            C804  -2          A01X+170058Y+137939X0120Y0150R090 S1      
327m3769            U18   -1          A18X+066955Y+055189X0240Y0240R180 S2      
327m3769            R105  -1   M      A18X+064790Y+054497X0198Y0197R180 S2      
317m3769            VIA   -    M      A01X+064241Y+054553X0200Y         S2      
017m3769            VIA   -    M      A18X+064241Y+054553X0260Y         S2      
017m3769                  -    MD0100PA00X+064241Y+054553                       
327m3769            J22   -B12        A01X+063836Y+054947X0140Y0480R270 S1      
317m3770            VIA   -    MD0100PA01X+025670Y+061452X0200Y         S0      
327m3770            J21   -A66        A01X+027030Y+061400X0140Y0480R090 S1      
317m3770            VIA   -    MD0080PA01X+029468Y+107894X0160Y         S0      
327m3770            PEX0  -BH41       A01X+029468Y+107894X0180Y         S1      
317m3771            VIA   -    MD0100PA01X+046828Y+138430X0180Y         S0      
317m3771            J12   -N4   D0122PA01X+048232Y+151413X0282Y    R180 S3      
327m3771            C363  -2          A01X+046838Y+137939X0120Y0150R090 S1      
327m3772            J24   -B31        A01X+109544Y+049116X0140Y0480R270 S1      
327m3772            C463  -2          A01X+106987Y+049057X0120Y0150     S1      
317m3773            VIA   -    MD0100PA01X+125821Y+138430X0180Y         S0      
317m3773            J13   -E4   D0122PA01X+133106Y+160114X0282Y    R180 S3      
327m3773            C544  -2          A01X+125831Y+137939X0120Y0150R090 S1      
317m3774            VIA   -    MD0080PA01X+154626Y+107894X0160Y    R270 S0      
327m3774            J42   -A27        A01X+141325Y+013539X0150Y0500R090 S1      
317m3774            VIA   -    MD0100PA01X+139965Y+013592X0200Y         S0      
327m3774            PEX3  -BH9        A01X+154626Y+107894X0180Y         S1      
317m3775            VIA   -    MD0100PA01X+170932Y+136010X0180Y         S0      
317m3775            J9    -U4   D0122PA01X+167752Y+147831X0282Y    R180 S3      
327m3775            C802  -2          A01X+170922Y+135519X0120Y0150R090 S1      
327PRSNTB1_NIC2_N   VIA   -    M      A01X+067068Y+046280X0300Y         S1      
327PRSNTB1_NIC2_N   J22   -A42        A01X+065647Y+046518X0140Y0480R270 S1      
327PRSNTB1_NIC2_N   R142  -2          A01X+067531Y+045880X0198Y0197R180 S1      
327PRSNTB1_NIC2_N   R107  -1   M      A01X+067531Y+046280X0198Y0197     S1      
317m3776            VIA   -    MD0100PA01X+025670Y+057200X0200Y         S0      
327m3776            J21   -A48        A01X+027030Y+057148X0140Y0480R090 S1      
317m3776            VIA   -    MD0080PA01X+031712Y+107894X0160Y         S0      
327m3776            PEX0  -BH47       A01X+031712Y+107894X0180Y         S1      
317m3777            J12   -C1   D0122PA01X+045634Y+161217X0282Y    R180 S3      
327m3777            C341  -2          A01X+044390Y+135519X0120Y0150R090 S1      
317m3777            VIA   -    MD0100PA01X+044380Y+136010X0180Y         S0      
317m3778            VIA   -    MD0080PA01X+114901Y+107520X0160Y         S0      
327m3778            PEX2  -BJ25       A01X+114902Y+107520X0180Y         S1      
327m3778            J24   -A65        A01X+111355Y+039388X0140Y0480R270 S1      
317m3778            VIA   -    MD0100PA01X+112715Y+039440X0200Y    R180 S0      
317m3779            J13   -L4   D0122PA01X+133106Y+156532X0282Y    R180 S3      
317m3779            VIA   -    MD0080PA01X+115650Y+125098X0160Y    R090 S0      
327m3779            PEX2  -B27        A01X+115650Y+125098X0180Y         S1      
317m3780            VIA   -    MD0080PA01X+158366Y+107520X0160Y    R270 S0      
327m3780            J44   -A20        A01X+161797Y+011886X0150Y0500R090 S1      
317m3780            VIA   -    MD0100PA01X+160437Y+011834X0200Y         S0      
327m3780            PEX3  -BJ19       A01X+158366Y+107520X0180Y         S1      
317m3781            VIA   -    MD0100PA01X+166036Y+140850X0180Y         S0      
317m3781            J9    -J7   D0122PA01X+170350Y+157634X0282Y    R180 S3      
327m3781            C812  -2          A01X+166026Y+140359X0120Y0150R090 S1      
317NIC2_SLOT_ID1    VIA   -    M      A01X+066083Y+061259X0200Y         S2      
017NIC2_SLOT_ID1    VIA   -    M      A18X+066083Y+061259X0260Y         S2      
017NIC2_SLOT_ID1          -    MD0100PA00X+066083Y+061259                       
327NIC2_SLOT_ID1    R130  -1          A18X+065376Y+061440X0198Y0197     S2      
327NIC2_SLOT_ID1    R129  -1   M      A18X+065376Y+061040X0198Y0197     S2      
327NIC2_SLOT_ID1    J22   -OA6        A01X+065647Y+061165X0140Y0480R270 S1      
317m3782            VIA   -    MD0100PA01X+026400Y+059326X0200Y         S0      
327m3782            J21   -A57        A01X+027030Y+059274X0140Y0480R090 S1      
317m3782            VIA   -    MD0080PA01X+030590Y+108642X0160Y         S0      
327m3782            PEX0  -BF44       A01X+030590Y+108642X0180Y         S1      
317m3783            VIA   -    MD0100PA01X+045264Y+136010X0180Y         S0      
327m3783            C358  -2          A01X+045254Y+135519X0120Y0150R090 S1      
317m3783            J12   -O2   D0122PA01X+046500Y+150902X0282Y    R180 S3      
327m3784            J24   -B20        A01X+109544Y+053057X0140Y0480R270 S1      
327m3784            C458  -2          A01X+105947Y+053119X0120Y0150     S1      
317m3785            J13   -L2   D0122PA01X+131374Y+156532X0282Y    R180 S3      
317m3785            VIA   -    MD0080PA01X+114902Y+125098X0160Y    R090 S0      
327m3785            PEX2  -B25        A01X+114902Y+125098X0180Y         S1      
327m3786            J42   -B23        A01X+143136Y+012594X0150Y0500R090 S1      
327m3786            C701  -2          A01X+144026Y+012530X0120Y0150R180 S1      
317m3787            J9    -O2   D0122PA01X+166020Y+150902X0282Y    R180 S3      
317m3787            VIA   -    MD0080PA01X+151634Y+122106X0160Y         S0      
327m3787            PEX3  -K1         A01X+151634Y+122106X0180Y         S1      
327NCSI_NIC2_RXD1   VIA   -    M      A01X+061613Y+060126X0300Y         S1      
327NCSI_NIC2_RXD1   R119  -1          A01X+061063Y+059959X0198Y0197R180 S1      
327NCSI_NIC2_RXD1   J22   -OB8        A01X+063836Y+060693X0140Y0480R270 S1      
317m3788            VIA   -    MD0100PA01X+025670Y+060034X0200Y         S0      
327m3788            J21   -A60        A01X+027030Y+059982X0140Y0480R090 S1      
317m3788            VIA   -    MD0080PA01X+030216Y+107894X0160Y         S0      
327m3788            PEX0  -BH43       A01X+030216Y+107894X0180Y         S1      
317m3789            VIA   -    MD0100PA01X+048052Y+140850X0180Y         S0      
317m3789            J12   -N6   D0122PA01X+049965Y+151413X0282Y    R180 S3      
327m3789            C367  -2          A01X+048062Y+140359X0120Y0150R090 S1      
327m3790            J24   -B39        A01X+109544Y+047226X0140Y0480R270 S1      
327m3790            C470  -2          A01X+105947Y+047289X0120Y0150     S1      
317m3791            VIA   -    MD0080PA01X+157244Y+108642X0160Y    R270 S0      
327m3791            PEX3  -BF16       A01X+157244Y+108642X0180Y         S1      
327m3791            J43   -A18        A01X+151561Y+011413X0150Y0500R090 S1      
317m3791            VIA   -    MD0100PA01X+150931Y+011466X0200Y         S0      
317m3792            VIA   -    MD0100PA01X+173720Y+140850X0180Y         S0      
317m3792            J9    -T8   D0122PA01X+171216Y+148343X0282Y    R180 S3      
327m3792            C795  -2          A01X+173730Y+140359X0120Y0150R090 S1      
327NIC2_LD_N        VIA   -    M      A01X+061530Y+062595X0300Y         S1      
327NIC2_LD_N        J22   -OB3        A01X+063836Y+061874X0140Y0480R270 S1      
327NIC2_LD_N        R113  -1          A01X+061066Y+062360X0198Y0197R180 S1      
317m3793            VIA   -    MD0080PA01X+032461Y+110886X0160Y    R270 S0      
327m3793            J21   -A39        A01X+027030Y+053325X0140Y0480R090 S1      
317m3793            VIA   -    MD0100PA01X+025670Y+053273X0200Y         S0      
327m3793            PEX0  -AY49       A01X+032461Y+110886X0180Y         S1      
317m3794            J12   -V1   D0122PA01X+045634Y+147398X0282Y    R180 S3      
317m3794            VIA   -    MD0080PA01X+065827Y+124350X0160Y         S0      
327m3794            PEX1  -D16        A01X+065827Y+124350X0180Y         S1      
317m3795            VIA   -    MD0080PA01X+115649Y+107894X0160Y         S0      
327m3795            PEX2  -BH27       A01X+115650Y+107894X0180Y         S1      
317m3795            VIA   -    MD0100PA01X+112715Y+040517X0200Y    R180 S0      
327m3795            J24   -A60        A01X+111355Y+040569X0140Y0480R270 S1      
327m3796            J44   -B17        A01X+163608Y+011177X0150Y0500R090 S1      
327m3796            C721  -2          A01X+164498Y+011112X0120Y0150R180 S1      
317m3797            J9    -C7   D0122PA01X+170350Y+161217X0282Y    R180 S3      
317m3797            VIA   -    MD0080PA01X+152382Y+120984X0160Y         S0      
327m3797            PEX3  -N3         A01X+152382Y+120984X0180Y         S1      
327NIC2_DATA_IN     VIA   -    M      A01X+061613Y+062100X0300Y         S1      
327NIC2_DATA_IN     J22   -OB4        A01X+063836Y+061638X0140Y0480R270 S1      
327NIC2_DATA_IN     R114  -1          A01X+061066Y+061960X0198Y0197R180 S1      
327m3798            J21   -B39        A01X+028842Y+053325X0140Y0480R090 S1      
327m3798            C18   -2          A01X+032439Y+053262X0120Y0150R180 S1      
317m3799            VIA   -    MD0100PA01X+046488Y+136010X0180Y         S0      
317m3799            J12   -D3   D0122PA01X+047366Y+160705X0282Y    R180 S3      
327m3799            C344  -2          A01X+046478Y+135519X0120Y0150R090 S1      
327m3800            J24   -B51        A01X+109544Y+042695X0140Y0480R270 S1      
327m3800            C475  -2          A01X+105947Y+042636X0120Y0150     S1      
317m3801            VIA   -    MD0080PA01X+154626Y+107520X0160Y    R270 S0      
327m3801            J42   -A26        A01X+141325Y+013303X0150Y0500R090 S1      
317m3801            VIA   -    MD0100PA01X+139965Y+013252X0200Y         S0      
327m3801            PEX3  -BJ9        A01X+154626Y+107520X0180Y         S1      
317m3802            J9    -P1   D0122PA01X+165154Y+150468X0282Y    R180 S3      
317m3802            VIA   -    MD0080PA01X+152756Y+121732X0160Y         S0      
327m3802            PEX3  -L4         A01X+152756Y+121732X0180Y         S1      
317m3803            VIA   -    MD0080PA01X+031338Y+113504X0160Y    R270 S0      
327m3803            PEX0  -AN46       A01X+031338Y+113504X0180Y         S1      
317m3803            VIA   -    MD0100PA01X+026400Y+047074X0200Y         S0      
327m3803            J21   -A18        A01X+027030Y+047022X0140Y0480R090 S1      
317m3804            VIA   -    MD0100PA01X+046828Y+140850X0180Y         S0      
317m3804            J12   -B4   D0122PA01X+048232Y+161650X0282Y    R180 S3      
327m3804            C347  -2          A01X+046838Y+140359X0120Y0150R090 S1      
317m3805            VIA   -    MD0080PA01X+117894Y+107894X0160Y         S0      
327m3805            PEX2  -BH33       A01X+117894Y+107894X0180Y         S1      
317m3805            VIA   -    MD0100PA01X+112715Y+046938X0200Y    R180 S0      
327m3805            J24   -A40        A01X+111355Y+046990X0140Y0480R270 S1      
317m3806            J13   -L3   D0122PA01X+132240Y+156610X0282Y    R180 S3      
317m3806            VIA   -    MD0080PA01X+115276Y+124724X0160Y         S0      
327m3806            PEX2  -C26        A01X+115276Y+124724X0180Y         S1      
317m3807            VIA   -    MD0080PA01X+156870Y+107894X0160Y    R270 S0      
327m3807            PEX3  -BH15       A01X+156870Y+107894X0180Y         S1      
327m3807            J43   -A21        A01X+151561Y+012122X0150Y0500R090 S1      
317m3807            VIA   -    MD0100PA01X+150201Y+012174X0200Y         S0      
317m3808            VIA   -    MD0100PA01X+164812Y+138430X0180Y         S0      
317m3808            J9    -J5   D0122PA01X+168618Y+157634X0282Y    R180 S3      
327m3808            C816  -2          A01X+164802Y+137939X0120Y0150R090 S1      
317NIC7_DATA_IN     VIA   -    M      A01X+167026Y+038650X0200Y         S2      
017NIC7_DATA_IN     VIA   -    M      A18X+167026Y+038650X0260Y         S2      
017NIC7_DATA_IN           -    MD0100PA00X+167026Y+038650                       
327NIC7_DATA_IN     J27   -OB4        A01X+165968Y+038913X0140Y0480R090 S1      
327NIC7_DATA_IN     R369  -1          A18X+167497Y+038191X0198Y0197R180 S2      
327m3809            J21   -B27        A01X+028842Y+049148X0140Y0480R090 S1      
327m3809            C25   -2          A01X+032439Y+049209X0120Y0150R180 S1      
317m3810            VIA   -    MD0100PA01X+049276Y+138430X0180Y         S0      
317m3810            J12   -O7   D0122PA01X+050831Y+150980X0282Y    R180 S3      
327m3810            C369  -2          A01X+049286Y+137939X0120Y0150R090 S1      
327m3811            J24   -B33        A01X+109544Y+048644X0140Y0480R270 S1      
327m3811            C466  -2          A01X+105947Y+048706X0120Y0150     S1      
327m3812            J42   -B24        A01X+143136Y+012831X0150Y0500R090 S1      
327m3812            C700  -2          A01X+144026Y+012890X0120Y0150R180 S1      
317m3813            VIA   -    MD0100PA01X+173380Y+136010X0180Y         S0      
317m3813            J9    -V7   D0122PA01X+170350Y+147398X0282Y    R180 S3      
327m3813            C796  -2          A01X+173370Y+135519X0120Y0150R090 S1      
317m3814            VIA   -    M      A01X+065806Y+065012X0200Y         S2      
017m3814            VIA   -    M      A18X+065806Y+065012X0260Y         S2      
017m3814                  -    MD0100PA00X+065806Y+065012                       
327m3814            R147  -1          A01X+065806Y+065316X0198Y0197R090 S1      
317m3814            VIA   -    MD0100PA00X+065115Y+057772X0200Y         S0      
327m3814            J22   -B10        A01X+063836Y+055419X0140Y0480R270 S1      
327m3815            U43   -1          A18X+164685Y+045163X0240Y0240R270 S2      
327m3815            R360  -1          A18X+165349Y+046324X0198Y0197     S2      
317m3815            VIA   -    M      A01X+165349Y+045857X0200Y         S2      
017m3815            VIA   -    M      A18X+165349Y+045857X0260Y         S2      
017m3815                  -    MD0100PA00X+165349Y+045857                       
327m3815            J27   -B12        A01X+165968Y+045604X0140Y0480R090 S1      
317m3816            VIA   -    MD0080PA01X+031712Y+113504X0160Y    R270 S0      
327m3816            J21   -A17        A01X+027030Y+046785X0140Y0480R090 S1      
317m3816            VIA   -    MD0100PA01X+026400Y+046734X0200Y         S0      
327m3816            PEX0  -AN47       A01X+031712Y+113504X0180Y         S1      
317m3817            VIA   -    MD0080PA01X+116398Y+107894X0160Y         S0      
327m3817            PEX2  -BH29       A01X+116398Y+107894X0180Y         S1      
317m3817            VIA   -    MD0100PA01X+112715Y+041934X0200Y    R180 S0      
327m3817            J24   -A54        A01X+111355Y+041986X0140Y0480R270 S1      
327m3818            J43   -B21        A01X+153372Y+012122X0150Y0500R090 S1      
327m3818            C710  -2          A01X+155302Y+012184X0120Y0150R180 S1      
317m3819            VIA   -    MD0100PA01X+166376Y+136010X0180Y         S0      
317m3819            J9    -H6   D0122PA01X+169484Y+158579X0282Y    R180 S3      
327m3819            C815  -2          A01X+166386Y+135519X0120Y0150R090 S1      
327NIC2_BIF2_N      VIA   -    M      A01X+061613Y+055267X0300Y         S1      
327NIC2_BIF2_N      R135  -1          A01X+060435Y+055456X0198Y0197R180 S1      
327NIC2_BIF2_N      R136  -1   M      A01X+060820Y+055456X0198Y0197     S1      
327NIC2_BIF2_N      J22   -B9         A01X+063836Y+055656X0140Y0480R270 S1      
317m3820            VIA   -    M      A01X+166696Y+038205X0200Y         S2      
017m3820            VIA   -    M      A18X+166696Y+038205X0260Y         S2      
017m3820                  -    MD0100PA00X+166696Y+038205                       
327m3820            R361  -1          A18X+164884Y+038450X0198Y0197     S2      
327m3820            R379  -1   M      A18X+165218Y+038450X0198Y0197R180 S2      
327m3820            J27   -OB1        A01X+165968Y+038205X0140Y0480R090 S1      
317m3821            VIA   -    MD0100PA01X+025670Y+061112X0200Y         S0      
327m3821            J21   -A65        A01X+027030Y+061163X0140Y0480R090 S1      
317m3821            VIA   -    MD0080PA01X+029468Y+107520X0160Y         S0      
327m3821            PEX0  -BJ41       A01X+029468Y+107520X0180Y         S1      
317m3822            J12   -V7   D0122PA01X+050831Y+147398X0282Y    R180 S3      
317m3822            VIA   -    MD0080PA01X+068071Y+124350X0160Y         S0      
327m3822            PEX1  -D22        A01X+068071Y+124350X0180Y         S1      
327m3823            J24   -B48        A01X+109544Y+043404X0140Y0480R270 S1      
327m3823            C473  -2          A01X+106987Y+043342X0120Y0150     S1      
317m3824            VIA   -    MD0100PA01X+125481Y+138430X0180Y         S0      
317m3824            J13   -F4   D0122PA01X+133106Y+159602X0282Y    R180 S3      
327m3824            C543  -2          A01X+125471Y+137939X0120Y0150R090 S1      
327m3825            J42   -B18        A01X+143136Y+011413X0150Y0500R090 S1      
327m3825            C704  -2          A01X+144026Y+011472X0120Y0150R180 S1      
317m3826            VIA   -    MD0100PA01X+161480Y+136010X0180Y         S0      
317m3826            J9    -I1   D0122PA01X+165154Y+158146X0282Y    R180 S3      
327m3826            C825  -2          A01X+161490Y+135519X0120Y0150R090 S1      
327m3827            VIA   -    M      A01X+067109Y+061950X0300Y         S1      
327m3827            J22   -OA2        A01X+065647Y+062110X0140Y0480R270 S1      
327m3827            R150  -1          A01X+067591Y+062140X0198Y0197     S1      
327m3828            VIA   -    M      A01X+162326Y+038472X0300Y    R180 S1      
327m3828            R405  -1          A01X+160510Y+038472X0198Y0197R180 S1      
327m3828            J27   -OA2        A01X+164156Y+038441X0140Y0480R090 S1      
327m3829            J21   -B48        A01X+028842Y+057148X0140Y0480R090 S1      
327m3829            C13   -2          A01X+032439Y+057209X0120Y0150R180 S1      
317m3830            J12   -T4   D0122PA01X+048232Y+148343X0282Y    R180 S3      
317m3830            VIA   -    MD0080PA01X+066949Y+125472X0160Y         S0      
327m3830            PEX1  -A19        A01X+066949Y+125472X0180Y         S1      
317m3831            VIA   -    MD0080PA01X+116772Y+108642X0160Y         S0      
327m3831            PEX2  -BF30       A01X+116772Y+108642X0180Y         S1      
317m3831            VIA   -    MD0100PA01X+111985Y+042643X0200Y    R180 S0      
327m3831            J24   -A51        A01X+111355Y+042695X0140Y0480R270 S1      
317m3832            VIA   -    MD0100PA01X+126705Y+136010X0180Y         S0      
317m3832            J13   -G5   D0122PA01X+133972Y+159169X0282Y    R180 S3      
327m3832            C541  -2          A01X+126695Y+135519X0120Y0150R090 S1      
327m3833            J44   -B18        A01X+163608Y+011413X0150Y0500R090 S1      
327m3833            C720  -2          A01X+164498Y+011472X0120Y0150R180 S1      
317m3834            VIA   -    MD0100PA01X+168484Y+136010X0180Y         S0      
317m3834            J9    -V1   D0122PA01X+165154Y+147398X0282Y    R180 S3      
327m3834            C808  -2          A01X+168474Y+135519X0120Y0150R090 S1      
327m3835            VIA   -    M      A01X+061564Y+063798X0300Y         S1      
327m3835            R106  -1          A01X+061066Y+064197X0198Y0197R180 S1      
327m3835            R124  -1   M      A01X+061066Y+063797X0198Y0197R180 S1      
327m3835            J22   -OB1        A01X+063836Y+062346X0140Y0480R270 S1      
317NCSI_NIC7_RXD0   VIA   -    M      A01X+166726Y+040350X0200Y         S2      
017NCSI_NIC7_RXD0   VIA   -    M      A18X+166726Y+040350X0260Y         S2      
017NCSI_NIC7_RXD0         -    MD0100PA00X+166726Y+040350                       
327NCSI_NIC7_RXD0   J27   -OB9        A01X+165968Y+040094X0140Y0480R090 S1      
327NCSI_NIC7_RXD0   R373  -1          A18X+167497Y+040592X0198Y0197R180 S2      
327m3836            J21   -B50        A01X+028842Y+057620X0140Y0480R090 S1      
327m3836            C12   -2          A01X+031399Y+057555X0120Y0150R180 S1      
317m3837            VIA   -    MD0080PA01X+062835Y+124724X0160Y         S0      
327m3837            PEX1  -C8         A01X+062835Y+124724X0180Y         S1      
317m3837            J12   -I1   D0122PA01X+045634Y+158146X0282Y    R180 S3      
327m3838            J24   -B66        A01X+109544Y+039152X0140Y0480R270 S1      
327m3838            C485  -2          A01X+106987Y+039090X0120Y0150     S1      
327m3839            J43   -B27        A01X+153372Y+013539X0150Y0500R090 S1      
327m3839            C706  -2          A01X+155302Y+013601X0120Y0150R180 S1      
317m3840            J9    -C6   D0122PA01X+169484Y+161138X0282Y    R180 S3      
317m3840            VIA   -    MD0080PA01X+152008Y+120610X0160Y         S0      
327m3840            PEX3  -P2         A01X+152008Y+120610X0180Y         S1      
327m3841            R148  -1          A01X+066206Y+065316X0198Y0197R090 S1      
317m3841            VIA   -    MD0100PA00X+065823Y+064645X0200Y         S0      
317m3841            VIA   -    M      A01X+066176Y+055168X0200Y    R180 S2      
017m3841            VIA   -    M      A18X+066176Y+055168X0260Y    R180 S2      
017m3841                  -    MD0100PA00X+066176Y+055168                       
327m3841            J22   -A11        A01X+065647Y+055183X0140Y0480R270 S1      
317m3842            VIA   -    MD0100PA00X+164977Y+044996X0200Y         S0      
327m3842            J27   -B10        A01X+165968Y+045132X0140Y0480R090 S1      
317m3842            VIA   -    M      A01X+169268Y+034802X0200Y    R180 S2      
017m3842            VIA   -    M      A18X+169268Y+034802X0260Y    R180 S2      
017m3842                  -    MD0100PA00X+169268Y+034802                       
327m3842            R402  -1          A01X+169268Y+034547X0198Y0197R270 S1      
317m3843            VIA   -    MD0080PA01X+032461Y+108268X0160Y    R270 S0      
327m3843            PEX0  -BG49       A01X+032461Y+108268X0180Y         S1      
327m3843            J21   -A44        A01X+027030Y+056203X0140Y0480R090 S1      
317m3843            VIA   -    MD0100PA01X+026400Y+056151X0200Y         S0      
317m3844            VIA   -    MD0080PA01X+117520Y+108268X0160Y         S0      
327m3844            PEX2  -BG32       A01X+117520Y+108268X0180Y         S1      
317m3844            VIA   -    MD0100PA01X+111985Y+044400X0200Y    R180 S0      
327m3844            J24   -A44        A01X+111355Y+044348X0140Y0480R270 S1      
317m3845            VIA   -    MD0100PA01X+124597Y+136010X0180Y         S0      
317m3845            J13   -E2   D0122PA01X+131374Y+160114X0282Y    R180 S3      
327m3845            C548  -2          A01X+124607Y+135519X0120Y0150R090 S1      
317m3846            J9    -B6   D0122PA01X+169484Y+161650X0282Y    R180 S3      
317m3846            VIA   -    MD0080PA01X+151634Y+120610X0160Y         S0      
327m3846            PEX3  -P1         A01X+151634Y+120610X0180Y         S1      
317m3847            VIA   -    MD0080PA01X+032461Y+112382X0160Y    R270 S0      
317m3847            VIA   -    MD0100PA01X+025670Y+048860X0200Y         S0      
327m3847            J21   -A26        A01X+027030Y+048911X0140Y0480R090 S1      
327m3847            PEX0  -AT49       A01X+032461Y+112382X0180Y         S1      
317m3848            VIA   -    MD0080PA01X+116398Y+107520X0160Y         S0      
327m3848            PEX2  -BJ29       A01X+116398Y+107520X0180Y         S1      
317m3848            VIA   -    MD0100PA01X+112715Y+042274X0200Y    R180 S0      
327m3848            J24   -A53        A01X+111355Y+042222X0140Y0480R270 S1      
317m3849            J9    -P7   D0122PA01X+170350Y+150468X0282Y    R180 S3      
317m3849            VIA   -    MD0080PA01X+153504Y+124350X0160Y         S0      
327m3849            PEX3  -D6         A01X+153504Y+124350X0180Y         S1      
327m3850            VIA   -    M      A01X+161740Y+038788X0300Y    R180 S1      
327m3850            R358  -2          A01X+160510Y+038872X0198Y0197     S1      
327m3850            J27   -OA4        A01X+164156Y+038913X0140Y0480R090 S1      
317m3851            VIA   -    MD0080PA01X+031338Y+112756X0160Y    R270 S0      
327m3851            PEX0  -AR46       A01X+031338Y+112756X0180Y         S1      
327m3851            J21   -A24        A01X+027030Y+048439X0140Y0480R090 S1      
317m3851            VIA   -    MD0100PA01X+026400Y+048491X0200Y         S0      
317m3852            VIA   -    MD0080PA01X+074803Y+108268X0160Y         S0      
327m3852            PEX1  -BG40       A01X+074803Y+108268X0180Y         S1      
327m3852            J22   -A17        A01X+065647Y+053766X0140Y0480R270 S1      
317m3852            VIA   -    MD0100PA01X+066277Y+053818X0200Y         S0      
317m3853            VIA   -    MD0100PA01X+048936Y+138430X0180Y         S0      
317m3853            J12   -P7   D0122PA01X+050831Y+150468X0282Y    R180 S3      
327m3853            C368  -2          A01X+048926Y+137939X0120Y0150R090 S1      
317m3854            VIA   -    MD0080PA01X+119764Y+108268X0160Y         S0      
327m3854            PEX2  -BG38       A01X+119764Y+108268X0180Y         S1      
317m3854            VIA   -    MD0100PA01X+111985Y+052400X0200Y    R180 S0      
327m3854            J24   -A23        A01X+111355Y+052348X0140Y0480R270 S1      
317m3855            VIA   -    MD0100PA01X+128269Y+138430X0180Y         S0      
317m3855            J13   -F7   D0122PA01X+135705Y+159681X0282Y    R180 S3      
327m3855            C538  -2          A01X+128279Y+137939X0120Y0150R090 S1      
317m3856            VIA   -    MD0100PA01X+169708Y+138430X0180Y         S0      
317m3856            J9    -V3   D0122PA01X+166886Y+147398X0282Y    R180 S3      
327m3856            C805  -2          A01X+169698Y+137939X0120Y0150R090 S1      
327m3857            VIA   -    M      A01X+162408Y+040072X0300Y    R180 S1      
327m3857            R378  -1          A01X+160510Y+040072X0198Y0197R180 S1      
327m3857            J27   -OA7        A01X+164156Y+039622X0140Y0480R090 S1      
317m3858            VIA   -    MD0100PA01X+026400Y+058986X0200Y         S0      
327m3858            J21   -A56        A01X+027030Y+059037X0140Y0480R090 S1      
317m3858            VIA   -    MD0080PA01X+030590Y+108268X0160Y         S0      
327m3858            PEX0  -BG44       A01X+030590Y+108268X0180Y         S1      
317m3859            VIA   -    MD0100PA01X+066277Y+047987X0200Y    R180 S0      
327m3859            J22   -A36        A01X+065647Y+047935X0140Y0480R270 S1      
317m3859            VIA   -    MD0080PA01X+072559Y+108268X0160Y         S0      
327m3859            PEX1  -BG34       A01X+072559Y+108268X0180Y         S1      
317m3860            VIA   -    MD0100PA01X+050500Y+136010X0180Y         S0      
317m3860            J12   -N8   D0122PA01X+051697Y+151413X0282Y    R180 S3      
327m3860            C371  -2          A01X+050510Y+135519X0120Y0150R090 S1      
317m3861            VIA   -    MD0080PA01X+116023Y+108642X0160Y         S0      
327m3861            PEX2  -BF28       A01X+116024Y+108642X0180Y         S1      
317m3861            VIA   -    MD0100PA01X+111985Y+041226X0200Y    R180 S0      
327m3861            J24   -A57        A01X+111355Y+041278X0140Y0480R270 S1      
317m3862            J9    -P3   D0122PA01X+166886Y+150468X0282Y    R180 S3      
317m3862            VIA   -    MD0080PA01X+151634Y+124724X0160Y         S0      
327m3862            PEX3  -C1         A01X+151634Y+124724X0180Y         S1      
327NCSI_NIC7_TXD0   VIA   -    M      A01X+162286Y+040872X0300Y    R180 S1      
327NCSI_NIC7_TXD0   R375  -1          A01X+160510Y+040872X0198Y0197R180 S1      
327NCSI_NIC7_TXD0   J27   -OA9        A01X+164156Y+040094X0140Y0480R090 S1      
317m3863            VIA   -    MD0080PA01X+031338Y+112008X0160Y    R270 S0      
327m3863            J21   -A31        A01X+027030Y+051435X0140Y0480R090 S1      
317m3863            VIA   -    MD0100PA01X+026400Y+051487X0200Y         S0      
327m3863            PEX0  -AU46       A01X+031338Y+112008X0180Y         S1      
317m3864            VIA   -    MD0100PA01X+067007Y+048695X0200Y    R180 S0      
327m3864            J22   -A33        A01X+065647Y+048644X0140Y0480R270 S1      
317m3864            VIA   -    MD0080PA01X+072933Y+107520X0160Y         S0      
327m3864            PEX1  -BJ35       A01X+072933Y+107520X0180Y         S1      
317m3865            J12   -V3   D0122PA01X+047366Y+147398X0282Y    R180 S3      
317m3865            VIA   -    MD0080PA01X+066575Y+124350X0160Y         S0      
327m3865            PEX1  -D18        A01X+066575Y+124350X0180Y         S1      
317m3866            VIA   -    MD0080PA01X+119016Y+108268X0160Y         S0      
327m3866            PEX2  -BG36       A01X+119016Y+108268X0180Y         S1      
317m3866            VIA   -    MD0100PA01X+111985Y+049404X0200Y    R180 S0      
327m3866            J24   -A30        A01X+111355Y+049352X0140Y0480R270 S1      
317m3867            J9    -B2   D0122PA01X+166020Y+161650X0282Y    R180 S3      
317m3867            VIA   -    MD0080PA01X+151634Y+119114X0160Y         S0      
327m3867            PEX3  -V1         A01X+151634Y+119114X0180Y         S1      
327m3868            R403  -1          A01X+168868Y+034547X0198Y0197R270 S1      
317m3868            VIA   -    M      A01X+168742Y+034794X0200Y    R180 S2      
017m3868            VIA   -    M      A18X+168742Y+034794X0260Y    R180 S2      
017m3868                  -    MD0100PA00X+168742Y+034794                       
317m3868            VIA   -    MD0100PA00X+163627Y+045388X0200Y         S0      
327m3868            J27   -A11        A01X+164156Y+045368X0140Y0480R090 S1      
327m3869            J21   -B44        A01X+028842Y+056203X0140Y0480R090 S1      
327m3869            C16   -2          A01X+031399Y+056138X0120Y0150R180 S1      
327m3870            J22   -B36        A01X+063836Y+047935X0140Y0480R270 S1      
327m3870            C257  -2          A01X+061278Y+048000X0120Y0150     S1      
327m3871            J24   -B57        A01X+109544Y+041278X0140Y0480R270 S1      
327m3871            C479  -2          A01X+105947Y+041219X0120Y0150     S1      
327m3872            J27   -B17        A01X+165968Y+046785X0140Y0480R090 S1      
327m3872            C665  -2          A01X+168525Y+046721X0120Y0150R180 S1      
317m3873            J9    -C5   D0122PA01X+168618Y+161217X0282Y    R180 S3      
317m3873            VIA   -    MD0080PA01X+152382Y+120236X0160Y         S0      
327m3873            PEX3  -R3         A01X+152382Y+120236X0180Y         S1      
327m3874            VIA   -    M      A18X+165976Y+038800X0260Y         S2      
317m3874            VIA   -    MD0100PA00X+166378Y+038441X0200Y         S0      
327m3874            R359  -1          A18X+165534Y+038800X0198Y0197     S2      
327m3874            J27   -OB2        A01X+165968Y+038441X0140Y0480R090 S1      
327m3875            J21   -B30        A01X+028842Y+051199X0140Y0480R090 S1      
327m3875            C24   -2          A01X+031399Y+051134X0120Y0150R180 S1      
327m3876            J22   -A20        A01X+065647Y+053057X0140Y0480R270 S1      
317m3876            VIA   -    MD0100PA01X+067007Y+053109X0200Y    R180 S0      
317m3876            VIA   -    MD0080PA01X+074429Y+107520X0160Y         S0      
327m3876            PEX1  -BJ39       A01X+074429Y+107520X0180Y         S1      
317m3877            VIA   -    MD0080PA01X+118268Y+108642X0160Y         S0      
327m3877            PEX2  -BF34       A01X+118268Y+108642X0180Y         S1      
317m3877            VIA   -    MD0100PA01X+111985Y+047647X0200Y    R180 S0      
327m3877            J24   -A37        A01X+111355Y+047699X0140Y0480R270 S1      
317m3878            J13   -M1   D0122PA01X+130508Y+156098X0282Y    R180 S3      
317m3878            VIA   -    MD0080PA01X+114528Y+124350X0160Y         S0      
327m3878            PEX2  -D24        A01X+114528Y+124350X0180Y         S1      
327m3879            C636  -2          A01X+168525Y+060750X0120Y0150R180 S1      
327m3879            J27   -B63        A01X+165968Y+060691X0140Y0480R090 S1      
317m3880            J9    -N8   D0122PA01X+171216Y+151413X0282Y    R180 S3      
317m3880            VIA   -    MD0080PA01X+153878Y+125472X0160Y         S0      
327m3880            PEX3  -A7         A01X+153878Y+125472X0180Y         S1      
327NCSI_NIC7_TXD1   VIA   -    M      A01X+161366Y+040472X0300Y    R180 S1      
327NCSI_NIC7_TXD1   R376  -1          A01X+160510Y+040472X0198Y0197R180 S1      
327NCSI_NIC7_TXD1   J27   -OA8        A01X+164156Y+039858X0140Y0480R090 S1      
327PU_CLKREQ4       J34   -A11        A01X+049908Y+009760X0150Y0500R090 S1      
317PU_CLKREQ4       VIA   -    M      A01X+049253Y+009767X0200Y         S2      
017PU_CLKREQ4       VIA   -    M      A18X+049253Y+009767X0260Y         S2      
017PU_CLKREQ4             -    MD0100PA00X+049253Y+009767                       
327PU_CLKREQ4       R422  -2          A01X+048926Y+009767X0198Y0197     S1      
327m3881            J21   -B54        A01X+028842Y+058565X0140Y0480R090 S1      
327m3881            C9    -2          A01X+032439Y+058626X0120Y0150R180 S1      
327m3882            J22   -B40        A01X+063836Y+046990X0140Y0480R270 S1      
327m3882            C258  -2          A01X+060238Y+046929X0120Y0150     S1      
327m3883            J24   -B23        A01X+109544Y+052348X0140Y0480R270 S1      
327m3883            C460  -2          A01X+106987Y+052413X0120Y0150     S1      
317m3884            J13   -K4   D0122PA01X+133106Y+157043X0282Y    R180 S3      
317m3884            VIA   -    MD0080PA01X+115650Y+125472X0160Y    R090 S0      
327m3884            PEX2  -A27        A01X+115650Y+125472X0180Y         S1      
317m3885            VIA   -    MD0080PA01X+168838Y+113504X0160Y    R270 S0      
317m3885            VIA   -    MD0100PA01X+163526Y+046734X0200Y         S0      
327m3885            J27   -A17        A01X+164156Y+046785X0140Y0480R090 S1      
327m3885            PEX3  -AN47       A01X+168838Y+113504X0180Y         S1      
317m3886            VIA   -    MD0100PA01X+163588Y+140850X0180Y         S0      
317m3886            J9    -I4   D0122PA01X+167752Y+158067X0282Y    R180 S3      
327m3886            C818  -2          A01X+163578Y+140359X0120Y0150R090 S1      
327NIC7_BIF1_N      J27   -B8         A01X+165968Y+044660X0140Y0480R090 S1      
317NIC7_BIF1_N      VIA   -    M      A01X+164979Y+044049X0200Y         S2      
017NIC7_BIF1_N      VIA   -    M      A18X+164979Y+044049X0260Y         S2      
017NIC7_BIF1_N            -    MD0100PA00X+164979Y+044049                       
327NIC7_BIF1_N      R388  -1          A18X+161534Y+043103X0198Y0197     S2      
327NIC7_BIF1_N      R389  -1   M      A18X+161919Y+043103X0198Y0197R180 S2      
327PU_CLKREQ5       J35   -A11        A01X+060144Y+009760X0150Y0500R090 S1      
317PU_CLKREQ5       VIA   -    M      A01X+059489Y+009767X0200Y         S2      
017PU_CLKREQ5       VIA   -    M      A18X+059489Y+009767X0260Y         S2      
017PU_CLKREQ5             -    MD0100PA00X+059489Y+009767                       
327PU_CLKREQ5       R426  -2          A01X+059162Y+009767X0198Y0197     S1      
327m3887            J21   -B37        A01X+028842Y+052852X0140Y0480R090 S1      
327m3887            C19   -2          A01X+031399Y+052911X0120Y0150R180 S1      
317m3888            VIA   -    MD0080PA01X+071437Y+107520X0160Y         S0      
327m3888            J22   -A47        A01X+065647Y+043640X0140Y0480R270 S1      
317m3888            VIA   -    MD0100PA01X+067007Y+043692X0200Y    R180 S0      
327m3888            PEX1  -BJ31       A01X+071437Y+107520X0180Y         S1      
327m3889            J24   -B30        A01X+109544Y+049352X0140Y0480R270 S1      
327m3889            C464  -2          A01X+106987Y+049417X0120Y0150     S1      
327m3890            C639  -2          A01X+169565Y+059684X0120Y0150R180 S1      
327m3890            J27   -B59        A01X+165968Y+059746X0140Y0480R090 S1      
317m3891            J9    -C4   D0122PA01X+167752Y+161138X0282Y    R180 S3      
317m3891            VIA   -    MD0080PA01X+152008Y+119862X0160Y         S0      
327m3891            PEX3  -T2         A01X+152008Y+119862X0180Y         S1      
327NIC7_LD_N        R368  -1          A18X+167497Y+037791X0198Y0197R180 S2      
317NIC7_LD_N        VIA   -    M      A01X+167026Y+037791X0200Y         S2      
017NIC7_LD_N        VIA   -    M      A18X+167026Y+037791X0260Y         S2      
017NIC7_LD_N              -    MD0100PA00X+167026Y+037791                       
327NIC7_LD_N        J27   -OB3        A01X+165968Y+038677X0140Y0480R090 S1      
327m3892            J35   -B9         A01X+061955Y+009287X0150Y0500R090 S1      
317m3892            VIA   -    M      A01X+062428Y+009287X0200Y         S2      
017m3892            VIA   -    M      A18X+062428Y+009287X0260Y         S2      
017m3892                  -    MD0100PA00X+062428Y+009287                       
327m3892            R425  -2          A01X+064011Y+009820X0198Y0197R270 S1      
327m3892            R424  -2   M      A01X+063611Y+009820X0198Y0197R270 S1      
327m3893            J21   -B17        A01X+028842Y+046785X0140Y0480R090 S1      
327m3893            C32   -2          A01X+031399Y+046721X0120Y0150R180 S1      
317m3894            VIA   -    MD0080PA01X+072185Y+107520X0160Y         S0      
327m3894            J22   -A39        A01X+065647Y+047226X0140Y0480R270 S1      
317m3894            VIA   -    MD0100PA01X+067007Y+047278X0200Y    R180 S0      
327m3894            PEX1  -BJ33       A01X+072185Y+107520X0180Y         S1      
317m3895            J12   -U2   D0122PA01X+046500Y+147831X0282Y    R180 S3      
317m3895            VIA   -    MD0080PA01X+066201Y+125098X0160Y         S0      
327m3895            PEX1  -B17        A01X+066201Y+125098X0180Y         S1      
327m3896            J24   -B37        A01X+109544Y+047699X0140Y0480R270 S1      
327m3896            C467  -2          A01X+106987Y+047640X0120Y0150     S1      
317m3897            VIA   -    MD0100PA01X+129493Y+136010X0180Y         S0      
317m3897            J13   -E8   D0122PA01X+136571Y+160114X0282Y    R180 S3      
327m3897            C536  -2          A01X+129503Y+135519X0120Y0150R090 S1      
317m3898            VIA   -    MD0080PA01X+168838Y+111260X0160Y    R270 S0      
317m3898            VIA   -    MD0100PA01X+163526Y+052564X0200Y         S0      
327m3898            J27   -A36        A01X+164156Y+052616X0140Y0480R090 S1      
327m3898            PEX3  -AW47       A01X+168838Y+111260X0180Y         S1      
317m3899            J9    -C3   D0122PA01X+166886Y+161217X0282Y    R180 S3      
317m3899            VIA   -    MD0080PA01X+152382Y+119488X0160Y         S0      
327m3899            PEX3  -U3         A01X+152382Y+119488X0180Y         S1      
317PRSNTB2_NIC7_N   VIA   -    M      A01X+163322Y+045846X0200Y         S2      
017PRSNTB2_NIC7_N   VIA   -    M      A18X+163322Y+045846X0260Y         S2      
017PRSNTB2_NIC7_N         -    MD0100PA00X+163322Y+045846                       
327PRSNTB2_NIC7_N   R398  -2          A01X+162354Y+046286X0198Y0197     S1      
327PRSNTB2_NIC7_N   R364  -1   M      A01X+162354Y+045886X0198Y0197R180 S1      
327PRSNTB2_NIC7_N   J27   -A12        A01X+164156Y+045604X0140Y0480R090 S1      
327m3900            J34   -B9         A01X+051718Y+009287X0150Y0500R090 S1      
317m3900            VIA   -    M      A01X+052192Y+009287X0200Y         S2      
017m3900            VIA   -    M      A18X+052192Y+009287X0260Y         S2      
017m3900                  -    MD0100PA00X+052192Y+009287                       
327m3900            R423  -2          A01X+053775Y+009820X0198Y0197R270 S1      
327m3900            R421  -2   M      A01X+053375Y+009820X0198Y0197R270 S1      
327m3901            J21   -B20        A01X+028842Y+047494X0140Y0480R090 S1      
327m3901            C30   -2          A01X+032439Y+047432X0120Y0150R180 S1      
317m3902            VIA   -    MD0080PA01X+071063Y+108268X0160Y         S0      
327m3902            J22   -A50        A01X+065647Y+042931X0140Y0480R270 S1      
317m3902            VIA   -    MD0100PA01X+066277Y+042983X0200Y    R180 S0      
327m3902            PEX1  -BG30       A01X+071063Y+108268X0180Y         S1      
317m3903            VIA   -    MD0100PA01X+045604Y+140850X0180Y         S0      
317m3903            J12   -O3   D0122PA01X+047366Y+150980X0282Y    R180 S3      
327m3903            C361  -2          A01X+045614Y+140359X0120Y0150R090 S1      
317m3904            VIA   -    MD0080PA01X+114901Y+107894X0160Y         S0      
327m3904            PEX2  -BH25       A01X+114902Y+107894X0180Y         S1      
317m3904            VIA   -    MD0100PA01X+112715Y+039100X0200Y    R180 S0      
327m3904            J24   -A66        A01X+111355Y+039152X0140Y0480R270 S1      
317m3905            VIA   -    MD0080PA01X+168838Y+112756X0160Y    R270 S0      
327m3905            PEX3  -AR47       A01X+168838Y+112756X0180Y         S1      
317m3905            VIA   -    MD0100PA01X+163526Y+048151X0200Y         S0      
327m3905            J27   -A23        A01X+164156Y+048203X0140Y0480R090 S1      
317m3906            VIA   -    MD0100PA01X+163928Y+136010X0180Y         S0      
317m3906            J9    -I3   D0122PA01X+166886Y+158146X0282Y    R180 S3      
327m3906            C821  -2          A01X+163938Y+135519X0120Y0150R090 S1      
317NIC7_CLK         VIA   -    M      A01X+166362Y+039386X0200Y         S2      
017NIC7_CLK         VIA   -    M      A18X+166362Y+039386X0260Y         S2      
017NIC7_CLK               -    MD0100PA00X+166362Y+039386                       
327NIC7_CLK         J27   -OB6        A01X+165968Y+039386X0140Y0480R090 S1      
327NIC7_CLK         R371  -1          A18X+167497Y+038991X0198Y0197R180 S2      
327PRSNT_SSD5_N     J35   -A12        A01X+060144Y+009996X0150Y0500R090 S1      
317PRSNT_SSD5_N     VIA   -    M      A01X+059450Y+010341X0200Y         S2      
017PRSNT_SSD5_N     VIA   -    M      A18X+059450Y+010341X0260Y         S2      
017PRSNT_SSD5_N           -    MD0100PA00X+059450Y+010341                       
327PRSNT_SSD5_N     R4063 -2          A01X+059142Y+010341X0198Y0197R270 S1      
327m3907            C261  -2          A01X+060238Y+044413X0120Y0150     S1      
327m3907            J22   -B44        A01X+063836Y+044348X0140Y0480R270 S1      
317m3908            VIA   -    MD0080PA01X+120512Y+108268X0160Y         S0      
327m3908            PEX2  -BG40       A01X+120512Y+108268X0180Y         S1      
317m3908            VIA   -    MD0100PA01X+111985Y+053818X0200Y    R180 S0      
327m3908            J24   -A17        A01X+111355Y+053766X0140Y0480R270 S1      
317m3909            VIA   -    MD0100PA01X+126705Y+140850X0180Y         S0      
317m3909            J13   -F6   D0122PA01X+134839Y+159602X0282Y    R180 S3      
327m3909            C539  -2          A01X+126695Y+140359X0120Y0150R090 S1      
327m3910            J27   -B27        A01X+165968Y+049148X0140Y0480R090 S1      
327m3910            C658  -2          A01X+169565Y+049209X0120Y0150R180 S1      
317m3911            J9    -B8   D0122PA01X+171216Y+161650X0282Y    R180 S3      
317m3911            VIA   -    MD0080PA01X+151634Y+121358X0160Y         S0      
327m3911            PEX3  -M1         A01X+151634Y+121358X0180Y         S1      
317NIC7_DATA_OUT    VIA   -    M      A01X+166926Y+039150X0200Y         S2      
017NIC7_DATA_OUT    VIA   -    M      A18X+166926Y+039150X0260Y         S2      
017NIC7_DATA_OUT          -    MD0100PA00X+166926Y+039150                       
327NIC7_DATA_OUT    J27   -OB5        A01X+165968Y+039150X0140Y0480R090 S1      
327NIC7_DATA_OUT    R370  -1          A18X+167497Y+038591X0198Y0197R180 S2      
327PRSNT_SSD4_N     J34   -A12        A01X+049908Y+009996X0150Y0500R090 S1      
317PRSNT_SSD4_N     VIA   -    M      A01X+049214Y+010341X0200Y         S2      
017PRSNT_SSD4_N     VIA   -    M      A18X+049214Y+010341X0260Y         S2      
017PRSNT_SSD4_N           -    MD0100PA00X+049214Y+010341                       
327PRSNT_SSD4_N     R4061 -2          A01X+048906Y+010341X0198Y0197R270 S1      
327m3912            C269  -2          A01X+060238Y+041579X0120Y0150     S1      
327m3912            J22   -B56        A01X+063836Y+041514X0140Y0480R270 S1      
317m3913            VIA   -    MD0080PA01X+119390Y+107520X0160Y         S0      
327m3913            PEX2  -BJ37       A01X+119390Y+107520X0180Y         S1      
317m3913            VIA   -    MD0100PA01X+112715Y+051692X0200Y    R180 S0      
327m3913            J24   -A26        A01X+111355Y+051640X0140Y0480R270 S1      
317m3914            J13   -M3   D0122PA01X+132240Y+156098X0282Y    R180 S3      
317m3914            VIA   -    MD0080PA01X+115276Y+124350X0160Y         S0      
327m3914            PEX2  -D26        A01X+115276Y+124350X0180Y         S1      
317m3915            VIA   -    MD0080PA01X+167716Y+108268X0160Y         S0      
327m3915            PEX3  -BG44       A01X+167716Y+108268X0180Y         S1      
317m3915            VIA   -    MD0100PA01X+163526Y+058986X0200Y         S0      
327m3915            J27   -A56        A01X+164156Y+059037X0140Y0480R090 S1      
317m3916            J9    -O3   D0122PA01X+166886Y+150980X0282Y    R180 S3      
317m3916            VIA   -    MD0080PA01X+152008Y+124724X0160Y         S0      
327m3916            PEX3  -C2         A01X+152008Y+124724X0180Y         S1      
317m3917            VIA   -    MD0100PA01X+066277Y+049404X0200Y    R180 S0      
327m3917            J22   -A30        A01X+065647Y+049352X0140Y0480R270 S1      
317m3917            VIA   -    MD0080PA01X+073307Y+108268X0160Y         S0      
327m3917            PEX1  -BG36       A01X+073307Y+108268X0180Y         S1      
317m3918            VIA   -    MD0080PA01X+117894Y+107520X0160Y         S0      
327m3918            PEX2  -BJ33       A01X+117894Y+107520X0180Y         S1      
317m3918            VIA   -    MD0100PA01X+112715Y+047278X0200Y    R180 S0      
327m3918            J24   -A39        A01X+111355Y+047226X0140Y0480R270 S1      
317m3919            J13   -K6   D0122PA01X+134839Y+157043X0282Y    R180 S3      
317m3919            VIA   -    MD0080PA01X+116398Y+125472X0160Y    R090 S0      
327m3919            PEX2  -A29        A01X+116398Y+125472X0180Y         S1      
327m3920            J27   -B40        A01X+165968Y+053561X0140Y0480R090 S1      
327m3920            C650  -2          A01X+169565Y+053622X0120Y0150R180 S1      
317m3921            J9    -C1   D0122PA01X+165154Y+161217X0282Y    R180 S3      
317m3921            VIA   -    MD0080PA01X+152382Y+118740X0160Y         S0      
327m3921            PEX3  -W3         A01X+152382Y+118740X0180Y         S1      
317RST_HP_NIC4_N    VIA   -    M      A01X+110804Y+066815X0200Y         S2      
017RST_HP_NIC4_N    VIA   -    M      A18X+110804Y+066815X0260Y         S2      
017RST_HP_NIC4_N          -    MD0100PA00X+110804Y+066815                       
327RST_HP_NIC4_N    U31   -4          A01X+110804Y+067236X0220Y0530R180 S1      
327RST_HP_NIC4_N    U30   -2          A01X+110102Y+065572X0160Y0360R270 S1      
327PRSNTB0_NIC7_N   VIA   -    M      A01X+168192Y+054034X0300Y    R180 S1      
327PRSNTB0_NIC7_N   J27   -B42        A01X+165968Y+054034X0140Y0480R090 S1      
327PRSNTB0_NIC7_N   R396  -2          A01X+168677Y+054591X0198Y0197R180 S1      
327PRSNTB0_NIC7_N   R363  -1   M      A01X+168677Y+054191X0198Y0197     S1      
327m3922            J43   -B9         A01X+153372Y+009287X0150Y0500R090 S1      
317m3922            VIA   -    M      A01X+153845Y+009287X0200Y         S2      
017m3922            VIA   -    M      A18X+153845Y+009287X0260Y         S2      
017m3922                  -    MD0100PA00X+153845Y+009287                       
327m3922            R449  -2          A01X+155428Y+009820X0198Y0197R270 S1      
327m3922            R448  -2   M      A01X+155028Y+009820X0198Y0197R270 S1      
327m3923            C267  -2          A01X+061278Y+042285X0120Y0150     S1      
327m3923            J22   -B53        A01X+063836Y+042222X0140Y0480R270 S1      
317m3924            J12   -O1   D0122PA01X+045634Y+150980X0282Y    R180 S3      
327m3924            C357  -2          A01X+044390Y+137939X0120Y0150R090 S1      
317m3924            VIA   -    MD0100PA01X+044380Y+138430X0180Y         S0      
317m3925            VIA   -    MD0080PA01X+115649Y+107520X0160Y         S0      
327m3925            PEX2  -BJ27       A01X+115650Y+107520X0180Y         S1      
327m3925            J24   -A59        A01X+111355Y+040805X0140Y0480R270 S1      
317m3925            VIA   -    MD0100PA01X+112715Y+040857X0200Y    R180 S0      
317m3926            VIA   -    MD0080PA01X+169587Y+110886X0160Y    R270 S0      
327m3926            PEX3  -AY49       A01X+169587Y+110886X0180Y         S1      
317m3926            VIA   -    MD0100PA01X+162796Y+053273X0200Y         S0      
327m3926            J27   -A39        A01X+164156Y+053325X0140Y0480R090 S1      
317m3927            J9    -O8   D0122PA01X+171216Y+150902X0282Y    R180 S3      
317m3927            VIA   -    MD0080PA01X+153878Y+125098X0160Y         S0      
327m3927            PEX3  -B7         A01X+153878Y+125098X0180Y         S1      
327PU_CLKREQ12      J42   -A11        A01X+141325Y+009760X0150Y0500R090 S1      
317PU_CLKREQ12      VIA   -    M      A01X+140670Y+009767X0200Y         S2      
017PU_CLKREQ12      VIA   -    M      A18X+140670Y+009767X0260Y         S2      
017PU_CLKREQ12            -    MD0100PA00X+140670Y+009767                       
327PU_CLKREQ12      R446  -2          A01X+140343Y+009767X0198Y0197     S1      
327m3928            C274  -2          A01X+061278Y+039090X0120Y0150     S1      
327m3928            J22   -B66        A01X+063836Y+039152X0140Y0480R270 S1      
327m3929            J24   -B63        A01X+109544Y+039860X0140Y0480R270 S1      
327m3929            C483  -2          A01X+106187Y+039801X0120Y0150     S1      
327m3930            J27   -B60        A01X+165968Y+059982X0140Y0480R090 S1      
327m3930            C638  -2          A01X+169565Y+060044X0120Y0150R180 S1      
317m3931            J9    -B4   D0122PA01X+167752Y+161650X0282Y    R180 S3      
317m3931            VIA   -    MD0080PA01X+151634Y+119862X0160Y         S0      
327m3931            PEX3  -T1         A01X+151634Y+119862X0180Y         S1      
327m3932            VIA   -    M      A01X+112223Y+068306X0300Y         S1      
327m3932            U31   -1          A01X+111552Y+068201X0220Y0530R180 S1      
327m3932            R255  -1   M      A01X+111908Y+068969X0198Y0197     S1      
327m3932            Q5    -6          A01X+111886Y+069480X0170Y0240R180 S1      
327m3933            J42   -B9         A01X+143136Y+009287X0150Y0500R090 S1      
317m3933            VIA   -    M      A01X+143609Y+009287X0200Y         S2      
017m3933            VIA   -    M      A18X+143609Y+009287X0260Y         S2      
017m3933                  -    MD0100PA00X+143609Y+009287                       
327m3933            R447  -2          A01X+145192Y+009820X0198Y0197R270 S1      
327m3933            R445  -2   M      A01X+144792Y+009820X0198Y0197R270 S1      
317m3934            VIA   -    MD0080PA01X+073681Y+107894X0160Y         S0      
327m3934            PEX1  -BH37       A01X+073681Y+107894X0180Y         S1      
317m3934            VIA   -    MD0100PA01X+067007Y+051352X0200Y    R180 S0      
327m3934            J22   -A27        A01X+065647Y+051404X0140Y0480R270 S1      
317m3935            VIA   -    MD0100PA01X+047712Y+136010X0180Y         S0      
317m3935            J12   -P5   D0122PA01X+049098Y+150468X0282Y    R180 S3      
327m3935            C364  -2          A01X+047702Y+135519X0120Y0150R090 S1      
317m3936            VIA   -    MD0080PA01X+117520Y+108642X0160Y         S0      
327m3936            PEX2  -BF32       A01X+117520Y+108642X0180Y         S1      
317m3936            VIA   -    MD0100PA01X+111985Y+044060X0200Y    R180 S0      
327m3936            J24   -A45        A01X+111355Y+044112X0140Y0480R270 S1      
317m3937            VIA   -    MD0100PA01X+127045Y+136010X0180Y         S0      
317m3937            J13   -F5   D0122PA01X+133972Y+159681X0282Y    R180 S3      
327m3937            C542  -2          A01X+127055Y+135519X0120Y0150R090 S1      
317m3938            VIA   -    MD0080PA01X+166968Y+108268X0160Y         S0      
327m3938            PEX3  -BG42       A01X+166968Y+108268X0180Y         S1      
317m3938            VIA   -    MD0100PA01X+163526Y+060403X0200Y         S0      
327m3938            J27   -A62        A01X+164156Y+060455X0140Y0480R090 S1      
317m3939            VIA   -    MD0100PA01X+171272Y+136010X0180Y         S0      
317m3939            J9    -T4   D0122PA01X+167752Y+148343X0282Y    R180 S3      
327m3939            C803  -2          A01X+171282Y+135519X0120Y0150R090 S1      
327PU_CLKREQ13      J43   -A11        A01X+151561Y+009760X0150Y0500R090 S1      
317PU_CLKREQ13      VIA   -    M      A01X+150906Y+009767X0200Y         S2      
017PU_CLKREQ13      VIA   -    M      A18X+150906Y+009767X0260Y         S2      
017PU_CLKREQ13            -    MD0100PA00X+150906Y+009767                       
327PU_CLKREQ13      R450  -2          A01X+150580Y+009767X0198Y0197     S1      
327m3940            C260  -2          A01X+060238Y+044053X0120Y0150     S1      
327m3940            J22   -B45        A01X+063836Y+044112X0140Y0480R270 S1      
317m3941            VIA   -    MD0100PA01X+050160Y+136010X0180Y         S0      
327m3941            C370  -2          A01X+050150Y+135519X0120Y0150R090 S1      
317m3941            J12   -O8   D0122PA01X+051697Y+150902X0282Y    R180 S3      
327m3942            J24   -B17        A01X+109544Y+053766X0140Y0480R270 S1      
327m3942            C456  -2          A01X+106987Y+053831X0120Y0150     S1      
317m3943            VIA   -    MD0080PA01X+117146Y+125472X0160Y    R090 S0      
317m3943            J13   -K8   D0122PA01X+136571Y+157043X0282Y    R180 S3      
327m3943            PEX2  -A31        A01X+117146Y+125472X0180Y         S1      
327m3944            J27   -B36        A01X+165968Y+052616X0140Y0480R090 S1      
327m3944            C653  -2          A01X+168525Y+052551X0120Y0150R180 S1      
317m3945            VIA   -    MD0100PA01X+171272Y+140850X0180Y         S0      
317m3945            J9    -U5   D0122PA01X+168618Y+147910X0282Y    R180 S3      
327m3945            C801  -2          A01X+171282Y+140359X0120Y0150R090 S1      
327m3946            VIA   -    M      A01X+161308Y+038072X0300Y    R180 S1      
327m3946            R404  -1          A01X+160510Y+038072X0198Y0197R180 S1      
327m3946            J27   -OA1        A01X+164156Y+038205X0140Y0480R090 S1      
327m3947            C266  -2          A01X+061278Y+041925X0120Y0150     S1      
327m3947            J22   -B54        A01X+063836Y+041986X0140Y0480R270 S1      
327m3948            J24   -B62        A01X+109544Y+040096X0140Y0480R270 S1      
327m3948            C484  -2          A01X+106187Y+040161X0120Y0150     S1      
317m3949            VIA   -    MD0080PA01X+166594Y+107520X0160Y         S0      
317m3949            VIA   -    MD0100PA01X+162796Y+061112X0200Y         S0      
327m3949            J27   -A65        A01X+164156Y+061163X0140Y0480R090 S1      
327m3949            PEX3  -BJ41       A01X+166594Y+107520X0180Y         S1      
317m3950            J9    -N2   D0122PA01X+166020Y+151413X0282Y    R180 S3      
317m3950            VIA   -    MD0080PA01X+152008Y+122106X0160Y         S0      
327m3950            PEX3  -K2         A01X+152008Y+122106X0180Y         S1      
327NIC7_BIF2_N      VIA   -    M      A18X+162926Y+043300X0260Y         S2      
317NIC7_BIF2_N      VIA   -    MD0100PA00X+165009Y+044484X0200Y         S0      
327NIC7_BIF2_N      R391  -1   M      A18X+161919Y+043503X0198Y0197R180 S2      
327NIC7_BIF2_N      R390  -1          A18X+161534Y+043503X0198Y0197     S2      
327NIC7_BIF2_N      J27   -B9         A01X+165968Y+044896X0140Y0480R090 S1      
327m3951            J22   -B17        A01X+063836Y+053766X0140Y0480R270 S1      
327m3951            C245  -2          A01X+061278Y+053831X0120Y0150     S1      
317m3952            J12   -U6   D0122PA01X+049965Y+147831X0282Y    R180 S3      
317m3952            VIA   -    MD0080PA01X+067697Y+125098X0160Y         S0      
327m3952            PEX1  -B21        A01X+067697Y+125098X0180Y         S1      
327m3953            J24   -B18        A01X+109544Y+053530X0140Y0480R270 S1      
327m3953            C455  -2          A01X+106987Y+053471X0120Y0150     S1      
317m3954            VIA   -    MD0080PA01X+116772Y+124350X0160Y         S0      
327m3954            PEX2  -D30        A01X+116772Y+124350X0180Y         S1      
317m3954            J13   -M7   D0122PA01X+135705Y+156098X0282Y    R180 S3      
327m3955            J27   -B53        A01X+165968Y+058329X0140Y0480R090 S1      
327m3955            C643  -2          A01X+169565Y+058266X0120Y0150R180 S1      
317m3956            VIA   -    MD0100PA01X+167260Y+138430X0180Y         S0      
317m3956            J9    -I8   D0122PA01X+171216Y+158067X0282Y    R180 S3      
327m3956            C810  -2          A01X+167250Y+137939X0120Y0150R090 S1      
327m3957            VIA   -    M      A01X+162445Y+039150X0300Y    R180 S1      
327m3957            R358  -1          A01X+160195Y+038872X0198Y0197     S1      
327m3957            J27   -OA5        A01X+164156Y+039150X0140Y0480R090 S1      
317m3958            VIA   -    MD0080PA01X+071811Y+108268X0160Y         S0      
327m3958            J22   -A44        A01X+065647Y+044348X0140Y0480R270 S1      
317m3958            VIA   -    MD0100PA01X+066277Y+044400X0200Y    R180 S0      
327m3958            PEX1  -BG32       A01X+071811Y+108268X0180Y         S1      
317m3959            VIA   -    MD0080PA01X+062835Y+124350X0160Y         S0      
327m3959            PEX1  -D8         A01X+062835Y+124350X0180Y         S1      
317m3959            J12   -J1   D0122PA01X+045634Y+157634X0282Y    R180 S3      
327m3960            J24   -B44        A01X+109544Y+044348X0140Y0480R270 S1      
327m3960            C472  -2          A01X+105947Y+044413X0120Y0150     S1      
317m3961            J13   -M5   D0122PA01X+133972Y+156098X0282Y    R180 S3      
317m3961            VIA   -    MD0080PA01X+116024Y+124350X0160Y         S0      
327m3961            PEX2  -D28        A01X+116024Y+124350X0180Y         S1      
327m3962            J27   -B24        A01X+165968Y+048439X0140Y0480R090 S1      
327m3962            C660  -2          A01X+168525Y+048498X0120Y0150R180 S1      
317m3963            VIA   -    MD0100PA01X+168824Y+140850X0180Y         S0      
317m3963            J9    -T2   D0122PA01X+166020Y+148343X0282Y    R180 S3      
327m3963            C806  -2          A01X+168834Y+140359X0120Y0150R090 S1      
327PRSNT_SSD13_N    J43   -A12        A01X+151561Y+009996X0150Y0500R090 S1      
317PRSNT_SSD13_N    VIA   -    M      A01X+150867Y+010341X0200Y         S2      
017PRSNT_SSD13_N    VIA   -    M      A18X+150867Y+010341X0260Y         S2      
017PRSNT_SSD13_N          -    MD0100PA00X+150867Y+010341                       
327PRSNT_SSD13_N    R4079 -2          A01X+150559Y+010341X0198Y0197R270 S1      
317m3964            VIA   -    MD0080PA01X+069567Y+108268X0160Y         S0      
327m3964            J22   -A62        A01X+065647Y+040096X0140Y0480R270 S1      
317m3964            VIA   -    MD0100PA01X+066277Y+040148X0200Y    R180 S0      
327m3964            PEX1  -BG26       A01X+069567Y+108268X0180Y         S1      
317m3965            VIA   -    MD0080PA01X+063583Y+124724X0160Y         S0      
327m3965            PEX1  -C10        A01X+063583Y+124724X0180Y         S1      
317m3965            J12   -I3   D0122PA01X+047366Y+158146X0282Y    R180 S3      
327m3966            J24   -B56        A01X+109544Y+041514X0140Y0480R270 S1      
327m3966            C480  -2          A01X+105947Y+041579X0120Y0150     S1      
327m3967            J27   -B26        A01X+165968Y+048911X0140Y0480R090 S1      
327m3967            C659  -2          A01X+169565Y+048849X0120Y0150R180 S1      
317m3968            VIA   -    MD0100PA01X+168824Y+136010X0180Y         S0      
317m3968            J9    -U1   D0122PA01X+165154Y+147910X0282Y    R180 S3      
327m3968            C809  -2          A01X+168834Y+135519X0120Y0150R090 S1      
327m3969            VIA   -    M      A01X+161382Y+041272X0300Y    R180 S1      
327m3969            R377  -1          A01X+160510Y+041272X0198Y0197R180 S1      
327m3969            J27   -OA14       A01X+164156Y+041276X0140Y0480R090 S1      
327m3970            C270  -2          A01X+061278Y+040507X0120Y0150     S1      
327m3970            J22   -B60        A01X+063836Y+040569X0140Y0480R270 S1      
317m3971            J12   -T6   D0122PA01X+049965Y+148343X0282Y    R180 S3      
317m3971            VIA   -    MD0080PA01X+067697Y+125472X0160Y         S0      
327m3971            PEX1  -A21        A01X+067697Y+125472X0180Y         S1      
317m3972            VIA   -    MD0080PA01X+119016Y+108642X0160Y         S0      
327m3972            PEX2  -BF36       A01X+119016Y+108642X0180Y         S1      
317m3972            VIA   -    MD0100PA01X+111985Y+049064X0200Y    R180 S0      
327m3972            J24   -A31        A01X+111355Y+049116X0140Y0480R270 S1      
317m3973            VIA   -    MD0080PA01X+169587Y+111634X0160Y    R270 S0      
317m3973            VIA   -    MD0100PA01X+162796Y+051856X0200Y         S0      
327m3973            J27   -A33        A01X+164156Y+051908X0140Y0480R090 S1      
327m3973            PEX3  -AV49       A01X+169587Y+111634X0180Y         S1      
317NIC7_SLOT_ID0    VIA   -    M      A01X+167035Y+039791X0200Y         S2      
017NIC7_SLOT_ID0    VIA   -    M      A18X+167035Y+039791X0260Y         S2      
017NIC7_SLOT_ID0          -    MD0100PA00X+167035Y+039791                       
327NIC7_SLOT_ID0    J27   -OB7        A01X+165968Y+039622X0140Y0480R090 S1      
327NIC7_SLOT_ID0    R383  -1          A18X+167497Y+039392X0198Y0197R180 S2      
327NIC7_SLOT_ID0    R382  -1   M      A18X+167497Y+039791X0198Y0197R180 S2      
327m3974            J22   -B27        A01X+063836Y+051404X0140Y0480R270 S1      
327m3974            C250  -2          A01X+060238Y+051342X0120Y0150     S1      
317m3975            VIA   -    MD0100PA01X+048052Y+136010X0180Y         S0      
317m3975            J12   -O5   D0122PA01X+049098Y+150980X0282Y    R180 S3      
327m3975            C365  -2          A01X+048062Y+135519X0120Y0150R090 S1      
327m3976            J24   -B60        A01X+109544Y+040569X0140Y0480R270 S1      
327m3976            C481  -2          A01X+106987Y+040507X0120Y0150     S1      
317m3977            VIA   -    MD0080PA01X+169213Y+113130X0160Y    R270 S0      
317m3977            VIA   -    MD0100PA01X+162796Y+047782X0200Y         S0      
327m3977            J27   -A21        A01X+164156Y+047730X0140Y0480R090 S1      
327m3977            PEX3  -AP48       A01X+169213Y+113130X0180Y         S1      
327NIC7_SLOT_ID1    VIA   -    M      A01X+161622Y+039386X0300Y    R180 S1      
327NIC7_SLOT_ID1    R384  -1          A01X+160510Y+039672X0198Y0197R180 S1      
327NIC7_SLOT_ID1    R385  -1   M      A01X+160510Y+039272X0198Y0197R180 S1      
327NIC7_SLOT_ID1    J27   -OA6        A01X+164156Y+039386X0140Y0480R090 S1      
317m3978            VIA   -    MD0080PA01X+072933Y+107894X0160Y         S0      
327m3978            PEX1  -BH35       A01X+072933Y+107894X0180Y         S1      
317m3978            VIA   -    MD0100PA01X+067007Y+048355X0200Y    R180 S0      
327m3978            J22   -A34        A01X+065647Y+048408X0140Y0480R270 S1      
317m3979            J12   -U8   D0122PA01X+051697Y+147831X0282Y    R180 S3      
317m3979            VIA   -    MD0080PA01X+068445Y+125098X0160Y         S0      
327m3979            PEX1  -B23        A01X+068445Y+125098X0180Y         S1      
327m3980            J24   -B53        A01X+109544Y+042222X0140Y0480R270 S1      
327m3980            C478  -2          A01X+106987Y+042285X0120Y0150     S1      
317m3981            VIA   -    MD0080PA01X+169587Y+108268X0160Y    R270 S0      
327m3981            PEX3  -BG49       A01X+169587Y+108268X0180Y         S1      
317m3981            VIA   -    MD0100PA01X+163526Y+056151X0200Y         S0      
327m3981            J27   -A44        A01X+164156Y+056203X0140Y0480R090 S1      
317NCSI_NIC7_RXD1   VIA   -    M      A01X+166526Y+039858X0200Y         S2      
017NCSI_NIC7_RXD1   VIA   -    M      A18X+166526Y+039858X0260Y         S2      
017NCSI_NIC7_RXD1         -    MD0100PA00X+166526Y+039858                       
327NCSI_NIC7_RXD1   J27   -OB8        A01X+165968Y+039858X0140Y0480R090 S1      
327NCSI_NIC7_RXD1   R374  -1          A18X+167497Y+040192X0198Y0197R180 S2      
327m3982            J22   -B37        A01X+063836Y+047699X0140Y0480R270 S1      
327m3982            C256  -2          A01X+061278Y+047640X0120Y0150     S1      
317m3983            J12   -U1   D0122PA01X+045634Y+147910X0282Y    R180 S3      
317m3983            VIA   -    MD0080PA01X+065827Y+124724X0160Y         S0      
327m3983            PEX1  -C16        A01X+065827Y+124724X0180Y         S1      
327m3984            J27   -B45        A01X+165968Y+056439X0140Y0480R090 S1      
327m3984            C648  -2          A01X+168525Y+056498X0120Y0150R180 S1      
327m3985            R250  -1          A01X+111915Y+065316X0198Y0197R090 S1      
317m3985            VIA   -    MD0100PA00X+111532Y+064645X0200Y         S0      
317m3985            VIA   -    M      A01X+111885Y+055168X0200Y    R180 S2      
017m3985            VIA   -    M      A18X+111885Y+055168X0260Y    R180 S2      
017m3985                  -    MD0100PA00X+111885Y+055168                       
327m3985            J24   -A11        A01X+111355Y+055183X0140Y0480R270 S1      
327PRSNT_SSD12_N    J42   -A12        A01X+141325Y+009996X0150Y0500R090 S1      
317PRSNT_SSD12_N    VIA   -    M      A01X+140631Y+010341X0200Y         S2      
017PRSNT_SSD12_N    VIA   -    M      A18X+140631Y+010341X0260Y         S2      
017PRSNT_SSD12_N          -    MD0100PA00X+140631Y+010341                       
327PRSNT_SSD12_N    R4077 -2          A01X+140323Y+010341X0198Y0197R270 S1      
317m3986            VIA   -    MD0080PA01X+070315Y+108642X0160Y         S0      
327m3986            J22   -A57        A01X+065647Y+041278X0140Y0480R270 S1      
317m3986            VIA   -    MD0100PA01X+066277Y+041226X0200Y    R180 S0      
327m3986            PEX1  -BF28       A01X+070315Y+108642X0180Y         S1      
317m3987            VIA   -    MD0100PA01X+045604Y+138430X0180Y         S0      
317m3987            J12   -B2   D0122PA01X+046500Y+161650X0282Y    R180 S3      
327m3987            C343  -2          A01X+045614Y+137939X0120Y0150R090 S1      
317m3988            J13   -L1   D0122PA01X+130508Y+156610X0282Y    R180 S3      
317m3988            VIA   -    MD0080PA01X+114528Y+124724X0160Y         S0      
327m3988            PEX2  -C24        A01X+114528Y+124724X0180Y         S1      
327m3989            J27   -B33        A01X+165968Y+051908X0140Y0480R090 S1      
327m3989            C655  -2          A01X+169565Y+051845X0120Y0150R180 S1      
327PRSNTB1_NIC7_N   VIA   -    M      A01X+162735Y+054271X0300Y    R180 S1      
327PRSNTB1_NIC7_N   R397  -2          A01X+162272Y+054671X0198Y0197     S1      
327PRSNTB1_NIC7_N   R362  -1   M      A01X+162272Y+054271X0198Y0197R180 S1      
327PRSNTB1_NIC7_N   J27   -A42        A01X+164156Y+054034X0140Y0480R090 S1      
327m3990            J22   -B18        A01X+063836Y+053530X0140Y0480R270 S1      
327m3990            C244  -2          A01X+061278Y+053471X0120Y0150     S1      
317m3991            J12   -I2   D0122PA01X+046500Y+158067X0282Y    R180 S3      
317m3991            VIA   -    MD0080PA01X+063209Y+125098X0160Y         S0      
327m3991            PEX1  -B9         A01X+063209Y+125098X0180Y         S1      
317m3992            J13   -L5   D0122PA01X+133972Y+156610X0282Y    R180 S3      
317m3992            VIA   -    MD0080PA01X+116024Y+124724X0160Y         S0      
327m3992            PEX2  -C28        A01X+116024Y+124724X0180Y         S1      
317m3993            VIA   -    MD0080PA01X+167716Y+108642X0160Y         S0      
327m3993            PEX3  -BF44       A01X+167716Y+108642X0180Y         S1      
317m3993            VIA   -    MD0100PA01X+163526Y+059326X0200Y         S0      
327m3993            J27   -A57        A01X+164156Y+059274X0140Y0480R090 S1      
317m3994            J14   -L6   D0122PA01X+152161Y+156532X0282Y    R180 S3      
317m3994            VIA   -    MD0080PA01X+162106Y+125098X0160Y    R090 S0      
327m3994            PEX3  -B29        A01X+162106Y+125098X0180Y         S1      
327m3995            J22   -B23        A01X+063836Y+052348X0140Y0480R270 S1      
327m3995            C249  -2          A01X+061278Y+052413X0120Y0150     S1      
317m3996            J12   -P1   D0122PA01X+045634Y+150468X0282Y    R180 S3      
327m3996            C356  -2          A01X+044030Y+137939X0120Y0150R090 S1      
317m3996            VIA   -    MD0100PA01X+044040Y+138430X0180Y         S0      
327m3997            J27   -B18        A01X+165968Y+047022X0140Y0480R090 S1      
327m3997            C664  -2          A01X+168525Y+047081X0120Y0150R180 S1      
317m3998            VIA   -    MD0100PA01X+154705Y+140850X0180Y         S0      
317m3998            J14   -F4   D0122PA01X+150429Y+159602X0282Y    R180 S3      
327m3998            C754  -2          A01X+154695Y+140359X0120Y0150R090 S1      
327NIC4_BIF1_N      VIA   -    M      A01X+107316Y+055937X0300Y         S1      
327NIC4_BIF1_N      R235  -1          A01X+106144Y+055856X0198Y0197R180 S1      
327NIC4_BIF1_N      R236  -1   M      A01X+106529Y+055856X0198Y0197     S1      
327NIC4_BIF1_N      J24   -B8         A01X+109544Y+055892X0140Y0480R270 S1      
317m3999            VIA   -    M      A01X+163244Y+045226X0200Y         S2      
017m3999            VIA   -    M      A18X+163244Y+045226X0260Y         S2      
017m3999                  -    MD0100PA00X+163244Y+045226                       
327m3999            R394  -1          A01X+162354Y+045387X0198Y0197R180 S1      
327m3999            J27   -A9         A01X+164156Y+044896X0140Y0480R090 S1      
317m4000            VIA   -    MD0080PA01X+069193Y+107520X0160Y         S0      
327m4000            J22   -A65        A01X+065647Y+039388X0140Y0480R270 S1      
317m4000            VIA   -    MD0100PA01X+067007Y+039440X0200Y    R180 S0      
327m4000            PEX1  -BJ25       A01X+069193Y+107520X0180Y         S1      
317m4001            VIA   -    MD0100PA01X+046828Y+136010X0180Y         S0      
317m4001            J12   -C3   D0122PA01X+047366Y+161217X0282Y    R180 S3      
327m4001            C345  -2          A01X+046838Y+135519X0120Y0150R090 S1      
317m4002            VIA   -    MD0100PA01X+123373Y+138430X0180Y         S0      
317m4002            J13   -F1   D0122PA01X+130508Y+159681X0282Y    R180 S3      
327m4002            C550  -2          A01X+123383Y+137939X0120Y0150R090 S1      
327m4003            J27   -B51        A01X+165968Y+057856X0140Y0480R090 S1      
327m4003            C644  -2          A01X+168525Y+057915X0120Y0150R180 S1      
317m4004            J14   -M1   D0122PA01X+147831Y+156098X0282Y    R180 S3      
317m4004            VIA   -    MD0080PA01X+160236Y+124350X0160Y         S0      
327m4004            PEX3  -D24        A01X+160236Y+124350X0180Y         S1      
327NIC7_BIF0_N      J27   -B7         A01X+165968Y+044423X0140Y0480R090 S1      
317NIC7_BIF0_N      VIA   -    M      A01X+165004Y+043516X0200Y         S2      
017NIC7_BIF0_N      VIA   -    M      A18X+165004Y+043516X0260Y         S2      
017NIC7_BIF0_N            -    MD0100PA00X+165004Y+043516                       
327NIC7_BIF0_N      R387  -1   M      A18X+161923Y+042702X0198Y0197R180 S2      
327NIC7_BIF0_N      R386  -1          A18X+161534Y+042703X0198Y0197     S2      
327m4005            J22   -B62        A01X+063836Y+040096X0140Y0480R270 S1      
327m4005            C273  -2          A01X+060478Y+040161X0120Y0150     S1      
317m4006            J12   -T8   D0122PA01X+051697Y+148343X0282Y    R180 S3      
317m4006            VIA   -    MD0080PA01X+068445Y+125472X0160Y         S0      
327m4006            PEX1  -A23        A01X+068445Y+125472X0180Y         S1      
317m4007            VIA   -    MD0080PA01X+169213Y+112382X0160Y    R270 S0      
317m4007            VIA   -    MD0100PA01X+162796Y+049200X0200Y         S0      
327m4007            J27   -A27        A01X+164156Y+049148X0140Y0480R090 S1      
327m4007            PEX3  -AT48       A01X+169213Y+112382X0180Y         S1      
317m4008            J14   -K4   D0122PA01X+150429Y+157043X0282Y    R180 S3      
317m4008            VIA   -    MD0080PA01X+161358Y+125472X0160Y    R090 S0      
327m4008            PEX3  -A27        A01X+161358Y+125472X0180Y         S1      
327NIC4_SLOT_ID0    VIA   -    M      A01X+107239Y+060619X0300Y         S1      
327NIC4_SLOT_ID0    J24   -OB7        A01X+109544Y+060929X0140Y0480R270 S1      
327NIC4_SLOT_ID0    R230  -1          A01X+106772Y+060759X0198Y0197R180 S1      
327NIC4_SLOT_ID0    R229  -1   M      A01X+106775Y+060360X0198Y0197R180 S1      
317m4009            VIA   -    M      A01X+166926Y+040900X0200Y         S2      
017m4009            VIA   -    M      A18X+166926Y+040900X0260Y         S2      
017m4009                  -    MD0100PA00X+166926Y+040900                       
327m4009            J27   -OB14       A01X+165968Y+041276X0140Y0480R090 S1      
327m4009            R372  -1          A18X+167497Y+040992X0198Y0197R180 S2      
317m4010            VIA   -    MD0080PA01X+074055Y+108268X0160Y         S0      
327m4010            PEX1  -BG38       A01X+074055Y+108268X0180Y         S1      
317m4010            VIA   -    MD0100PA01X+066277Y+052400X0200Y    R180 S0      
327m4010            J22   -A23        A01X+065647Y+052348X0140Y0480R270 S1      
317m4011            J13   -L6   D0122PA01X+134839Y+156532X0282Y    R180 S3      
317m4011            VIA   -    MD0080PA01X+116398Y+125098X0160Y    R090 S0      
327m4011            PEX2  -B29        A01X+116398Y+125098X0180Y         S1      
317m4012            VIA   -    MD0080PA01X+168464Y+111260X0160Y    R270 S0      
317m4012            VIA   -    MD0100PA01X+163526Y+052904X0200Y         S0      
327m4012            J27   -A37        A01X+164156Y+052852X0140Y0480R090 S1      
327m4012            PEX3  -AW46       A01X+168464Y+111260X0180Y         S1      
317m4013            VIA   -    MD0100PA01X+153481Y+136010X0180Y         S0      
317m4013            J14   -S1   D0122PA01X+147831Y+148933X0282Y    R180 S3      
327m4013            C744  -2          A01X+153471Y+135519X0120Y0150R090 S1      
317NIC4_SLOT_ID1    VIA   -    M      A01X+111791Y+061259X0200Y         S2      
017NIC4_SLOT_ID1    VIA   -    M      A18X+111791Y+061259X0260Y         S2      
017NIC4_SLOT_ID1          -    MD0100PA00X+111791Y+061259                       
327NIC4_SLOT_ID1    R232  -1          A18X+111085Y+061440X0198Y0197     S2      
327NIC4_SLOT_ID1    R231  -1   M      A18X+111085Y+061040X0198Y0197     S2      
327NIC4_SLOT_ID1    J24   -OA6        A01X+111355Y+061165X0140Y0480R270 S1      
327PRSNTB3_NIC7_N   VIA   -    M      A01X+168202Y+062291X0300Y    R180 S1      
327PRSNTB3_NIC7_N   J27   -B70        A01X+165968Y+062344X0140Y0480R090 S1      
327PRSNTB3_NIC7_N   R399  -2          A01X+168677Y+062691X0198Y0197R180 S1      
327PRSNTB3_NIC7_N   R365  -1   M      A01X+168677Y+062291X0198Y0197     S1      
317m4014            VIA   -    MD0080PA01X+071063Y+108642X0160Y         S0      
327m4014            J22   -A51        A01X+065647Y+042695X0140Y0480R270 S1      
317m4014            VIA   -    MD0100PA01X+066277Y+042643X0200Y    R180 S0      
327m4014            PEX1  -BF30       A01X+071063Y+108642X0180Y         S1      
317m4015            VIA   -    MD0100PA01X+047712Y+140850X0180Y         S0      
327m4015            C366  -2          A01X+047702Y+140359X0120Y0150R090 S1      
317m4015            J12   -O6   D0122PA01X+049965Y+150902X0282Y    R180 S3      
317m4016            VIA   -    MD0100PA01X+127045Y+140850X0180Y         S0      
317m4016            J13   -E6   D0122PA01X+134839Y+160114X0282Y    R180 S3      
327m4016            C540  -2          A01X+127055Y+140359X0120Y0150R090 S1      
327m4017            J27   -B50        A01X+165968Y+057620X0140Y0480R090 S1      
327m4017            C645  -2          A01X+168525Y+057555X0120Y0150R180 S1      
317m4018            VIA   -    MD0100PA01X+152257Y+140850X0180Y         S0      
317m4018            J14   -G1   D0122PA01X+147831Y+159169X0282Y    R180 S3      
327m4018            C760  -2          A01X+152247Y+140359X0120Y0150R090 S1      
327m4019            VIA   -    M      A01X+107319Y+059139X0300Y         S1      
327m4019            J24   -OB14       A01X+109544Y+059276X0140Y0480R270 S1      
327m4019            R219  -1          A01X+106772Y+059159X0198Y0197R180 S1      
317m4020            VIA   -    MD0080PA01X+072185Y+107894X0160Y         S0      
327m4020            J22   -A40        A01X+065647Y+046990X0140Y0480R270 S1      
317m4020            VIA   -    MD0100PA01X+067007Y+046938X0200Y    R180 S0      
327m4020            PEX1  -BH33       A01X+072185Y+107894X0180Y         S1      
317m4021            J12   -U5   D0122PA01X+049098Y+147910X0282Y    R180 S3      
317m4021            VIA   -    MD0080PA01X+067323Y+124724X0160Y         S0      
327m4021            PEX1  -C20        A01X+067323Y+124724X0180Y         S1      
317m4022            VIA   -    MD0080PA01X+116772Y+124724X0160Y         S0      
327m4022            PEX2  -C30        A01X+116772Y+124724X0180Y         S1      
317m4022            J13   -L7   D0122PA01X+135705Y+156610X0282Y    R180 S3      
327m4023            J27   -B30        A01X+165968Y+051199X0140Y0480R090 S1      
327m4023            C657  -2          A01X+168525Y+051134X0120Y0150R180 S1      
317m4024            J14   -X8   D0122PA01X+153894Y+146295X0282Y    R180 S3      
317m4024            VIA   -    MD0080PA01X+165846Y+125098X0160Y    R090 S0      
327m4024            PEX3  -B39        A01X+165846Y+125098X0180Y         S1      
327m4025            VIA   -    M      A01X+112817Y+062540X0300Y         S1      
327m4025            J24   -OA1        A01X+111355Y+062346X0140Y0480R270 S1      
327m4025            R251  -1          A01X+113300Y+062540X0198Y0197     S1      
317m4026            VIA   -    MD0080PA01X+070315Y+108268X0160Y         S0      
327m4026            J22   -A56        A01X+065647Y+041514X0140Y0480R270 S1      
317m4026            VIA   -    MD0100PA01X+066277Y+041566X0200Y    R180 S0      
327m4026            PEX1  -BG28       A01X+070315Y+108268X0180Y         S1      
317m4027            VIA   -    MD0100PA01X+046488Y+140850X0180Y         S0      
317m4027            J12   -C4   D0122PA01X+048232Y+161138X0282Y    R180 S3      
327m4027            C346  -2          A01X+046478Y+140359X0120Y0150R090 S1      
317m4028            VIA   -    MD0080PA01X+168464Y+112756X0160Y    R270 S0      
327m4028            PEX3  -AR46       A01X+168464Y+112756X0180Y         S1      
317m4028            VIA   -    MD0100PA01X+163526Y+048491X0200Y         S0      
327m4028            J27   -A24        A01X+164156Y+048439X0140Y0480R090 S1      
317m4029            J14   -W4   D0122PA01X+150429Y+146807X0282Y    R180 S3      
317m4029            VIA   -    MD0080PA01X+164350Y+125472X0160Y    R090 S0      
327m4029            PEX3  -A35        A01X+164350Y+125472X0180Y         S1      
327m4030            U28   -1          A18X+112663Y+055189X0240Y0240R180 S2      
327m4030            R207  -1   M      A18X+110498Y+054497X0198Y0197R180 S2      
317m4030            VIA   -    M      A01X+109950Y+054553X0200Y         S2      
017m4030            VIA   -    M      A18X+109950Y+054553X0260Y         S2      
017m4030                  -    MD0100PA00X+109950Y+054553                       
327m4030            J24   -B12        A01X+109544Y+054947X0140Y0480R270 S1      
327m4031            C262  -2          A01X+061278Y+043342X0120Y0150     S1      
327m4031            J22   -B48        A01X+063836Y+043404X0140Y0480R270 S1      
317m4032            VIA   -    MD0080PA01X+063583Y+124350X0160Y         S0      
327m4032            PEX1  -D10        A01X+063583Y+124350X0180Y         S1      
317m4032            J12   -J3   D0122PA01X+047366Y+157634X0282Y    R180 S3      
317m4033            J13   -K2   D0122PA01X+131374Y+157043X0282Y    R180 S3      
317m4033            VIA   -    MD0080PA01X+114902Y+125472X0160Y    R090 S0      
327m4033            PEX2  -A25        A01X+114902Y+125472X0180Y         S1      
327m4034            J27   -B66        A01X+165968Y+061400X0140Y0480R090 S1      
327m4034            C634  -2          A01X+169565Y+061461X0120Y0150R180 S1      
317m4035            VIA   -    MD0100PA01X+153821Y+138430X0180Y         S0      
317m4035            J14   -E2   D0122PA01X+148697Y+160114X0282Y    R180 S3      
327m4035            C759  -2          A01X+153831Y+137939X0120Y0150R090 S1      
317m4036            VIA   -    M      A01X+111763Y+061840X0200Y         S2      
017m4036            VIA   -    M      A18X+111763Y+061840X0260Y         S2      
017m4036                  -    MD0100PA00X+111763Y+061840                       
327m4036            J24   -OA4        A01X+111355Y+061638X0140Y0480R270 S1      
327m4036            R205  -2          A18X+111085Y+061840X0198Y0197R180 S2      
327m4037            J22   -B63        A01X+063836Y+039860X0140Y0480R270 S1      
327m4037            C272  -2          A01X+060478Y+039801X0120Y0150     S1      
317m4038            VIA   -    MD0080PA01X+167342Y+107894X0160Y         S0      
327m4038            PEX3  -BH43       A01X+167342Y+107894X0180Y         S1      
317m4038            VIA   -    MD0100PA01X+162796Y+060034X0200Y         S0      
327m4038            J27   -A60        A01X+164156Y+059982X0140Y0480R090 S1      
317m4039            VIA   -    MD0100PA01X+155045Y+140850X0180Y         S0      
317m4039            J14   -E4   D0122PA01X+150429Y+160114X0282Y    R180 S3      
327m4039            C755  -2          A01X+155055Y+140359X0120Y0150R090 S1      
327PRSNTB3_NIC4_N   VIA   -    M      A01X+107310Y+038260X0300Y         S1      
327PRSNTB3_NIC4_N   R246  -2          A01X+106835Y+037860X0198Y0197     S1      
327PRSNTB3_NIC4_N   J24   -B70        A01X+109544Y+038207X0140Y0480R270 S1      
327PRSNTB3_NIC4_N   R212  -1   M      A01X+106835Y+038260X0198Y0197R180 S1      
317m4040            VIA   -    MD0100PA01X+066277Y+052060X0200Y    R180 S0      
327m4040            J22   -A24        A01X+065647Y+052112X0140Y0480R270 S1      
317m4040            VIA   -    MD0080PA01X+074055Y+108642X0160Y         S0      
327m4040            PEX1  -BF38       A01X+074055Y+108642X0180Y         S1      
317m4041            J12   -D1   D0122PA01X+045634Y+160705X0282Y    R180 S3      
327m4041            C340  -2          A01X+044030Y+135519X0120Y0150R090 S1      
317m4041            VIA   -    MD0100PA01X+044040Y+136010X0180Y         S0      
327m4042            J27   -B39        A01X+165968Y+053325X0140Y0480R090 S1      
327m4042            C651  -2          A01X+169565Y+053262X0120Y0150R180 S1      
317m4043            VIA   -    MD0100PA01X+152597Y+140850X0180Y         S0      
317m4043            J14   -F1   D0122PA01X+147831Y+159681X0282Y    R180 S3      
327m4043            C761  -2          A01X+152607Y+140359X0120Y0150R090 S1      
327NIC4_DATA_IN     VIA   -    M      A01X+107322Y+062100X0300Y         S1      
327NIC4_DATA_IN     J24   -OB4        A01X+109544Y+061638X0140Y0480R270 S1      
327NIC4_DATA_IN     R216  -1          A01X+106775Y+061960X0198Y0197R180 S1      
317m4044            VIA   -    MD0100PA01X+021298Y+048695X0200Y    R180 S0      
327m4044            J20   -A33        A01X+019938Y+048644X0140Y0480R270 S1      
317m4044            VIA   -    MD0080PA01X+027224Y+107520X0160Y         S0      
327m4044            PEX0  -BJ35       A01X+027224Y+107520X0180Y         S1      
317m4045            VIA   -    MD0080PA01X+074803Y+108642X0160Y         S0      
327m4045            PEX1  -BF40       A01X+074803Y+108642X0180Y         S1      
327m4045            J22   -A18        A01X+065647Y+053530X0140Y0480R270 S1      
317m4045            VIA   -    MD0100PA01X+066277Y+053478X0200Y         S0      
317m4046            J12   -U4   D0122PA01X+048232Y+147831X0282Y    R180 S3      
317m4046            VIA   -    MD0080PA01X+066949Y+125098X0160Y         S0      
327m4046            PEX1  -B19        A01X+066949Y+125098X0180Y         S1      
317m4047            VIA   -    MD0100PA01X+124257Y+136010X0180Y         S0      
317m4047            J13   -F2   D0122PA01X+131374Y+159602X0282Y    R180 S3      
327m4047            C547  -2          A01X+124247Y+135519X0120Y0150R090 S1      
327m4048            J27   -B20        A01X+165968Y+047494X0140Y0480R090 S1      
327m4048            C663  -2          A01X+169565Y+047432X0120Y0150R180 S1      
317m4049            VIA   -    MD0100PA01X+157493Y+138430X0180Y         S0      
317m4049            J14   -Q6   D0122PA01X+152161Y+149878X0282Y    R180 S3      
327m4049            C735  -2          A01X+157503Y+137939X0120Y0150R090 S1      
317m4050            VIA   -    MD0100PA01X+021298Y+047278X0200Y    R180 S0      
327m4050            J20   -A39        A01X+019938Y+047226X0140Y0480R270 S1      
317m4050            VIA   -    MD0080PA01X+026476Y+107520X0160Y         S0      
327m4050            PEX0  -BJ33       A01X+026476Y+107520X0180Y         S1      
317m4051            VIA   -    MD0080PA01X+071437Y+107894X0160Y         S0      
327m4051            J22   -A48        A01X+065647Y+043404X0140Y0480R270 S1      
317m4051            VIA   -    MD0100PA01X+067007Y+043352X0200Y    R180 S0      
327m4051            PEX1  -BH31       A01X+071437Y+107894X0180Y         S1      
317m4052            VIA   -    MD0100PA01X+046488Y+138430X0180Y         S0      
327m4052            C362  -2          A01X+046478Y+137939X0120Y0150R090 S1      
317m4052            J12   -O4   D0122PA01X+048232Y+150902X0282Y    R180 S3      
317m4053            VIA   -    MD0080PA01X+168838Y+112008X0160Y    R270 S0      
317m4053            VIA   -    MD0100PA01X+163526Y+051147X0200Y         S0      
327m4053            J27   -A30        A01X+164156Y+051199X0140Y0480R090 S1      
327m4053            PEX3  -AU47       A01X+168838Y+112008X0180Y         S1      
317m4054            VIA   -    MD0100PA01X+158377Y+136010X0180Y         S0      
317m4054            J14   -S7   D0122PA01X+153028Y+148933X0282Y    R180 S3      
327m4054            C732  -2          A01X+158367Y+135519X0120Y0150R090 S1      
317NCSI_NIC4_TXD0   VIA   -    M      A01X+112217Y+060457X0200Y         S2      
017NCSI_NIC4_TXD0   VIA   -    M      A18X+112217Y+060457X0260Y         S2      
017NCSI_NIC4_TXD0         -    MD0100PA00X+112217Y+060457                       
327NCSI_NIC4_TXD0   R222  -1          A18X+111085Y+059840X0198Y0197     S2      
327NCSI_NIC4_TXD0   J24   -OA9        A01X+111355Y+060457X0140Y0480R270 S1      
327m4055            J20   -B37        A01X+018127Y+047699X0140Y0480R270 S1      
327m4055            C45   -2          A01X+015570Y+047640X0120Y0150     S1      
317m4056            VIA   -    MD0080PA01X+071811Y+108642X0160Y         S0      
327m4056            J22   -A45        A01X+065647Y+044112X0140Y0480R270 S1      
317m4056            VIA   -    MD0100PA01X+066277Y+044060X0200Y    R180 S0      
327m4056            PEX1  -BF32       A01X+071811Y+108642X0180Y         S1      
317m4057            VIA   -    MD0080PA01X+169587Y+113130X0160Y    R270 S0      
317m4057            VIA   -    MD0100PA01X+162796Y+047442X0200Y         S0      
327m4057            J27   -A20        A01X+164156Y+047494X0140Y0480R090 S1      
327m4057            PEX3  -AP49       A01X+169587Y+113130X0180Y         S1      
317m4058            J14   -K8   D0122PA01X+153894Y+157043X0282Y    R180 S3      
317m4058            VIA   -    MD0080PA01X+162854Y+125472X0160Y    R090 S0      
327m4058            PEX3  -A31        A01X+162854Y+125472X0180Y         S1      
327PRSNTB2_NIC4_N   VIA   -    M      A01X+112784Y+054947X0300Y         S1      
327PRSNTB2_NIC4_N   J24   -A12        A01X+111355Y+054947X0140Y0480R270 S1      
327PRSNTB2_NIC4_N   R245  -2          A01X+113260Y+054580X0198Y0197R180 S1      
327PRSNTB2_NIC4_N   R211  -1   M      A01X+113260Y+054980X0198Y0197     S1      
327m4059            J20   -B36        A01X+018127Y+047935X0140Y0480R270 S1      
327m4059            C46   -2          A01X+015570Y+048000X0120Y0150     S1      
317m4060            VIA   -    MD0080PA01X+073307Y+108642X0160Y         S0      
327m4060            PEX1  -BF36       A01X+073307Y+108642X0180Y         S1      
317m4060            VIA   -    MD0100PA01X+066277Y+049064X0200Y    R180 S0      
327m4060            J22   -A31        A01X+065647Y+049116X0140Y0480R270 S1      
317m4061            VIA   -    MD0100PA01X+045604Y+136010X0180Y         S0      
317m4061            J12   -N2   D0122PA01X+046500Y+151413X0282Y    R180 S3      
327m4061            C359  -2          A01X+045614Y+135519X0120Y0150R090 S1      
317m4062            VIA   -    MD0080PA01X+117146Y+125098X0160Y    R090 S0      
317m4062            J13   -L8   D0122PA01X+136571Y+156532X0282Y    R180 S3      
327m4062            PEX2  -B31        A01X+117146Y+125098X0180Y         S1      
327m4063            J27   -B34        A01X+165968Y+052144X0140Y0480R090 S1      
327m4063            C654  -2          A01X+169565Y+052205X0120Y0150R180 S1      
317m4064            J14   -L1   D0122PA01X+147831Y+156610X0282Y    R180 S3      
317m4064            VIA   -    MD0080PA01X+160236Y+124724X0160Y         S0      
327m4064            PEX3  -C24        A01X+160236Y+124724X0180Y         S1      
327NIC4_CLK         VIA   -    M      A01X+107322Y+061113X0300Y         S1      
327NIC4_CLK         R218  -1          A01X+106775Y+061160X0198Y0197R180 S1      
327NIC4_CLK         J24   -OB6        A01X+109544Y+061165X0140Y0480R270 S1      
327m4065            J20   -B63        A01X+018127Y+039860X0140Y0480R270 S1      
327m4065            C61   -2          A01X+014770Y+039801X0120Y0150     S1      
327m4066            J22   -B24        A01X+063836Y+052112X0140Y0480R270 S1      
327m4066            C248  -2          A01X+061278Y+052053X0120Y0150     S1      
317m4067            J12   -I4   D0122PA01X+048232Y+158067X0282Y    R180 S3      
317m4067            VIA   -    MD0080PA01X+063957Y+125098X0160Y         S0      
327m4067            PEX1  -B11        A01X+063957Y+125098X0180Y         S1      
317m4068            VIA   -    MD0100PA01X+123033Y+138430X0180Y         S0      
317m4068            J13   -G1   D0122PA01X+130508Y+159169X0282Y    R180 S3      
327m4068            C549  -2          A01X+123023Y+137939X0120Y0150R090 S1      
317m4069            VIA   -    MD0080PA01X+168838Y+107520X0160Y         S0      
327m4069            PEX3  -BJ47       A01X+168838Y+107520X0180Y         S1      
317m4069            VIA   -    MD0100PA01X+162796Y+056860X0200Y         S0      
327m4069            J27   -A47        A01X+164156Y+056911X0140Y0480R090 S1      
317m4070            VIA   -    MD0100PA01X+156269Y+140850X0180Y         S0      
317m4070            J14   -R5   D0122PA01X+151295Y+149445X0282Y    R180 S3      
327m4070            C737  -2          A01X+156279Y+140359X0120Y0150R090 S1      
327m4071            C50   -2          A01X+014530Y+044413X0120Y0150     S1      
327m4071            J20   -B44        A01X+018127Y+044348X0140Y0480R270 S1      
317m4072            VIA   -    MD0080PA01X+070689Y+107894X0160Y         S0      
327m4072            J22   -A54        A01X+065647Y+041986X0140Y0480R270 S1      
317m4072            VIA   -    MD0100PA01X+067007Y+041934X0200Y    R180 S0      
327m4072            PEX1  -BH29       A01X+070689Y+107894X0180Y         S1      
317m4073            VIA   -    MD0100PA01X+129153Y+136010X0180Y         S0      
317m4073            J13   -F8   D0122PA01X+136571Y+159602X0282Y    R180 S3      
327m4073            C535  -2          A01X+129143Y+135519X0120Y0150R090 S1      
327m4074            J27   -B48        A01X+165968Y+057148X0140Y0480R090 S1      
327m4074            C646  -2          A01X+169565Y+057209X0120Y0150R180 S1      
317m4075            J14   -W8   D0122PA01X+153894Y+146807X0282Y    R180 S3      
317m4075            VIA   -    MD0080PA01X+165846Y+125472X0160Y    R090 S0      
327m4075            PEX3  -A39        A01X+165846Y+125472X0180Y         S1      
327m4076            VIA   -    M      A01X+112786Y+055460X0300Y         S1      
327m4076            J24   -A9         A01X+111355Y+055656X0140Y0480R270 S1      
327m4076            R241  -1          A01X+114120Y+054970X0198Y0197     S1      
327m4077            J20   -B17        A01X+018127Y+053766X0140Y0480R270 S1      
327m4077            C34   -2          A01X+015570Y+053831X0120Y0150     S1      
327m4078            C275  -2          A01X+061278Y+039450X0120Y0150     S1      
327m4078            J22   -B65        A01X+063836Y+039388X0140Y0480R270 S1      
317m4079            J12   -U7   D0122PA01X+050831Y+147910X0282Y    R180 S3      
317m4079            VIA   -    MD0080PA01X+068071Y+124724X0160Y         S0      
327m4079            PEX1  -C22        A01X+068071Y+124724X0180Y         S1      
317m4080            VIA   -    MD0080PA01X+168838Y+107894X0160Y         S0      
327m4080            PEX3  -BH47       A01X+168838Y+107894X0180Y         S1      
317m4080            VIA   -    MD0100PA01X+162796Y+057200X0200Y         S0      
327m4080            J27   -A48        A01X+164156Y+057148X0140Y0480R090 S1      
317m4081            J14   -X3   D0122PA01X+149563Y+146374X0282Y    R180 S3      
317m4081            VIA   -    MD0080PA01X+163976Y+124724X0160Y         S0      
327m4081            PEX3  -C34        A01X+163976Y+124724X0180Y         S1      
317m4082            VIA   -    M      A01X+031226Y+032452X0200Y         S2      
017m4082            VIA   -    M      A18X+031226Y+032452X0260Y         S2      
017m4082                  -    MD0100PA00X+031226Y+032452                       
327m4082            Q2    -6          A01X+030731Y+032185X0170Y0240R270 S1      
327m4082            R102  -1   M      A01X+031226Y+032189X0198Y0197R270 S1      
327m4082            U16   -1          A01X+032027Y+032884X0220Y0530R090 S1      
327m4083            C57   -2          A01X+014530Y+041219X0120Y0150     S1      
327m4083            J20   -B57        A01X+018127Y+041278X0140Y0480R270 S1      
327m4084            J22   -B34        A01X+063836Y+048408X0140Y0480R270 S1      
327m4084            C254  -2          A01X+060238Y+048346X0120Y0150     S1      
317m4085            J12   -H2   D0122PA01X+046500Y+158579X0282Y    R180 S3      
317m4085            VIA   -    MD0080PA01X+063209Y+125472X0160Y         S0      
327m4085            PEX1  -A9         A01X+063209Y+125472X0180Y         S1      
327m4086            J27   -B21        A01X+165968Y+047730X0140Y0480R090 S1      
327m4086            C662  -2          A01X+169565Y+047792X0120Y0150R180 S1      
317m4087            VIA   -    MD0100PA01X+155045Y+138430X0180Y         S0      
317m4087            J14   -R3   D0122PA01X+149563Y+149445X0282Y    R180 S3      
327m4087            C741  -2          A01X+155055Y+137939X0120Y0150R090 S1      
327NCSI_NIC4_RXD0   VIA   -    M      A01X+107237Y+059632X0300Y         S1      
327NCSI_NIC4_RXD0   J24   -OB9        A01X+109544Y+060457X0140Y0480R270 S1      
327NCSI_NIC4_RXD0   R220  -1          A01X+106772Y+059559X0198Y0197R180 S1      
317m4088            VIA   -    MD0100PA01X+020568Y+052060X0200Y    R180 S0      
327m4088            J20   -A24        A01X+019938Y+052112X0140Y0480R270 S1      
317m4088            VIA   -    MD0080PA01X+028346Y+108642X0160Y         S0      
327m4088            PEX0  -BF38       A01X+028346Y+108642X0180Y         S1      
327m4089            C263  -2          A01X+061278Y+043702X0120Y0150     S1      
327m4089            J22   -B47        A01X+063836Y+043640X0140Y0480R270 S1      
317m4090            J12   -U3   D0122PA01X+047366Y+147910X0282Y    R180 S3      
317m4090            VIA   -    MD0080PA01X+066575Y+124724X0160Y         S0      
327m4090            PEX1  -C18        A01X+066575Y+124724X0180Y         S1      
327m4091            J27   -B37        A01X+165968Y+052852X0140Y0480R090 S1      
327m4091            C652  -2          A01X+168525Y+052911X0120Y0150R180 S1      
317m4092            VIA   -    MD0100PA01X+158717Y+138430X0180Y         S0      
317m4092            J14   -E8   D0122PA01X+153894Y+160114X0282Y    R180 S3      
327m4092            C747  -2          A01X+158727Y+137939X0120Y0150R090 S1      
317m4093            VIA   -    M      A01X+112267Y+059550X0200Y         S2      
017m4093            VIA   -    M      A18X+112267Y+059550X0260Y         S2      
017m4093                  -    MD0100PA00X+112267Y+059550                       
327m4093            J24   -OA14       A01X+111355Y+059276X0140Y0480R270 S1      
327m4093            R224  -1          A18X+111085Y+059440X0198Y0197     S2      
327m4094            J20   -B34        A01X+018127Y+048408X0140Y0480R270 S1      
327m4094            C43   -2          A01X+014530Y+048346X0120Y0150     S1      
327m4095            J22   -B31        A01X+063836Y+049116X0140Y0480R270 S1      
327m4095            C252  -2          A01X+061278Y+049057X0120Y0150     S1      
317m4096            J12   -T2   D0122PA01X+046500Y+148343X0282Y    R180 S3      
317m4096            VIA   -    MD0080PA01X+066201Y+125472X0160Y         S0      
327m4096            PEX1  -A17        A01X+066201Y+125472X0180Y         S1      
317m4097            VIA   -    MD0080PA01X+168090Y+107894X0160Y         S0      
327m4097            PEX3  -BH45       A01X+168090Y+107894X0180Y         S1      
317m4097            VIA   -    MD0100PA01X+162796Y+058617X0200Y         S0      
327m4097            J27   -A54        A01X+164156Y+058565X0140Y0480R090 S1      
317m4098            VIA   -    MD0100PA01X+158717Y+140850X0180Y         S0      
317m4098            J14   -Q8   D0122PA01X+153894Y+149878X0282Y    R180 S3      
327m4098            C731  -2          A01X+158727Y+140359X0120Y0150R090 S1      
317RST_HP_NIC1_N    VIA   -    M      A01X+029772Y+033956X0200Y         S2      
017RST_HP_NIC1_N    VIA   -    M      A18X+029772Y+033956X0260Y         S2      
017RST_HP_NIC1_N          -    MD0100PA00X+029772Y+033956                       
327RST_HP_NIC1_N    U15   -2          A01X+030328Y+034488X0160Y0360R270 S1      
327RST_HP_NIC1_N    U16   -4          A01X+031063Y+033632X0220Y0530R090 S1      
327PRSNTB0_NIC4_N   VIA   -    M      A01X+107319Y+046518X0300Y         S1      
327PRSNTB0_NIC4_N   R243  -2          A01X+106835Y+045960X0198Y0197     S1      
327PRSNTB0_NIC4_N   J24   -B42        A01X+109544Y+046518X0140Y0480R270 S1      
327PRSNTB0_NIC4_N   R209  -1   M      A01X+106835Y+046360X0198Y0197R180 S1      
317m4099            VIA   -    MD0100PA01X+021298Y+046938X0200Y    R180 S0      
327m4099            J20   -A40        A01X+019938Y+046990X0140Y0480R270 S1      
317m4099            VIA   -    MD0080PA01X+026476Y+107894X0160Y         S0      
327m4099            PEX0  -BH33       A01X+026476Y+107894X0180Y         S1      
327m4100            J22   -B33        A01X+063836Y+048644X0140Y0480R270 S1      
327m4100            C255  -2          A01X+060238Y+048706X0120Y0150     S1      
317m4101            VIA   -    MD0100PA01X+045264Y+138430X0180Y         S0      
317m4101            J12   -C2   D0122PA01X+046500Y+161138X0282Y    R180 S3      
327m4101            C342  -2          A01X+045254Y+137939X0120Y0150R090 S1      
317m4102            VIA   -    MD0080PA01X+168090Y+107520X0160Y         S0      
327m4102            PEX3  -BJ45       A01X+168090Y+107520X0180Y         S1      
317m4102            VIA   -    MD0100PA01X+162796Y+058277X0200Y         S0      
327m4102            J27   -A53        A01X+164156Y+058329X0140Y0480R090 S1      
317m4103            J14   -L5   D0122PA01X+151295Y+156610X0282Y    R180 S3      
317m4103            VIA   -    MD0080PA01X+161732Y+124724X0160Y         S0      
327m4103            PEX3  -C28        A01X+161732Y+124724X0180Y         S1      
327m4104            VIA   -    M      A01X+107320Y+063089X0300Y         S1      
327m4104            J24   -OB2        A01X+109544Y+062110X0140Y0480R270 S1      
327m4104            R206  -1          A01X+106775Y+062760X0198Y0197R180 S1      
327m4105            C58   -2          A01X+014530Y+041579X0120Y0150     S1      
327m4105            J20   -B56        A01X+018127Y+041514X0140Y0480R270 S1      
317m4106            VIA   -    MD0080PA01X+069941Y+107520X0160Y         S0      
327m4106            J22   -A59        A01X+065647Y+040805X0140Y0480R270 S1      
317m4106            VIA   -    MD0100PA01X+067007Y+040857X0200Y    R180 S0      
327m4106            PEX1  -BJ27       A01X+069941Y+107520X0180Y         S1      
317m4107            VIA   -    MD0100PA01X+045264Y+140850X0180Y         S0      
317m4107            J12   -P3   D0122PA01X+047366Y+150468X0282Y    R180 S3      
327m4107            C360  -2          A01X+045254Y+140359X0120Y0150R090 S1      
317m4108            VIA   -    MD0080PA01X+168464Y+108642X0160Y         S0      
327m4108            PEX3  -BF46       A01X+168464Y+108642X0180Y         S1      
317m4108            VIA   -    MD0100PA01X+163526Y+057908X0200Y         S0      
327m4108            J27   -A51        A01X+164156Y+057856X0140Y0480R090 S1      
317m4109            J14   -W6   D0122PA01X+152161Y+146807X0282Y    R180 S3      
317m4109            VIA   -    MD0080PA01X+165098Y+125472X0160Y    R090 S0      
327m4109            PEX3  -A37        A01X+165098Y+125472X0180Y         S1      
317NCSI_NIC4_TXD1   VIA   -    M      A01X+111767Y+060693X0200Y         S2      
017NCSI_NIC4_TXD1   VIA   -    M      A18X+111767Y+060693X0260Y         S2      
017NCSI_NIC4_TXD1         -    MD0100PA00X+111767Y+060693                       
327NCSI_NIC4_TXD1   R223  -1          A18X+111085Y+060240X0198Y0197     S2      
327NCSI_NIC4_TXD1   J24   -OA8        A01X+111355Y+060693X0140Y0480R270 S1      
317m4110            VIA   -    MD0100PA01X+021298Y+040857X0200Y    R180 S0      
327m4110            J20   -A59        A01X+019938Y+040805X0140Y0480R270 S1      
317m4110            VIA   -    MD0080PA01X+024232Y+107520X0160Y         S0      
327m4110            PEX0  -BJ27       A01X+024232Y+107520X0180Y         S1      
327m4111            C265  -2          A01X+060238Y+042996X0120Y0150     S1      
327m4111            J22   -B50        A01X+063836Y+042931X0140Y0480R270 S1      
317m4112            J12   -V5   D0122PA01X+049098Y+147398X0282Y    R180 S3      
317m4112            VIA   -    MD0080PA01X+067323Y+124350X0160Y         S0      
327m4112            PEX1  -D20        A01X+067323Y+124350X0180Y         S1      
327m4113            J27   -B23        A01X+165968Y+048203X0140Y0480R090 S1      
327m4113            C661  -2          A01X+168525Y+048138X0120Y0150R180 S1      
317m4114            VIA   -    MD0100PA01X+153481Y+140850X0180Y         S0      
317m4114            J14   -R2   D0122PA01X+148697Y+149366X0282Y    R180 S3      
327m4114            C742  -2          A01X+153471Y+140359X0120Y0150R090 S1      
317m4115            VIA   -    M      A01X+112327Y+061632X0200Y         S2      
017m4115            VIA   -    M      A18X+112327Y+061632X0260Y         S2      
017m4115                  -    MD0100PA00X+112327Y+061632                       
327m4115            R205  -1          A18X+110770Y+061840X0198Y0197R180 S2      
327m4115            J24   -OA5        A01X+111355Y+061402X0140Y0480R270 S1      
317m4116            VIA   -    MD0100PA01X+021298Y+043692X0200Y    R180 S0      
327m4116            J20   -A47        A01X+019938Y+043640X0140Y0480R270 S1      
317m4116            VIA   -    MD0080PA01X+025728Y+107520X0160Y         S0      
327m4116            PEX0  -BJ31       A01X+025728Y+107520X0180Y         S1      
327m4117            C271  -2          A01X+061278Y+040867X0120Y0150     S1      
327m4117            J22   -B59        A01X+063836Y+040805X0140Y0480R270 S1      
317m4118            VIA   -    MD0080PA01X+168464Y+112008X0160Y    R270 S0      
317m4118            VIA   -    MD0100PA01X+163526Y+051487X0200Y         S0      
327m4118            J27   -A31        A01X+164156Y+051435X0140Y0480R090 S1      
327m4118            PEX3  -AU46       A01X+168464Y+112008X0180Y         S1      
317m4119            J14   -Y5   D0122PA01X+151295Y+145862X0282Y    R180 S3      
317m4119            VIA   -    MD0080PA01X+164724Y+124350X0160Y         S0      
327m4119            PEX3  -D36        A01X+164724Y+124350X0180Y         S1      
327NIC4_BIF2_N      VIA   -    M      A01X+107322Y+055267X0300Y         S1      
327NIC4_BIF2_N      R237  -1          A01X+106144Y+055456X0198Y0197R180 S1      
327NIC4_BIF2_N      R238  -1   M      A01X+106529Y+055456X0198Y0197     S1      
327NIC4_BIF2_N      J24   -B9         A01X+109544Y+055656X0140Y0480R270 S1      
327m4120            J20   -B21        A01X+018127Y+052821X0140Y0480R270 S1      
327m4120            C35   -2          A01X+014530Y+052759X0120Y0150     S1      
327m4121            J22   -B26        A01X+063836Y+051640X0140Y0480R270 S1      
327m4121            C251  -2          A01X+060238Y+051702X0120Y0150     S1      
317m4122            VIA   -    MD0080PA01X+109665Y+107894X0160Y    R270 S0      
327m4122            J38   -A21        A01X+095616Y+012122X0150Y0500R090 S1      
317m4122            VIA   -    MD0100PA01X+094256Y+012174X0200Y         S0      
327m4122            PEX2  -BH11       A01X+109665Y+107894X0180Y         S1      
317m4123            VIA   -    MD0080PA01X+166594Y+107894X0160Y         S0      
317m4123            VIA   -    MD0100PA01X+162796Y+061452X0200Y         S0      
327m4123            J27   -A66        A01X+164156Y+061400X0140Y0480R090 S1      
327m4123            PEX3  -BH41       A01X+166594Y+107894X0180Y         S1      
317m4124            VIA   -    MD0100PA01X+157153Y+138430X0180Y         S0      
317m4124            J14   -R6   D0122PA01X+152161Y+149366X0282Y    R180 S3      
327m4124            C734  -2          A01X+157143Y+137939X0120Y0150R090 S1      
327NIC4_BIF0_N      VIA   -    M      A01X+107316Y+056437X0300Y         S1      
327NIC4_BIF0_N      R233  -1          A01X+106144Y+056256X0198Y0197R180 S1      
327NIC4_BIF0_N      R234  -1   M      A01X+106532Y+056257X0198Y0197     S1      
327NIC4_BIF0_N      J24   -B7         A01X+109544Y+056128X0140Y0480R270 S1      
327m4125            C64   -2          A01X+015570Y+039450X0120Y0150     S1      
327m4125            J20   -B65        A01X+018127Y+039388X0140Y0480R270 S1      
317m4126            VIA   -    MD0100PA01X+067007Y+051692X0200Y    R180 S0      
327m4126            J22   -A26        A01X+065647Y+051640X0140Y0480R270 S1      
317m4126            VIA   -    MD0080PA01X+073681Y+107520X0160Y         S0      
327m4126            PEX1  -BJ37       A01X+073681Y+107520X0180Y         S1      
317m4127            VIA   -    MD0080PA01X+113780Y+108268X0160Y    R270 S0      
327m4127            PEX2  -BG22       A01X+113780Y+108268X0180Y         S1      
327m4127            J41   -A23        A01X+126325Y+012594X0150Y0500R090 S1      
317m4127            VIA   -    MD0100PA01X+125695Y+012543X0200Y         S0      
327m4128            J27   -A63        A01X+164156Y+060691X0140Y0480R090 S1      
317m4128            VIA   -    MD0100PA01X+163526Y+060743X0200Y         S0      
317m4128            VIA   -    MD0080PA01X+166968Y+108642X0160Y         S0      
327m4128            PEX3  -BF42       A01X+166968Y+108642X0180Y         S1      
317m4129            J14   -L8   D0122PA01X+153894Y+156532X0282Y    R180 S3      
317m4129            VIA   -    MD0080PA01X+162854Y+125098X0160Y    R090 S0      
327m4129            PEX3  -B31        A01X+162854Y+125098X0180Y         S1      
317m4130            VIA   -    M      A01X+112333Y+061007X0200Y         S2      
017m4130            VIA   -    M      A18X+112333Y+061007X0260Y         S2      
017m4130                  -    MD0100PA00X+112333Y+061007                       
327m4130            R225  -1          A18X+111085Y+060640X0198Y0197     S2      
327m4130            J24   -OA7        A01X+111355Y+060929X0140Y0480R270 S1      
317P3V3_SSD13       VIA   -    MD0100PA00X+150582Y+023871X0200Y    R090 S0      
327P3V3_SSD13       R897  -1          A01X+150582Y+023613X0198Y0197R270 S1      
327P3V3_SSD13       PU65  -1          A01X+149583Y+021324X0110Y0240     S1      
327P3V3_SSD13       PU65  -2          A01X+149780Y+021324X0110Y0240     S1      
327P3V3_SSD13       PU65  -3          A01X+149977Y+021324X0110Y0240     S1      
327P3V3_SSD13       PU65  -4          A01X+150174Y+021324X0110Y0240     S1      
327P3V3_SSD13       PU65  -5          A01X+150370Y+021324X0110Y0240     S1      
327P3V3_SSD13       VIA   -           A18X+149919Y+019873X0260Y         S2      
327P3V3_SSD13       PC563 -1          A01X+149937Y+020064X0400Y0500     S1      
327P3V3_SSD13       PC562 -1          A01X+149830Y+020686X0198Y0197R180 S1      
327P3V3_SSD13       PD71  -C          A01X+150415Y+018984X0670Y0990R090 S1      
317P3V3_SSD13       VIA   -    MD0100PA00X+150354Y+020681X0200Y    R180 S0      
317P3V3_SSD13       VIA   -    MD0100PA00X+150177Y+021051X0200Y    R180 S0      
317P3V3_SSD13       VIA   -    MD0100PA00X+150104Y+020681X0200Y    R180 S0      
317P3V3_SSD13       VIA   -    MD0100PA00X+149927Y+021051X0200Y    R180 S0      
317P3V3_SSD13       VIA   -    MD0100PA00X+150321Y+020175X0200Y    R090 S0      
317P3V3_SSD13       VIA   -    MD0100PA00X+150621Y+020205X0200Y    R090 S0      
317P3V3_SSD13       VIA   -    MD0100PA00X+150419Y+019518X0200Y    R180 S0      
317P3V3_SSD13       VIA   -    MD0100PA00X+149919Y+019518X0200Y    R180 S0      
317P3V3_SSD13       VIA   -    MD0100PA00X+150321Y+019925X0200Y    R090 S0      
317P3V3_SSD13       VIA   -    MD0100PA00X+150169Y+019518X0200Y    R180 S0      
317P3V3_SSD13       VIA   -    M      A01X+150621Y+019925X0200Y    R090 S2      
017P3V3_SSD13       VIA   -    M      A18X+150621Y+019925X0260Y    R090 S2      
017P3V3_SSD13             -    MD0100PA00X+150621Y+019925                       
317P3V3_SSD13       VIA   -    MD0100PA00X+150669Y+019518X0200Y    R180 S0      
317P3V3_SSD13       VIA   -    MD0100PA00X+144268Y+014754X0200Y         S0      
327P3V3_SSD13       R6111 -1          A01X+144546Y+014754X0198Y0197     S1      
317P3V3_SSD13       VIA   -    MD0100PA00X+155028Y+010378X0200Y    R270 S0      
327P3V3_SSD13       R448  -1          A01X+155028Y+010135X0198Y0197R270 S1      
317P3V3_SSD13       VIA   -    MD0100PA00X+155722Y+010619X0200Y    R090 S0      
327P3V3_SSD13       R5753 -1          A01X+155979Y+010824X0198Y0197R270 S1      
327P3V3_SSD13       R5696 -2          A01X+149604Y+013484X0198Y0197     S1      
327P3V3_SSD13       PC966 -1   M      A01X+149486Y+011967X0400Y0500R090 S1      
327P3V3_SSD13       PU132 -6_7        A01X+148605Y+011762X0295Y0354R270 S1      
317P3V3_SSD13       VIA   -    MD0100PA00X+149059Y+011959X0200Y         S0      
317P3V3_SSD13       VIA   -    MD0100PA00X+149059Y+011659X0200Y         S0      
327P3V3_SSD13       J43   -B11        A01X+153372Y+009760X0150Y0500R090 S1      
317P3V3_SSD13       VIA   -    MD0100PA00X+154673Y+009855X0200Y    R090 S0      
327P3V3_SSD13       C978  -2   M      A01X+154420Y+009855X0198Y0197R270 S1      
317P3V3_SSD13       VIA   -    M      A01X+150021Y+009767X0200Y         S2      
017P3V3_SSD13       VIA   -    M      A18X+150021Y+009767X0260Y         S2      
017P3V3_SSD13             -    MD0100PA00X+150021Y+009767                       
327P3V3_SSD13       R450  -1          A01X+150264Y+009767X0198Y0197     S1      
317P3V3_SSD13       VIA   -    MD0100PA00X+157075Y+008058X0200Y         S0      
327P3V3_SSD13       R1720 -1          A01X+156833Y+008058X0198Y0197R180 S1      
317P3V3_SSD13       VIA   -    MD0100PA00X+157073Y+006858X0200Y         S0      
327P3V3_SSD13       R1719 -1          A01X+156833Y+006858X0198Y0197R180 S1      
317P3V3_SSD13       VIA   -    MD0100PA00X+157190Y+005801X0200Y         S0      
327P3V3_SSD13       U139  -1          A01X+157425Y+006472X0240Y0460R180 S1      
327P3V3_SSD13       C2738 -2   M      A01X+157451Y+005801X0198Y0197R180 S1      
317m4131            VIA   -    MD0100PA01X+021298Y+051352X0200Y    R180 S0      
327m4131            J20   -A27        A01X+019938Y+051404X0140Y0480R270 S1      
317m4131            VIA   -    MD0080PA01X+027972Y+107894X0160Y         S0      
327m4131            PEX0  -BH37       A01X+027972Y+107894X0180Y         S1      
317m4132            VIA   -    MD0080PA01X+072559Y+108642X0160Y         S0      
327m4132            PEX1  -BF34       A01X+072559Y+108642X0180Y         S1      
317m4132            VIA   -    MD0100PA01X+066277Y+047647X0200Y    R180 S0      
327m4132            J22   -A37        A01X+065647Y+047699X0140Y0480R270 S1      
327m4133            J41   -B21        A01X+128136Y+012122X0150Y0500R090 S1      
327m4133            C515  -2          A01X+130066Y+012184X0120Y0150R180 S1      
327m4134            J27   -B47        A01X+165968Y+056911X0140Y0480R090 S1      
327m4134            C647  -2          A01X+169565Y+056849X0120Y0150R180 S1      
317m4135            J14   -M3   D0122PA01X+149563Y+156098X0282Y    R180 S3      
317m4135            VIA   -    MD0080PA01X+160984Y+124350X0160Y         S0      
327m4135            PEX3  -D26        A01X+160984Y+124350X0180Y         S1      
327m4136            VIA   -    M      A01X+112817Y+061950X0300Y         S1      
327m4136            J24   -OA2        A01X+111355Y+062110X0140Y0480R270 S1      
327m4136            R252  -1          A01X+113300Y+062140X0198Y0197     S1      
327P3V3_SSD12       R895  -1          A01X+140346Y+023613X0198Y0197R270 S1      
317P3V3_SSD12       VIA   -    MD0100PA00X+140346Y+023871X0200Y    R090 S0      
327P3V3_SSD12       PU63  -1          A01X+139347Y+021324X0110Y0240     S1      
327P3V3_SSD12       PU63  -2          A01X+139544Y+021324X0110Y0240     S1      
327P3V3_SSD12       PU63  -3          A01X+139741Y+021324X0110Y0240     S1      
327P3V3_SSD12       PU63  -4          A01X+139937Y+021324X0110Y0240     S1      
327P3V3_SSD12       PU63  -5          A01X+140134Y+021324X0110Y0240     S1      
327P3V3_SSD12       VIA   -           A18X+139683Y+019873X0260Y         S2      
327P3V3_SSD12       PC551 -1          A01X+139700Y+020064X0400Y0500     S1      
327P3V3_SSD12       PC550 -1          A01X+139593Y+020686X0198Y0197R180 S1      
327P3V3_SSD12       PD69  -C          A01X+140179Y+018984X0670Y0990R090 S1      
317P3V3_SSD12       VIA   -    MD0100PA00X+140384Y+020205X0200Y    R090 S0      
317P3V3_SSD12       VIA   -    MD0100PA00X+139691Y+021051X0200Y    R180 S0      
317P3V3_SSD12       VIA   -    MD0100PA00X+139941Y+021051X0200Y    R180 S0      
317P3V3_SSD12       VIA   -    MD0100PA00X+140118Y+020681X0200Y    R180 S0      
317P3V3_SSD12       VIA   -    MD0100PA00X+139868Y+020681X0200Y    R180 S0      
317P3V3_SSD12       VIA   -    MD0100PA00X+140084Y+020175X0200Y    R090 S0      
317P3V3_SSD12       VIA   -    MD0100PA00X+140433Y+019518X0200Y    R180 S0      
317P3V3_SSD12       VIA   -    MD0100PA00X+140183Y+019518X0200Y    R180 S0      
317P3V3_SSD12       VIA   -    M      A01X+140384Y+019925X0200Y    R090 S2      
017P3V3_SSD12       VIA   -    M      A18X+140384Y+019925X0260Y    R090 S2      
017P3V3_SSD12             -    MD0100PA00X+140384Y+019925                       
317P3V3_SSD12       VIA   -    MD0100PA00X+140084Y+019925X0200Y    R090 S0      
317P3V3_SSD12       VIA   -    MD0100PA00X+139683Y+019518X0200Y    R180 S0      
317P3V3_SSD12       VIA   -    MD0100PA00X+139933Y+019518X0200Y    R180 S0      
327P3V3_SSD12       R6110 -1          A01X+134310Y+014754X0198Y0197     S1      
317P3V3_SSD12       VIA   -    MD0100PA00X+134032Y+014754X0200Y         S0      
327P3V3_SSD12       R5751 -1          A01X+145742Y+010824X0198Y0197R270 S1      
317P3V3_SSD12       VIA   -    MD0100PA00X+145486Y+010619X0200Y    R090 S0      
327P3V3_SSD12       R445  -1          A01X+144792Y+010135X0198Y0197R270 S1      
317P3V3_SSD12       VIA   -    MD0100PA00X+144792Y+010378X0200Y    R270 S0      
317P3V3_SSD12       VIA   -    MD0100PA00X+138823Y+011659X0200Y         S0      
317P3V3_SSD12       VIA   -    MD0100PA00X+138823Y+011959X0200Y         S0      
327P3V3_SSD12       PU131 -6_7        A01X+138369Y+011762X0295Y0354R270 S1      
327P3V3_SSD12       PC962 -1   M      A01X+139250Y+011967X0400Y0500R090 S1      
327P3V3_SSD12       R5699 -2          A01X+139368Y+013484X0198Y0197     S1      
327P3V3_SSD12       C977  -2   M      A01X+144184Y+009855X0198Y0197R270 S1      
317P3V3_SSD12       VIA   -    MD0100PA00X+144437Y+009855X0200Y    R090 S0      
327P3V3_SSD12       J42   -B11        A01X+143136Y+009760X0150Y0500R090 S1      
327P3V3_SSD12       R446  -1          A01X+140028Y+009767X0198Y0197     S1      
317P3V3_SSD12       VIA   -    M      A01X+139785Y+009767X0200Y         S2      
017P3V3_SSD12       VIA   -    M      A18X+139785Y+009767X0260Y         S2      
017P3V3_SSD12             -    MD0100PA00X+139785Y+009767                       
327P3V3_SSD12       R1717 -1          A01X+146597Y+008058X0198Y0197R180 S1      
317P3V3_SSD12       VIA   -    MD0100PA00X+146838Y+008058X0200Y         S0      
327P3V3_SSD12       R1716 -1          A01X+146597Y+006858X0198Y0197R180 S1      
317P3V3_SSD12       VIA   -    MD0100PA00X+146837Y+006858X0200Y         S0      
327P3V3_SSD12       U138  -1          A01X+147189Y+006472X0240Y0460R180 S1      
327P3V3_SSD12       C2736 -2   M      A01X+147215Y+005801X0198Y0197R180 S1      
317P3V3_SSD12       VIA   -    MD0100PA00X+147215Y+005551X0200Y         S0      
317m4137            VIA   -    MD0100PA01X+020568Y+039808X0200Y    R180 S0      
327m4137            J20   -A63        A01X+019938Y+039860X0140Y0480R270 S1      
317m4137            VIA   -    MD0080PA01X+023858Y+108642X0160Y         S0      
327m4137            PEX0  -BF26       A01X+023858Y+108642X0180Y         S1      
317m4138            VIA   -    MD0080PA01X+069567Y+108642X0160Y         S0      
327m4138            J22   -A63        A01X+065647Y+039860X0140Y0480R270 S1      
317m4138            VIA   -    MD0100PA01X+066277Y+039808X0200Y    R180 S0      
327m4138            PEX1  -BF26       A01X+069567Y+108642X0180Y         S1      
327m4139            C494  -2          A01X+098317Y+011112X0120Y0150R180 S1      
327m4139            J38   -B17        A01X+097427Y+011177X0150Y0500R090 S1      
327m4140            J27   -B54        A01X+165968Y+058565X0140Y0480R090 S1      
327m4140            C642  -2          A01X+169565Y+058626X0120Y0150R180 S1      
317m4141            J14   -M5   D0122PA01X+151295Y+156098X0282Y    R180 S3      
317m4141            VIA   -    MD0080PA01X+161732Y+124350X0160Y         S0      
327m4141            PEX3  -D28        A01X+161732Y+124350X0180Y         S1      
327NIC4_LD_N        VIA   -    M      A01X+107239Y+062595X0300Y         S1      
327NIC4_LD_N        J24   -OB3        A01X+109544Y+061874X0140Y0480R270 S1      
327NIC4_LD_N        R215  -1          A01X+106775Y+062360X0198Y0197R180 S1      
327m4142            J20   -B62        A01X+018127Y+040096X0140Y0480R270 S1      
327m4142            C62   -2          A01X+014770Y+040161X0120Y0150     S1      
327m4143            J22   -B20        A01X+063836Y+053057X0140Y0480R270 S1      
327m4143            C247  -2          A01X+060238Y+053119X0120Y0150     S1      
327m4144            C503  -2          A01X+119830Y+013601X0120Y0150R180 S1      
327m4144            J40   -B27        A01X+117900Y+013539X0150Y0500R090 S1      
317m4145            VIA   -    MD0080PA01X+168464Y+113504X0160Y    R270 S0      
327m4145            PEX3  -AN46       A01X+168464Y+113504X0180Y         S1      
317m4145            VIA   -    MD0100PA01X+163526Y+047074X0200Y         S0      
327m4145            J27   -A18        A01X+164156Y+047022X0140Y0480R090 S1      
317m4146            J14   -K2   D0122PA01X+148697Y+157043X0282Y    R180 S3      
317m4146            VIA   -    MD0080PA01X+160610Y+125472X0160Y    R090 S0      
327m4146            PEX3  -A25        A01X+160610Y+125472X0180Y         S1      
327NIC1_SLOT_ID1    VIA   -    M      A01X+024496Y+039386X0300Y    R180 S1      
327NIC1_SLOT_ID1    R78   -1          A01X+023384Y+039672X0198Y0197R180 S1      
327NIC1_SLOT_ID1    R79   -1   M      A01X+023384Y+039272X0198Y0197R180 S1      
327NIC1_SLOT_ID1    J21   -OA6        A01X+027030Y+039386X0140Y0480R090 S1      
317m4147            VIA   -    MD0100PA01X+020568Y+047647X0200Y    R180 S0      
327m4147            J20   -A37        A01X+019938Y+047699X0140Y0480R270 S1      
317m4147            VIA   -    MD0080PA01X+026850Y+108642X0160Y         S0      
327m4147            PEX0  -BF34       A01X+026850Y+108642X0180Y         S1      
327m4148            J22   -B39        A01X+063836Y+047226X0140Y0480R270 S1      
327m4148            C259  -2          A01X+060238Y+047289X0120Y0150     S1      
317m4149            VIA   -    MD0080PA01X+114154Y+107894X0160Y    R270 S0      
327m4149            PEX2  -BH23       A01X+114154Y+107894X0180Y         S1      
327m4149            J41   -A21        A01X+126325Y+012122X0150Y0500R090 S1      
317m4149            VIA   -    MD0100PA01X+124965Y+012174X0200Y         S0      
327m4150            J27   -B31        A01X+165968Y+051435X0140Y0480R090 S1      
327m4150            C656  -2          A01X+168525Y+051494X0120Y0150R180 S1      
317m4151            VIA   -    MD0100PA01X+157153Y+136010X0180Y         S0      
317m4151            J14   -F6   D0122PA01X+152161Y+159602X0282Y    R180 S3      
327m4151            C750  -2          A01X+157143Y+135519X0120Y0150R090 S1      
327m4152            VIA   -    M      A01X+024614Y+038788X0300Y    R180 S1      
327m4152            J21   -OA4        A01X+027030Y+038913X0140Y0480R090 S1      
327m4152            R52   -2          A01X+023384Y+038872X0198Y0197     S1      
327m4153            J20   -B18        A01X+018127Y+053530X0140Y0480R270 S1      
327m4153            C33   -2          A01X+015570Y+053471X0120Y0150     S1      
317m4154            VIA   -    MD0080PA01X+069941Y+107894X0160Y         S0      
327m4154            J22   -A60        A01X+065647Y+040569X0140Y0480R270 S1      
317m4154            VIA   -    MD0100PA01X+067007Y+040517X0200Y    R180 S0      
327m4154            PEX1  -BH27       A01X+069941Y+107894X0180Y         S1      
327m4155            C489  -2          A01X+098317Y+012890X0120Y0150R180 S1      
327m4155            J38   -B24        A01X+097427Y+012831X0150Y0500R090 S1      
327m4156            J27   -B65        A01X+165968Y+061163X0140Y0480R090 S1      
327m4156            C635  -2          A01X+169565Y+061101X0120Y0150R180 S1      
317m4157            J14   -X7   D0122PA01X+153028Y+146374X0282Y    R180 S3      
317m4157            VIA   -    MD0080PA01X+165472Y+124724X0160Y         S0      
327m4157            PEX3  -C38        A01X+165472Y+124724X0180Y         S1      
327m4158            VIA   -    M      A01X+025200Y+038472X0300Y    R180 S1      
327m4158            R99   -1          A01X+023384Y+038472X0198Y0197R180 S1      
327m4158            J21   -OA2        A01X+027030Y+038441X0140Y0480R090 S1      
327PRSNTB1_NIC4_N   VIA   -    M      A01X+112777Y+046280X0300Y         S1      
327PRSNTB1_NIC4_N   J24   -A42        A01X+111355Y+046518X0140Y0480R270 S1      
327PRSNTB1_NIC4_N   R244  -2          A01X+113240Y+045880X0198Y0197R180 S1      
327PRSNTB1_NIC4_N   R210  -1   M      A01X+113240Y+046280X0198Y0197     S1      
317m4159            VIA   -    MD0100PA01X+021298Y+048355X0200Y    R180 S0      
327m4159            J20   -A34        A01X+019938Y+048408X0140Y0480R270 S1      
317m4159            VIA   -    MD0080PA01X+027224Y+107894X0160Y         S0      
327m4159            PEX0  -BH35       A01X+027224Y+107894X0180Y         S1      
327m4160            C268  -2          A01X+060238Y+041219X0120Y0150     S1      
327m4160            J22   -B57        A01X+063836Y+041278X0140Y0480R270 S1      
317m4161            VIA   -    MD0080PA01X+113780Y+108642X0160Y    R270 S0      
327m4161            PEX2  -BF22       A01X+113780Y+108642X0180Y         S1      
327m4161            J41   -A24        A01X+126325Y+012831X0150Y0500R090 S1      
317m4161            VIA   -    MD0100PA01X+125695Y+012883X0200Y         S0      
317m4162            VIA   -    MD0080PA01X+168464Y+108268X0160Y         S0      
327m4162            PEX3  -BG46       A01X+168464Y+108268X0180Y         S1      
317m4162            VIA   -    MD0100PA01X+163526Y+057568X0200Y         S0      
327m4162            J27   -A50        A01X+164156Y+057620X0140Y0480R090 S1      
317m4163            J14   -L4   D0122PA01X+150429Y+156532X0282Y    R180 S3      
317m4163            VIA   -    MD0080PA01X+161358Y+125098X0160Y    R090 S0      
327m4163            PEX3  -B27        A01X+161358Y+125098X0180Y         S1      
317m4164            VIA   -    M      A01X+111515Y+065012X0200Y         S2      
017m4164            VIA   -    M      A18X+111515Y+065012X0260Y         S2      
017m4164                  -    MD0100PA00X+111515Y+065012                       
327m4164            R249  -1          A01X+111515Y+065316X0198Y0197R090 S1      
317m4164            VIA   -    MD0100PA00X+110824Y+057772X0200Y         S0      
327m4164            J24   -B10        A01X+109544Y+055419X0140Y0480R270 S1      
317m4165            VIA   -    MD0080PA01X+026102Y+108268X0160Y         S0      
327m4165            PEX0  -BG32       A01X+026102Y+108268X0180Y         S1      
317m4165            VIA   -    MD0100PA01X+020568Y+044400X0200Y    R180 S0      
327m4165            J20   -A44        A01X+019938Y+044348X0140Y0480R270 S1      
317m4166            VIA   -    MD0080PA01X+070689Y+107520X0160Y         S0      
327m4166            J22   -A53        A01X+065647Y+042222X0140Y0480R270 S1      
317m4166            VIA   -    MD0100PA01X+067007Y+042274X0200Y    R180 S0      
327m4166            PEX1  -BJ29       A01X+070689Y+107520X0180Y         S1      
327m4167            C492  -2          A01X+099357Y+011824X0120Y0150R180 S1      
327m4167            J38   -B20        A01X+097427Y+011886X0150Y0500R090 S1      
317m4168            VIA   -    MD0080PA01X+167342Y+107520X0160Y         S0      
327m4168            PEX3  -BJ43       A01X+167342Y+107520X0180Y         S1      
317m4168            VIA   -    MD0100PA01X+162796Y+059694X0200Y         S0      
327m4168            J27   -A59        A01X+164156Y+059746X0140Y0480R090 S1      
317m4169            J14   -K6   D0122PA01X+152161Y+157043X0282Y    R180 S3      
317m4169            VIA   -    MD0080PA01X+162106Y+125472X0160Y    R090 S0      
327m4169            PEX3  -A29        A01X+162106Y+125472X0180Y         S1      
327NCSI_NIC4_RXD1   VIA   -    M      A01X+107322Y+060126X0300Y         S1      
327NCSI_NIC4_RXD1   J24   -OB8        A01X+109544Y+060693X0140Y0480R270 S1      
327NCSI_NIC4_RXD1   R221  -1          A01X+106772Y+059959X0198Y0197R180 S1      
317m4170            VIA   -    MD0100PA01X+020568Y+042643X0200Y    R180 S0      
327m4170            J20   -A51        A01X+019938Y+042695X0140Y0480R270 S1      
317m4170            VIA   -    MD0080PA01X+025354Y+108642X0160Y         S0      
327m4170            PEX0  -BF30       A01X+025354Y+108642X0180Y         S1      
317m4171            VIA   -    MD0100PA01X+036742Y+140850X0180Y         S0      
317m4171            J11   -N8   D0122PA01X+034374Y+151413X0282Y    R180 S3      
327m4171            C160  -2          A01X+036752Y+140359X0120Y0150R090 S1      
327m4172            J22   -B30        A01X+063836Y+049352X0140Y0480R270 S1      
327m4172            C253  -2          A01X+061278Y+049417X0120Y0150     S1      
317m4173            VIA   -    MD0080PA01X+113405Y+107520X0160Y    R270 S0      
327m4173            PEX2  -BJ21       A01X+113405Y+107520X0180Y         S1      
327m4173            J41   -A26        A01X+126325Y+013303X0150Y0500R090 S1      
317m4173            VIA   -    MD0100PA01X+124965Y+013252X0200Y         S0      
317m4174            VIA   -    MD0080PA01X+169213Y+108268X0160Y    R270 S0      
327m4174            PEX3  -BG48       A01X+169213Y+108268X0180Y         S1      
317m4174            VIA   -    MD0100PA01X+163526Y+056491X0200Y         S0      
327m4174            J27   -A45        A01X+164156Y+056439X0140Y0480R090 S1      
317m4175            VIA   -    MD0100PA01X+158377Y+140850X0180Y         S0      
317m4175            J14   -R8   D0122PA01X+153894Y+149366X0282Y    R180 S3      
327m4175            C730  -2          A01X+158367Y+140359X0120Y0150R090 S1      
317m4176            VIA   -    M      A01X+029570Y+038205X0200Y         S2      
017m4176            VIA   -    M      A18X+029570Y+038205X0260Y         S2      
017m4176                  -    MD0100PA00X+029570Y+038205                       
327m4176            R55   -1          A18X+027758Y+038450X0198Y0197     S2      
327m4176            R73   -1   M      A18X+028092Y+038450X0198Y0197R180 S2      
327m4176            J21   -OB1        A01X+028842Y+038205X0140Y0480R090 S1      
327NIC4_DATA_OUT    VIA   -    M      A01X+107242Y+061607X0300Y         S1      
327NIC4_DATA_OUT    R217  -1          A01X+106775Y+061560X0198Y0197R180 S1      
327NIC4_DATA_OUT    J24   -OB5        A01X+109544Y+061402X0140Y0480R270 S1      
317m4177            VIA   -    MD0100PA01X+020568Y+041226X0200Y    R180 S0      
327m4177            J20   -A57        A01X+019938Y+041278X0140Y0480R270 S1      
317m4177            VIA   -    MD0080PA01X+024606Y+108642X0160Y         S0      
327m4177            PEX0  -BF28       A01X+024606Y+108642X0180Y         S1      
327m4178            C264  -2          A01X+060238Y+042636X0120Y0150     S1      
327m4178            J22   -B51        A01X+063836Y+042695X0140Y0480R270 S1      
317m4179            VIA   -    MD0080PA01X+113031Y+108268X0160Y    R270 S0      
327m4179            PEX2  -BG20       A01X+113031Y+108268X0180Y         S1      
327m4179            J40   -A17        A01X+116088Y+011177X0150Y0500R090 S1      
317m4179            VIA   -    MD0100PA01X+115458Y+011126X0200Y         S0      
317m4180            VIA   -    MD0080PA01X+169213Y+110886X0160Y    R270 S0      
327m4180            PEX3  -AY48       A01X+169213Y+110886X0180Y         S1      
317m4180            VIA   -    MD0100PA01X+162796Y+053613X0200Y         S0      
327m4180            J27   -A40        A01X+164156Y+053561X0140Y0480R090 S1      
317m4181            J14   -M7   D0122PA01X+153028Y+156098X0282Y    R180 S3      
317m4181            VIA   -    MD0080PA01X+162480Y+124350X0160Y         S0      
327m4181            PEX3  -D30        A01X+162480Y+124350X0180Y         S1      
327m4182            VIA   -    M      A01X+025319Y+039150X0300Y    R180 S1      
327m4182            R52   -1          A01X+023069Y+038872X0198Y0197     S1      
327m4182            J21   -OA5        A01X+027030Y+039150X0140Y0480R090 S1      
327m4183            VIA   -    M      A01X+107273Y+063798X0300Y         S1      
327m4183            R208  -1          A01X+106775Y+064197X0198Y0197R180 S1      
327m4183            R226  -1   M      A01X+106775Y+063797X0198Y0197R180 S1      
327m4183            J24   -OB1        A01X+109544Y+062346X0140Y0480R270 S1      
327m4184            C56   -2          A01X+015570Y+042285X0120Y0150     S1      
327m4184            J20   -B53        A01X+018127Y+042222X0140Y0480R270 S1      
317m4185            VIA   -    MD0080PA01X+074429Y+107894X0160Y         S0      
327m4185            PEX1  -BH39       A01X+074429Y+107894X0180Y         S1      
327m4185            J22   -A21        A01X+065647Y+052821X0140Y0480R270 S1      
317m4185            VIA   -    MD0100PA01X+067007Y+052769X0200Y    R180 S0      
317m4186            VIA   -    MD0080PA01X+113031Y+108642X0160Y    R270 S0      
327m4186            PEX2  -BF20       A01X+113031Y+108642X0180Y         S1      
327m4186            J40   -A18        A01X+116088Y+011413X0150Y0500R090 S1      
317m4186            VIA   -    MD0100PA01X+115458Y+011466X0200Y         S0      
327m4187            J27   -B44        A01X+165968Y+056203X0140Y0480R090 S1      
327m4187            C649  -2          A01X+168525Y+056138X0120Y0150R180 S1      
317m4188            J14   -X5   D0122PA01X+151295Y+146374X0282Y    R180 S3      
317m4188            VIA   -    MD0080PA01X+164724Y+124724X0160Y         S0      
327m4188            PEX3  -C36        A01X+164724Y+124724X0180Y         S1      
327m4189            C63   -2          A01X+015570Y+039090X0120Y0150     S1      
327m4189            J20   -B66        A01X+018127Y+039152X0140Y0480R270 S1      
317m4190            VIA   -    MD0100PA01X+036402Y+140850X0180Y         S0      
317m4190            J11   -O8   D0122PA01X+034374Y+150902X0282Y    R180 S3      
327m4190            C159  -2          A01X+036392Y+140359X0120Y0150R090 S1      
327m4191            J22   -B21        A01X+063836Y+052821X0140Y0480R270 S1      
327m4191            C246  -2          A01X+060238Y+052759X0120Y0150     S1      
317m4192            VIA   -    MD0080PA01X+112283Y+108268X0160Y    R270 S0      
327m4192            J40   -A23        A01X+116088Y+012594X0150Y0500R090 S1      
317m4192            VIA   -    MD0100PA01X+115458Y+012543X0200Y         S0      
327m4192            PEX2  -BG18       A01X+112283Y+108268X0180Y         S1      
327m4193            C640  -2          A01X+168525Y+059332X0120Y0150R180 S1      
327m4193            J27   -B57        A01X+165968Y+059274X0140Y0480R090 S1      
317m4194            J14   -L2   D0122PA01X+148697Y+156532X0282Y    R180 S3      
317m4194            VIA   -    MD0080PA01X+160610Y+125098X0160Y    R090 S0      
327m4194            PEX3  -B25        A01X+160610Y+125098X0180Y         S1      
317NIC1_DATA_OUT    VIA   -    M      A01X+029800Y+039150X0200Y         S2      
017NIC1_DATA_OUT    VIA   -    M      A18X+029800Y+039150X0260Y         S2      
017NIC1_DATA_OUT          -    MD0100PA00X+029800Y+039150                       
327NIC1_DATA_OUT    J21   -OB5        A01X+028842Y+039150X0140Y0480R090 S1      
327NIC1_DATA_OUT    R64   -1          A18X+030371Y+038591X0198Y0197R180 S2      
317m4195            VIA   -    MD0100PA01X+021298Y+051692X0200Y    R180 S0      
327m4195            J20   -A26        A01X+019938Y+051640X0140Y0480R270 S1      
317m4195            VIA   -    MD0080PA01X+027972Y+107520X0160Y         S0      
327m4195            PEX0  -BJ37       A01X+027972Y+107520X0180Y         S1      
317m4196            J11   -J3   D0122PA01X+030043Y+157634X0282Y    R180 S3      
317m4196            VIA   -    MD0080PA01X+017874Y+124350X0160Y         S0      
327m4196            PEX0  -D10        A01X+017874Y+124350X0180Y         S1      
317m4197            VIA   -    MD0080PA01X+069193Y+107894X0160Y         S0      
327m4197            J22   -A66        A01X+065647Y+039152X0140Y0480R270 S1      
317m4197            VIA   -    MD0100PA01X+067007Y+039100X0200Y    R180 S0      
327m4197            PEX1  -BH25       A01X+069193Y+107894X0180Y         S1      
317m4198            VIA   -    MD0080PA01X+111909Y+107520X0160Y    R270 S0      
327m4198            J40   -A26        A01X+116088Y+013303X0150Y0500R090 S1      
317m4198            VIA   -    MD0100PA01X+114728Y+013252X0200Y         S0      
327m4198            PEX2  -BJ17       A01X+111909Y+107520X0180Y         S1      
327m4199            C641  -2          A01X+168525Y+058972X0120Y0150R180 S1      
327m4199            J27   -B56        A01X+165968Y+059037X0140Y0480R090 S1      
317m4200            VIA   -    MD0100PA01X+155929Y+138430X0180Y         S0      
317m4200            J14   -G5   D0122PA01X+151295Y+159169X0282Y    R180 S3      
327m4200            C752  -2          A01X+155919Y+137939X0120Y0150R090 S1      
327NCSI_NIC1_TXD1   VIA   -    M      A01X+024240Y+040472X0300Y    R180 S1      
327NCSI_NIC1_TXD1   J21   -OA8        A01X+027030Y+039858X0140Y0480R090 S1      
327NCSI_NIC1_TXD1   R70   -1          A01X+023384Y+040472X0198Y0197R180 S1      
317m4201            VIA   -    MD0100PA01X+020568Y+052400X0200Y    R180 S0      
327m4201            J20   -A23        A01X+019938Y+052348X0140Y0480R270 S1      
317m4201            VIA   -    MD0080PA01X+028346Y+108268X0160Y         S0      
327m4201            PEX0  -BG38       A01X+028346Y+108268X0180Y         S1      
317m4202            J11   -H2   D0122PA01X+029177Y+158579X0282Y    R180 S3      
317m4202            VIA   -    MD0080PA01X+017500Y+125472X0160Y         S0      
327m4202            PEX0  -A9         A01X+017500Y+125472X0180Y         S1      
327m4203            C509  -2          A01X+118790Y+011472X0120Y0150R180 S1      
327m4203            J40   -B18        A01X+117900Y+011413X0150Y0500R090 S1      
317m4204            VIA   -    MD0080PA01X+169213Y+111634X0160Y    R270 S0      
317m4204            VIA   -    MD0100PA01X+162796Y+052196X0200Y         S0      
327m4204            J27   -A34        A01X+164156Y+052144X0140Y0480R090 S1      
327m4204            PEX3  -AV48       A01X+169213Y+111634X0180Y         S1      
327m4205            VIA   -    M      A01X+025282Y+040072X0300Y    R180 S1      
327m4205            R72   -1          A01X+023384Y+040072X0198Y0197R180 S1      
327m4205            J21   -OA7        A01X+027030Y+039622X0140Y0480R090 S1      
317m4206            VIA   -    MD0100PA01X+020568Y+047987X0200Y    R180 S0      
327m4206            J20   -A36        A01X+019938Y+047935X0140Y0480R270 S1      
317m4206            VIA   -    MD0080PA01X+026850Y+108268X0160Y         S0      
327m4206            PEX0  -BG34       A01X+026850Y+108268X0180Y         S1      
317m4207            J11   -U8   D0122PA01X+034374Y+147831X0282Y    R180 S3      
317m4207            VIA   -    MD0080PA01X+022736Y+125098X0160Y         S0      
327m4207            PEX0  -B23        A01X+022736Y+125098X0180Y         S1      
317m4208            VIA   -    MD0080PA01X+108917Y+107894X0160Y    R270 S0      
327m4208            J38   -A27        A01X+095616Y+013539X0150Y0500R090 S1      
317m4208            VIA   -    MD0100PA01X+094256Y+013592X0200Y         S0      
327m4208            PEX2  -BH9        A01X+108917Y+107894X0180Y         S1      
327m4209            C637  -2          A01X+168525Y+060390X0120Y0150R180 S1      
327m4209            J27   -B62        A01X+165968Y+060455X0140Y0480R090 S1      
317m4210            J14   -X6   D0122PA01X+152161Y+146295X0282Y    R180 S3      
317m4210            VIA   -    MD0080PA01X+165098Y+125098X0160Y    R090 S0      
327m4210            PEX3  -B37        A01X+165098Y+125098X0180Y         S1      
317m4211            VIA   -    MD0080PA01X+028720Y+107520X0160Y         S0      
327m4211            PEX0  -BJ39       A01X+028720Y+107520X0180Y         S1      
327m4211            J20   -A20        A01X+019938Y+053057X0140Y0480R270 S1      
317m4211            VIA   -    MD0100PA01X+021298Y+053109X0200Y    R180 S0      
317m4212            J11   -T2   D0122PA01X+029177Y+148343X0282Y    R180 S3      
317m4212            VIA   -    MD0080PA01X+020492Y+125472X0160Y         S0      
327m4212            PEX0  -A17        A01X+020492Y+125472X0180Y         S1      
317m4213            VIA   -    MD0080PA01X+112657Y+107894X0160Y    R270 S0      
327m4213            J40   -A21        A01X+116088Y+012122X0150Y0500R090 S1      
317m4213            VIA   -    MD0100PA01X+114728Y+012174X0200Y         S0      
327m4213            PEX2  -BH19       A01X+112657Y+107894X0180Y         S1      
317m4214            VIA   -    MD0080PA01X+169587Y+112382X0160Y    R270 S0      
317m4214            VIA   -    MD0100PA01X+162796Y+048860X0200Y         S0      
327m4214            J27   -A26        A01X+164156Y+048911X0140Y0480R090 S1      
327m4214            PEX3  -AT49       A01X+169587Y+112382X0180Y         S1      
317m4215            J14   -X4   D0122PA01X+150429Y+146295X0282Y    R180 S3      
317m4215            VIA   -    MD0080PA01X+164350Y+125098X0160Y    R090 S0      
327m4215            PEX3  -B35        A01X+164350Y+125098X0180Y         S1      
327NIC1_BIF1_N      J21   -B8         A01X+028842Y+044660X0140Y0480R090 S1      
317NIC1_BIF1_N      VIA   -    M      A01X+027853Y+044049X0200Y         S2      
017NIC1_BIF1_N      VIA   -    M      A18X+027853Y+044049X0260Y         S2      
017NIC1_BIF1_N            -    MD0100PA00X+027853Y+044049                       
327NIC1_BIF1_N      R82   -1          A18X+024408Y+043103X0198Y0197     S2      
327NIC1_BIF1_N      R83   -1   M      A18X+024793Y+043103X0198Y0197R180 S2      
317m4216            VIA   -    MD0100PA01X+021298Y+039100X0200Y    R180 S0      
327m4216            J20   -A66        A01X+019938Y+039152X0140Y0480R270 S1      
317m4216            VIA   -    MD0080PA01X+023484Y+107894X0160Y         S0      
327m4216            PEX0  -BH25       A01X+023484Y+107894X0180Y         S1      
317m4217            VIA   -    MD0100PA01X+025726Y+138430X0180Y         S0      
317m4217            J11   -B2   D0122PA01X+029177Y+161650X0282Y    R180 S3      
327m4217            C132  -2          A01X+025736Y+137939X0120Y0150R090 S1      
327m4218            C493  -2          A01X+098317Y+011472X0120Y0150R180 S1      
327m4218            J38   -B18        A01X+097427Y+011413X0150Y0500R090 S1      
317NIC1_CLK         VIA   -    M      A01X+029236Y+039386X0200Y         S2      
017NIC1_CLK         VIA   -    M      A18X+029236Y+039386X0260Y         S2      
017NIC1_CLK               -    MD0100PA00X+029236Y+039386                       
327NIC1_CLK         J21   -OB6        A01X+028842Y+039386X0140Y0480R090 S1      
327NIC1_CLK         R65   -1          A18X+030371Y+038991X0198Y0197R180 S2      
317m4219            VIA   -    MD0100PA01X+020568Y+053818X0200Y    R180 S0      
327m4219            J20   -A17        A01X+019938Y+053766X0140Y0480R270 S1      
317m4219            VIA   -    MD0080PA01X+029094Y+108268X0160Y         S0      
327m4219            PEX0  -BG40       A01X+029094Y+108268X0180Y         S1      
317m4220            J11   -U1   D0122PA01X+028311Y+147910X0282Y    R180 S3      
317m4220            VIA   -    MD0080PA01X+020118Y+124724X0160Y         S0      
327m4220            PEX0  -C16        A01X+020118Y+124724X0180Y         S1      
317m4221            VIA   -    MD0080PA01X+114528Y+108268X0160Y    R270 S0      
327m4221            PEX2  -BG24       A01X+114528Y+108268X0180Y         S1      
327m4221            J41   -A17        A01X+126325Y+011177X0150Y0500R090 S1      
317m4221            VIA   -    MD0100PA01X+125695Y+011126X0200Y         S0      
317m4222            VIA   -    MD0100PA01X+156269Y+136010X0180Y         S0      
317m4222            J14   -Q4   D0122PA01X+150429Y+149878X0282Y    R180 S3      
327m4222            C739  -2          A01X+156279Y+135519X0120Y0150R090 S1      
327PRSNTB0_NIC1_N   VIA   -    M      A01X+031066Y+054034X0300Y    R180 S1      
327PRSNTB0_NIC1_N   J21   -B42        A01X+028842Y+054034X0140Y0480R090 S1      
327PRSNTB0_NIC1_N   R90   -2          A01X+031551Y+054591X0198Y0197R180 S1      
327PRSNTB0_NIC1_N   R56   -1   M      A01X+031551Y+054191X0198Y0197     S1      
327m4223            J20   -B40        A01X+018127Y+046990X0140Y0480R270 S1      
327m4223            C47   -2          A01X+014530Y+046929X0120Y0150     S1      
317m4224            J11   -J1   D0122PA01X+028311Y+157634X0282Y    R180 S3      
317m4224            VIA   -    MD0080PA01X+017126Y+124350X0160Y         S0      
327m4224            PEX0  -D8         A01X+017126Y+124350X0180Y         S1      
327m4225            C488  -2          A01X+099357Y+013241X0120Y0150R180 S1      
327m4225            J38   -B26        A01X+097427Y+013303X0150Y0500R090 S1      
317m4226            J14   -X1   D0122PA01X+147831Y+146374X0282Y    R180 S3      
317m4226            VIA   -    MD0080PA01X+163228Y+124724X0160Y         S0      
327m4226            PEX3  -C32        A01X+163228Y+124724X0180Y         S1      
327m4227            C52   -2          A01X+015570Y+043702X0120Y0150     S1      
327m4227            J20   -B47        A01X+018127Y+043640X0140Y0480R270 S1      
317m4228            J11   -I2   D0122PA01X+029177Y+158067X0282Y    R180 S3      
317m4228            VIA   -    MD0080PA01X+017500Y+125098X0160Y         S0      
327m4228            PEX0  -B9         A01X+017500Y+125098X0180Y         S1      
327m4229            C500  -2          A01X+109594Y+011824X0120Y0150R180 S1      
327m4229            J39   -B20        A01X+107663Y+011886X0150Y0500R090 S1      
317m4230            VIA   -    MD0100PA01X+155929Y+140850X0180Y         S0      
317m4230            J14   -S5   D0122PA01X+151295Y+148933X0282Y    R180 S3      
327m4230            C736  -2          A01X+155919Y+140359X0120Y0150R090 S1      
317m4231            VIA   -    MD0100PA00X+028022Y+044849X0200Y         S0      
327m4231            J21   -B10        A01X+028842Y+045132X0140Y0480R090 S1      
327m4231            R96   -1          A01X+032142Y+034547X0198Y0197R270 S1      
317m4231            VIA   -    M      A01X+032142Y+034802X0200Y    R180 S2      
017m4231            VIA   -    M      A18X+032142Y+034802X0260Y    R180 S2      
017m4231                  -    MD0100PA00X+032142Y+034802                       
317m4232            VIA   -    MD0100PA01X+020568Y+040148X0200Y    R180 S0      
327m4232            J20   -A62        A01X+019938Y+040096X0140Y0480R270 S1      
317m4232            VIA   -    MD0080PA01X+023858Y+108268X0160Y         S0      
327m4232            PEX0  -BG26       A01X+023858Y+108268X0180Y         S1      
317m4233            VIA   -    MD0080PA01X+109291Y+108642X0160Y    R270 S0      
327m4233            PEX2  -BF10       A01X+109291Y+108642X0180Y         S1      
327m4233            J38   -A24        A01X+095616Y+012831X0150Y0500R090 S1      
317m4233            VIA   -    MD0100PA01X+094986Y+012883X0200Y         S0      
317m4234            VIA   -    MD0100PA01X+153821Y+136010X0180Y         S0      
317m4234            J14   -R1   D0122PA01X+147831Y+149445X0282Y    R180 S3      
327m4234            C745  -2          A01X+153831Y+135519X0120Y0150R090 S1      
327m4235            VIA   -    M      A01X+024182Y+038072X0300Y    R180 S1      
327m4235            J21   -OA1        A01X+027030Y+038205X0140Y0480R090 S1      
327m4235            R98   -1          A01X+023384Y+038072X0198Y0197R180 S1      
317m4236            VIA   -    MD0100PA01X+021298Y+039440X0200Y    R180 S0      
327m4236            J20   -A65        A01X+019938Y+039388X0140Y0480R270 S1      
317m4236            VIA   -    MD0080PA01X+023484Y+107520X0160Y         S0      
327m4236            PEX0  -BJ25       A01X+023484Y+107520X0180Y         S1      
317m4237            VIA   -    MD0080PA01X+111535Y+108642X0160Y    R270 S0      
327m4237            PEX2  -BF16       A01X+111535Y+108642X0180Y         S1      
327m4237            J39   -A18        A01X+105852Y+011413X0150Y0500R090 S1      
317m4237            VIA   -    MD0100PA01X+105222Y+011466X0200Y         S0      
317m4238            J13   -I6   D0122PA01X+134839Y+158067X0282Y    R180 S3      
317m4238            VIA   -    MD0080PA01X+110413Y+125098X0160Y         S0      
327m4238            PEX2  -B13        A01X+110413Y+125098X0180Y         S1      
317m4239            J14   -X2   D0122PA01X+148697Y+146295X0282Y    R180 S3      
317m4239            VIA   -    MD0080PA01X+163602Y+125098X0160Y    R090 S0      
327m4239            PEX3  -B33        A01X+163602Y+125098X0180Y         S1      
327PRSNTB3_NIC1_N   VIA   -    M      A01X+031076Y+062291X0300Y    R180 S1      
327PRSNTB3_NIC1_N   J21   -B70        A01X+028842Y+062344X0140Y0480R090 S1      
327PRSNTB3_NIC1_N   R93   -2          A01X+031551Y+062691X0198Y0197R180 S1      
327PRSNTB3_NIC1_N   R59   -1   M      A01X+031551Y+062291X0198Y0197     S1      
327m4240            J20   -B31        A01X+018127Y+049116X0140Y0480R270 S1      
327m4240            C41   -2          A01X+015570Y+049057X0120Y0150     S1      
317m4241            VIA   -    MD0080PA01X+114154Y+107520X0160Y    R270 S0      
327m4241            PEX2  -BJ23       A01X+114154Y+107520X0180Y         S1      
327m4241            J41   -A20        A01X+126325Y+011886X0150Y0500R090 S1      
317m4241            VIA   -    MD0100PA01X+124965Y+011834X0200Y         S0      
317m4242            J13   -I8   D0122PA01X+136571Y+158067X0282Y    R180 S3      
317m4242            VIA   -    MD0080PA01X+111161Y+125098X0160Y         S0      
327m4242            PEX2  -B15        A01X+111161Y+125098X0180Y         S1      
317m4243            J14   -L7   D0122PA01X+153028Y+156610X0282Y    R180 S3      
317m4243            VIA   -    MD0080PA01X+162480Y+124724X0160Y         S0      
327m4243            PEX3  -C30        A01X+162480Y+124724X0180Y         S1      
317RST_HP_NIC6_N    VIA   -    M      A01X+156513Y+066815X0200Y         S2      
017RST_HP_NIC6_N    VIA   -    M      A18X+156513Y+066815X0260Y         S2      
017RST_HP_NIC6_N          -    MD0100PA00X+156513Y+066815                       
327RST_HP_NIC6_N    U40   -2          A01X+155811Y+065572X0160Y0360R270 S1      
327RST_HP_NIC6_N    U41   -4          A01X+156513Y+067236X0220Y0530R180 S1      
327P3V3_SSD3        R893  -1          A01X+033929Y+023613X0198Y0197R270 S1      
317P3V3_SSD3        VIA   -    MD0100PA00X+033929Y+023871X0200Y    R090 S0      
327P3V3_SSD3        PU60  -1          A01X+032930Y+021324X0110Y0240     S1      
327P3V3_SSD3        PU60  -2          A01X+033126Y+021324X0110Y0240     S1      
327P3V3_SSD3        PU60  -3          A01X+033323Y+021324X0110Y0240     S1      
327P3V3_SSD3        PU60  -4          A01X+033520Y+021324X0110Y0240     S1      
327P3V3_SSD3        PU60  -5          A01X+033717Y+021324X0110Y0240     S1      
327P3V3_SSD3        PC539 -1          A01X+033283Y+020064X0400Y0500     S1      
327P3V3_SSD3        PC538 -1          A01X+033176Y+020686X0198Y0197R180 S1      
327P3V3_SSD3        PD66  -C          A01X+033762Y+018984X0670Y0990R090 S1      
317P3V3_SSD3        VIA   -    MD0100PA00X+033967Y+020205X0200Y    R090 S0      
317P3V3_SSD3        VIA   -    MD0100PA00X+033273Y+021051X0200Y    R180 S0      
317P3V3_SSD3        VIA   -    MD0100PA00X+033523Y+021051X0200Y    R180 S0      
317P3V3_SSD3        VIA   -    MD0100PA00X+033701Y+020681X0200Y    R180 S0      
317P3V3_SSD3        VIA   -    MD0100PA00X+033451Y+020681X0200Y    R180 S0      
317P3V3_SSD3        VIA   -    MD0100PA00X+033667Y+020175X0200Y    R090 S0      
317P3V3_SSD3        VIA   -    M      A01X+033967Y+019925X0200Y    R090 S2      
017P3V3_SSD3        VIA   -    M      A18X+033967Y+019925X0260Y    R090 S2      
017P3V3_SSD3              -    MD0100PA00X+033967Y+019925                       
317P3V3_SSD3        VIA   -    MD0100PA00X+034015Y+019518X0200Y    R180 S0      
317P3V3_SSD3        VIA   -    MD0100PA00X+033765Y+019518X0200Y    R180 S0      
317P3V3_SSD3        VIA   -    MD0100PA00X+033667Y+019925X0200Y    R090 S0      
317P3V3_SSD3        VIA   -    MD0100PA00X+033265Y+019518X0200Y    R180 S0      
317P3V3_SSD3        VIA   -    MD0100PA00X+033515Y+019518X0200Y    R180 S0      
327P3V3_SSD3        R5887 -1          A01X+027892Y+014754X0198Y0197     S1      
317P3V3_SSD3        VIA   -    MD0100PA00X+027615Y+014754X0200Y         S0      
327P3V3_SSD3        R5737 -1          A01X+039325Y+010824X0198Y0197R270 S1      
317P3V3_SSD3        VIA   -    MD0100PA00X+039068Y+010619X0200Y    R090 S0      
327P3V3_SSD3        R418  -1          A01X+038375Y+010135X0198Y0197R270 S1      
317P3V3_SSD3        VIA   -    MD0100PA00X+038375Y+010378X0200Y    R270 S0      
317P3V3_SSD3        VIA   -    MD0100PA00X+032406Y+011659X0200Y         S0      
317P3V3_SSD3        VIA   -    MD0100PA00X+032406Y+011959X0200Y         S0      
327P3V3_SSD3        PU84  -6_7        A01X+031952Y+011762X0295Y0354R270 S1      
327P3V3_SSD3        R5656 -2          A01X+032950Y+013484X0198Y0197     S1      
327P3V3_SSD3        PC683 -1   M      A01X+032832Y+011967X0400Y0500R090 S1      
327P3V3_SSD3        C968  -2   M      A01X+037766Y+009855X0198Y0197R270 S1      
317P3V3_SSD3        VIA   -    MD0100PA00X+038020Y+009855X0200Y    R090 S0      
327P3V3_SSD3        J33   -B11        A01X+036718Y+009760X0150Y0500R090 S1      
327P3V3_SSD3        R419  -1          A01X+033611Y+009767X0198Y0197     S1      
317P3V3_SSD3        VIA   -    M      A01X+033367Y+009767X0200Y         S2      
017P3V3_SSD3        VIA   -    M      A18X+033367Y+009767X0260Y         S2      
017P3V3_SSD3              -    MD0100PA00X+033367Y+009767                       
327P3V3_SSD3        R1649 -1          A01X+039668Y+003994X0198Y0197R090 S1      
317P3V3_SSD3        VIA   -    MD0100PA00X+039668Y+003754X0200Y    R270 S0      
327P3V3_SSD3        R1650 -1          A01X+040868Y+003994X0198Y0197R090 S1      
317P3V3_SSD3        VIA   -    MD0100PA00X+040868Y+003753X0200Y    R270 S0      
327P3V3_SSD3        U129  -1          A01X+039282Y+003402X0240Y0460R090 S1      
327P3V3_SSD3        C2718 -2   M      A01X+038611Y+003377X0198Y0197R090 S1      
317P3V3_SSD3        VIA   -    MD0100PA00X+038361Y+003377X0200Y    R270 S0      
317m4244            VIA   -    MD0080PA01X+028720Y+107894X0160Y         S0      
327m4244            PEX0  -BH39       A01X+028720Y+107894X0180Y         S1      
327m4244            J20   -A21        A01X+019938Y+052821X0140Y0480R270 S1      
317m4244            VIA   -    MD0100PA01X+021298Y+052769X0200Y    R180 S0      
317m4245            VIA   -    MD0100PA01X+031506Y+140850X0180Y         S0      
317m4245            J11   -O2   D0122PA01X+029177Y+150902X0282Y    R180 S3      
327m4245            C147  -2          A01X+031496Y+140359X0120Y0150R090 S1      
327m4246            C508  -2          A01X+119830Y+011824X0120Y0150R180 S1      
327m4246            J40   -B20        A01X+117900Y+011886X0150Y0500R090 S1      
317m4247            J13   -I1   D0122PA01X+130508Y+158146X0282Y    R180 S3      
317m4247            VIA   -    MD0080PA01X+108543Y+124724X0160Y         S0      
327m4247            PEX2  -C8         A01X+108543Y+124724X0180Y         S1      
317m4248            VIA   -    MD0100PA01X+158717Y+136010X0180Y         S0      
317m4248            J14   -R7   D0122PA01X+153028Y+149445X0282Y    R180 S3      
327m4248            C733  -2          A01X+158727Y+135519X0120Y0150R090 S1      
327PRSNTB1_NIC1_N   VIA   -    M      A01X+025609Y+054271X0300Y    R180 S1      
327PRSNTB1_NIC1_N   J21   -A42        A01X+027030Y+054034X0140Y0480R090 S1      
327PRSNTB1_NIC1_N   R91   -2          A01X+025146Y+054671X0198Y0197     S1      
327PRSNTB1_NIC1_N   R57   -1   M      A01X+025146Y+054271X0198Y0197R180 S1      
327m4249            VIA   -    M      A01X+157845Y+068379X0300Y         S1      
327m4249            U41   -1          A01X+157261Y+068201X0220Y0530R180 S1      
327m4249            R357  -1   M      A01X+157616Y+068969X0198Y0197     S1      
327m4249            Q7    -6          A01X+157594Y+069480X0170Y0240R180 S1      
327P3V3_SSD2        R890  -1          A01X+023692Y+023613X0198Y0197R270 S1      
317P3V3_SSD2        VIA   -    MD0100PA00X+023692Y+023871X0200Y    R090 S0      
327P3V3_SSD2        PU59  -1          A01X+022693Y+021324X0110Y0240     S1      
327P3V3_SSD2        PU59  -2          A01X+022890Y+021324X0110Y0240     S1      
327P3V3_SSD2        PU59  -3          A01X+023087Y+021324X0110Y0240     S1      
327P3V3_SSD2        PU59  -4          A01X+023284Y+021324X0110Y0240     S1      
327P3V3_SSD2        PU59  -5          A01X+023481Y+021324X0110Y0240     S1      
327P3V3_SSD2        PC525 -1          A01X+023047Y+020064X0400Y0500     S1      
327P3V3_SSD2        PC524 -1          A01X+022940Y+020686X0198Y0197R180 S1      
327P3V3_SSD2        PD65  -C          A01X+023525Y+018984X0670Y0990R090 S1      
317P3V3_SSD2        VIA   -    MD0100PA00X+023431Y+020175X0200Y    R090 S0      
317P3V3_SSD2        VIA   -    MD0100PA00X+023214Y+020681X0200Y    R180 S0      
317P3V3_SSD2        VIA   -    MD0100PA00X+023464Y+020681X0200Y    R180 S0      
317P3V3_SSD2        VIA   -    MD0100PA00X+023287Y+021051X0200Y    R180 S0      
317P3V3_SSD2        VIA   -    MD0100PA00X+023731Y+020205X0200Y    R090 S0      
317P3V3_SSD2        VIA   -    MD0100PA00X+023037Y+021051X0200Y    R180 S0      
317P3V3_SSD2        VIA   -    MD0100PA00X+023779Y+019518X0200Y    R180 S0      
317P3V3_SSD2        VIA   -    MD0100PA00X+023431Y+019925X0200Y    R090 S0      
317P3V3_SSD2        VIA   -    M      A01X+023731Y+019925X0200Y    R090 S2      
017P3V3_SSD2        VIA   -    M      A18X+023731Y+019925X0260Y    R090 S2      
017P3V3_SSD2              -    MD0100PA00X+023731Y+019925                       
317P3V3_SSD2        VIA   -    MD0100PA00X+023529Y+019518X0200Y    R180 S0      
317P3V3_SSD2        VIA   -    MD0100PA00X+023279Y+019518X0200Y    R180 S0      
317P3V3_SSD2        VIA   -    MD0100PA00X+023029Y+019518X0200Y    R180 S0      
327P3V3_SSD2        R5886 -1          A01X+017656Y+014754X0198Y0197     S1      
317P3V3_SSD2        VIA   -    MD0100PA00X+017378Y+014754X0200Y         S0      
327P3V3_SSD2        R5735 -1          A01X+029089Y+010824X0198Y0197R270 S1      
317P3V3_SSD2        VIA   -    MD0100PA00X+028832Y+010619X0200Y    R090 S0      
327P3V3_SSD2        R415  -1          A01X+028138Y+010135X0198Y0197R270 S1      
317P3V3_SSD2        VIA   -    MD0100PA00X+028138Y+010378X0200Y    R270 S0      
317P3V3_SSD2        VIA   -    MD0100PA00X+022170Y+011659X0200Y         S0      
317P3V3_SSD2        VIA   -    MD0100PA00X+022170Y+011959X0200Y         S0      
327P3V3_SSD2        PU83  -6_7        A01X+021716Y+011762X0295Y0354R270 S1      
327P3V3_SSD2        PC681 -1   M      A01X+022596Y+011967X0400Y0500R090 S1      
327P3V3_SSD2        R5660 -2          A01X+022714Y+013484X0198Y0197     S1      
327P3V3_SSD2        C967  -2   M      A01X+027530Y+009855X0198Y0197R270 S1      
317P3V3_SSD2        VIA   -    MD0100PA00X+027783Y+009855X0200Y    R090 S0      
327P3V3_SSD2        J32   -B11        A01X+026482Y+009760X0150Y0500R090 S1      
327P3V3_SSD2        R417  -1          A01X+023375Y+009767X0198Y0197     S1      
317P3V3_SSD2        VIA   -    M      A01X+023131Y+009767X0200Y         S2      
017P3V3_SSD2        VIA   -    M      A18X+023131Y+009767X0260Y         S2      
017P3V3_SSD2              -    MD0100PA00X+023131Y+009767                       
327P3V3_SSD2        R1647 -1          A01X+029944Y+008058X0198Y0197R180 S1      
317P3V3_SSD2        VIA   -    MD0100PA00X+030185Y+008058X0200Y         S0      
327P3V3_SSD2        R1646 -1          A01X+029944Y+006858X0198Y0197R180 S1      
317P3V3_SSD2        VIA   -    MD0100PA00X+030184Y+006858X0200Y         S0      
327P3V3_SSD2        C2716 -2   M      A01X+030561Y+005801X0198Y0197R180 S1      
327P3V3_SSD2        U128  -1          A01X+030536Y+006472X0240Y0460R180 S1      
317P3V3_SSD2        VIA   -    MD0100PA00X+030561Y+005551X0200Y         S0      
317m4250            VIA   -    MD0100PA01X+020568Y+041566X0200Y    R180 S0      
327m4250            J20   -A56        A01X+019938Y+041514X0140Y0480R270 S1      
317m4250            VIA   -    MD0080PA01X+024606Y+108268X0160Y         S0      
327m4250            PEX0  -BG28       A01X+024606Y+108268X0180Y         S1      
317m4251            VIA   -    MD0080PA01X+113405Y+107894X0160Y    R270 S0      
327m4251            PEX2  -BH21       A01X+113405Y+107894X0180Y         S1      
327m4251            J41   -A27        A01X+126325Y+013539X0150Y0500R090 S1      
317m4251            VIA   -    MD0100PA01X+124965Y+013592X0200Y         S0      
317m4252            J13   -I5   D0122PA01X+133972Y+158146X0282Y    R180 S3      
317m4252            VIA   -    MD0080PA01X+110039Y+124724X0160Y         S0      
327m4252            PEX2  -C12        A01X+110039Y+124724X0180Y         S1      
317m4253            VIA   -    MD0100PA01X+157493Y+140850X0180Y         S0      
317m4253            J14   -F7   D0122PA01X+153028Y+159681X0282Y    R180 S3      
327m4253            C749  -2          A01X+157503Y+140359X0120Y0150R090 S1      
327m4254            VIA   -    M      A18X+028850Y+038800X0260Y         S2      
317m4254            VIA   -    MD0100PA00X+029252Y+038441X0200Y         S0      
327m4254            R53   -1          A18X+028408Y+038800X0198Y0197     S2      
327m4254            J21   -OB2        A01X+028842Y+038441X0140Y0480R090 S1      
317m4255            VIA   -    MD0100PA01X+020568Y+049064X0200Y    R180 S0      
327m4255            J20   -A31        A01X+019938Y+049116X0140Y0480R270 S1      
317m4255            VIA   -    MD0080PA01X+027598Y+108642X0160Y         S0      
327m4255            PEX0  -BF36       A01X+027598Y+108642X0180Y         S1      
327m4256            C507  -2          A01X+119830Y+012184X0120Y0150R180 S1      
327m4256            J40   -B21        A01X+117900Y+012122X0150Y0500R090 S1      
317m4257            J13   -T6   D0122PA01X+134839Y+148343X0282Y    R180 S3      
317m4257            VIA   -    MD0080PA01X+113405Y+125472X0160Y         S0      
327m4257            PEX2  -A21        A01X+113405Y+125472X0180Y         S1      
317m4258            VIA   -    MD0100PA01X+153481Y+138430X0180Y         S0      
317m4258            J14   -F2   D0122PA01X+148697Y+159602X0282Y    R180 S3      
327m4258            C758  -2          A01X+153471Y+137939X0120Y0150R090 S1      
317NIC1_DATA_IN     VIA   -    M      A01X+029900Y+038650X0200Y         S2      
017NIC1_DATA_IN     VIA   -    M      A18X+029900Y+038650X0260Y         S2      
017NIC1_DATA_IN           -    MD0100PA00X+029900Y+038650                       
327NIC1_DATA_IN     J21   -OB4        A01X+028842Y+038913X0140Y0480R090 S1      
327NIC1_DATA_IN     R63   -1          A18X+030371Y+038191X0198Y0197R180 S2      
327m4259            C60   -2          A01X+015570Y+040867X0120Y0150     S1      
327m4259            J20   -B59        A01X+018127Y+040805X0140Y0480R270 S1      
317m4260            VIA   -    MD0100PA01X+031846Y+136010X0180Y         S0      
317m4260            J11   -O1   D0122PA01X+028311Y+150980X0282Y    R180 S3      
327m4260            C146  -2          A01X+031856Y+135519X0120Y0150R090 S1      
327m4261            C499  -2          A01X+109594Y+012184X0120Y0150R180 S1      
327m4261            J39   -B21        A01X+107663Y+012122X0150Y0500R090 S1      
317m4262            VIA   -    MD0100PA01X+125481Y+140850X0180Y         S0      
317m4262            J13   -C4   D0122PA01X+133106Y+161138X0282Y    R180 S3      
327m4262            C557  -2          A01X+125471Y+140359X0120Y0150R090 S1      
317m4263            VIA   -    MD0100PA01X+156269Y+138430X0180Y         S0      
317m4263            J14   -F5   D0122PA01X+151295Y+159681X0282Y    R180 S3      
327m4263            C753  -2          A01X+156279Y+137939X0120Y0150R090 S1      
327m4264            VIA   -    M      A01X+024256Y+041272X0300Y    R180 S1      
327m4264            J21   -OA14       A01X+027030Y+041276X0140Y0480R090 S1      
327m4264            R71   -1          A01X+023384Y+041272X0198Y0197R180 S1      
327m4265            C49   -2          A01X+014530Y+044053X0120Y0150     S1      
327m4265            J20   -B45        A01X+018127Y+044112X0140Y0480R270 S1      
317m4266            VIA   -    MD0100PA01X+035178Y+138430X0180Y         S0      
317m4266            J11   -O6   D0122PA01X+032642Y+150902X0282Y    R180 S3      
327m4266            C155  -2          A01X+035168Y+137939X0120Y0150R090 S1      
327m4267            C502  -2          A01X+108553Y+011112X0120Y0150R180 S1      
327m4267            J39   -B17        A01X+107663Y+011177X0150Y0500R090 S1      
317m4268            VIA   -    MD0100PA01X+126705Y+138430X0180Y         S0      
317m4268            J13   -D5   D0122PA01X+133972Y+160705X0282Y    R180 S3      
327m4268            C559  -2          A01X+126695Y+137939X0120Y0150R090 S1      
317m4269            VIA   -    MD0100PA01X+157493Y+136010X0180Y         S0      
317m4269            J14   -E6   D0122PA01X+152161Y+160114X0282Y    R180 S3      
327m4269            C751  -2          A01X+157503Y+135519X0120Y0150R090 S1      
327NIC1_LD_N        R62   -1          A18X+030371Y+037791X0198Y0197R180 S2      
317NIC1_LD_N        VIA   -    M      A01X+029900Y+037791X0200Y         S2      
017NIC1_LD_N        VIA   -    M      A18X+029900Y+037791X0260Y         S2      
017NIC1_LD_N              -    MD0100PA00X+029900Y+037791                       
327NIC1_LD_N        J21   -OB3        A01X+028842Y+038677X0140Y0480R090 S1      
327m4270            J20   -B27        A01X+018127Y+051404X0140Y0480R270 S1      
327m4270            C39   -2          A01X+014530Y+051342X0120Y0150     S1      
327m4271            J41   -B17        A01X+128136Y+011177X0150Y0500R090 S1      
327m4271            C518  -2          A01X+129026Y+011112X0120Y0150R180 S1      
317m4272            VIA   -    MD0100PA01X+129493Y+138430X0180Y         S0      
317m4272            J13   -B8   D0122PA01X+136571Y+161650X0282Y    R180 S3      
327m4272            C566  -2          A01X+129503Y+137939X0120Y0150R090 S1      
317m4273            VIA   -    MD0100PA01X+155929Y+136010X0180Y         S0      
317m4273            J14   -R4   D0122PA01X+150429Y+149366X0282Y    R180 S3      
327m4273            C738  -2          A01X+155919Y+135519X0120Y0150R090 S1      
317m4274            VIA   -    MD0100PA00X+026501Y+045388X0200Y         S0      
327m4274            J21   -A11        A01X+027030Y+045368X0140Y0480R090 S1      
327m4274            R97   -1          A01X+031742Y+034547X0198Y0197R270 S1      
317m4274            VIA   -    M      A01X+031607Y+034794X0200Y    R180 S2      
017m4274            VIA   -    M      A18X+031607Y+034794X0260Y    R180 S2      
017m4274                  -    MD0100PA00X+031607Y+034794                       
317m4275            VIA   -    MD0100PA01X+021298Y+042274X0200Y    R180 S0      
327m4275            J20   -A53        A01X+019938Y+042222X0140Y0480R270 S1      
317m4275            VIA   -    MD0080PA01X+024980Y+107520X0160Y         S0      
327m4275            PEX0  -BJ29       A01X+024980Y+107520X0180Y         S1      
317m4276            J11   -U4   D0122PA01X+030909Y+147831X0282Y    R180 S3      
317m4276            VIA   -    MD0080PA01X+021240Y+125098X0160Y         S0      
327m4276            PEX0  -B19        A01X+021240Y+125098X0180Y         S1      
327m4277            C501  -2          A01X+108553Y+011472X0120Y0150R180 S1      
327m4277            J39   -B18        A01X+107663Y+011413X0150Y0500R090 S1      
317m4278            J13   -U6   D0122PA01X+134839Y+147831X0282Y    R180 S3      
317m4278            VIA   -    MD0080PA01X+113405Y+125098X0160Y         S0      
327m4278            PEX2  -B21        A01X+113405Y+125098X0180Y         S1      
317m4279            VIA   -    MD0100PA01X+157153Y+140850X0180Y         S0      
317m4279            J14   -G7   D0122PA01X+153028Y+159169X0282Y    R180 S3      
327m4279            C748  -2          A01X+157143Y+140359X0120Y0150R090 S1      
327NCSI_NIC1_TXD0   VIA   -    M      A01X+025160Y+040872X0300Y    R180 S1      
327NCSI_NIC1_TXD0   R69   -1          A01X+023384Y+040872X0198Y0197R180 S1      
327NCSI_NIC1_TXD0   J21   -OA9        A01X+027030Y+040094X0140Y0480R090 S1      
317m4280            VIA   -    MD0100PA01X+021298Y+043352X0200Y    R180 S0      
327m4280            J20   -A48        A01X+019938Y+043404X0140Y0480R270 S1      
317m4280            VIA   -    MD0080PA01X+025728Y+107894X0160Y         S0      
327m4280            PEX0  -BH31       A01X+025728Y+107894X0180Y         S1      
317m4281            VIA   -    MD0100PA01X+033954Y+140850X0180Y         S0      
317m4281            J11   -P5   D0122PA01X+031776Y+150468X0282Y    R180 S3      
327m4281            C153  -2          A01X+033944Y+140359X0120Y0150R090 S1      
317m4282            VIA   -    MD0080PA01X+110039Y+108642X0160Y    R270 S0      
327m4282            PEX2  -BF12       A01X+110039Y+108642X0180Y         S1      
327m4282            J38   -A18        A01X+095616Y+011413X0150Y0500R090 S1      
317m4282            VIA   -    MD0100PA01X+094986Y+011466X0200Y         S0      
317m4283            J13   -V5   D0122PA01X+133972Y+147398X0282Y    R180 S3      
317m4283            VIA   -    MD0080PA01X+113031Y+124350X0160Y         S0      
327m4283            PEX2  -D20        A01X+113031Y+124350X0180Y         S1      
317m4284            J14   -Y3   D0122PA01X+149563Y+145862X0282Y    R180 S3      
317m4284            VIA   -    MD0080PA01X+163976Y+124350X0160Y         S0      
327m4284            PEX3  -D34        A01X+163976Y+124350X0180Y         S1      
317NCSI_NIC1_RXD1   VIA   -    M      A01X+029400Y+039858X0200Y         S2      
017NCSI_NIC1_RXD1   VIA   -    M      A18X+029400Y+039858X0260Y         S2      
017NCSI_NIC1_RXD1         -    MD0100PA00X+029400Y+039858                       
327NCSI_NIC1_RXD1   J21   -OB8        A01X+028842Y+039858X0140Y0480R090 S1      
327NCSI_NIC1_RXD1   R68   -1          A18X+030371Y+040192X0198Y0197R180 S2      
327m4285            J41   -B9         A01X+128136Y+009287X0150Y0500R090 S1      
317m4285            VIA   -    M      A01X+128609Y+009287X0200Y         S2      
017m4285            VIA   -    M      A18X+128609Y+009287X0260Y         S2      
017m4285                  -    MD0100PA00X+128609Y+009287                       
327m4285            R443  -2          A01X+130192Y+009820X0198Y0197R270 S1      
327m4285            R442  -2   M      A01X+129792Y+009820X0198Y0197R270 S1      
327m4286            J20   -B39        A01X+018127Y+047226X0140Y0480R270 S1      
327m4286            C48   -2          A01X+014530Y+047289X0120Y0150     S1      
327m4287            J41   -B27        A01X+128136Y+013539X0150Y0500R090 S1      
327m4287            C511  -2          A01X+130066Y+013601X0120Y0150R180 S1      
317m4288            VIA   -    MD0100PA01X+134389Y+138430X0180Y         S0      
317m4288            J13   -N6   D0122PA01X+134839Y+151413X0282Y    R180 S3      
327m4288            C578  -2          A01X+134399Y+137939X0120Y0150R090 S1      
317m4289            J14   -Y7   D0122PA01X+153028Y+145862X0282Y    R180 S3      
317m4289            VIA   -    MD0080PA01X+165472Y+124350X0160Y         S0      
327m4289            PEX3  -D38        A01X+165472Y+124350X0180Y         S1      
317m4290            VIA   -    M      A01X+029800Y+040900X0200Y         S2      
017m4290            VIA   -    M      A18X+029800Y+040900X0260Y         S2      
017m4290                  -    MD0100PA00X+029800Y+040900                       
327m4290            J21   -OB14       A01X+028842Y+041276X0140Y0480R090 S1      
327m4290            R66   -1          A18X+030371Y+040992X0198Y0197R180 S2      
327PU_CLKREQ10      J40   -A11        A01X+116088Y+009760X0150Y0500R090 S1      
317PU_CLKREQ10      VIA   -    M      A01X+115434Y+009767X0200Y         S2      
017PU_CLKREQ10      VIA   -    M      A18X+115434Y+009767X0260Y         S2      
017PU_CLKREQ10            -    MD0100PA00X+115434Y+009767                       
327PU_CLKREQ10      R441  -2          A01X+115107Y+009767X0198Y0197     S1      
327m4291            J20   -B20        A01X+018127Y+053057X0140Y0480R270 S1      
327m4291            C36   -2          A01X+014530Y+053119X0120Y0150     S1      
317m4292            J11   -T8   D0122PA01X+034374Y+148343X0282Y    R180 S3      
317m4292            VIA   -    MD0080PA01X+022736Y+125472X0160Y         S0      
327m4292            PEX0  -A23        A01X+022736Y+125472X0180Y         S1      
317m4293            VIA   -    MD0080PA01X+111161Y+107894X0160Y    R270 S0      
327m4293            PEX2  -BH15       A01X+111161Y+107894X0180Y         S1      
327m4293            J39   -A21        A01X+105852Y+012122X0150Y0500R090 S1      
317m4293            VIA   -    MD0100PA01X+104492Y+012174X0200Y         S0      
317m4294            VIA   -    MD0100PA01X+133165Y+136010X0180Y         S0      
317m4294            J13   -N4   D0122PA01X+133106Y+151413X0282Y    R180 S3      
327m4294            C574  -2          A01X+133175Y+135519X0120Y0150R090 S1      
317m4295            J14   -W2   D0122PA01X+148697Y+146807X0282Y    R180 S3      
317m4295            VIA   -    MD0080PA01X+163602Y+125472X0160Y    R090 S0      
327m4295            PEX3  -A33        A01X+163602Y+125472X0180Y         S1      
327m4296            U13   -1          A18X+027559Y+045163X0240Y0240R270 S2      
327m4296            R54   -1          A18X+028223Y+046324X0198Y0197     S2      
317m4296            VIA   -    M      A01X+028223Y+045857X0200Y         S2      
017m4296            VIA   -    M      A18X+028223Y+045857X0260Y         S2      
017m4296                  -    MD0100PA00X+028223Y+045857                       
327m4296            J21   -B12        A01X+028842Y+045604X0140Y0480R090 S1      
327PU_CLKREQ11      J41   -A11        A01X+126325Y+009760X0150Y0500R090 S1      
317PU_CLKREQ11      VIA   -    M      A01X+125670Y+009767X0200Y         S2      
017PU_CLKREQ11      VIA   -    M      A18X+125670Y+009767X0260Y         S2      
017PU_CLKREQ11            -    MD0100PA00X+125670Y+009767                       
327PU_CLKREQ11      R444  -2          A01X+125343Y+009767X0198Y0197     S1      
327m4297            J20   -B33        A01X+018127Y+048644X0140Y0480R270 S1      
327m4297            C44   -2          A01X+014530Y+048706X0120Y0150     S1      
317m4298            VIA   -    MD0080PA01X+109291Y+108268X0160Y    R270 S0      
327m4298            PEX2  -BG10       A01X+109291Y+108268X0180Y         S1      
327m4298            J38   -A23        A01X+095616Y+012594X0150Y0500R090 S1      
317m4298            VIA   -    MD0100PA01X+094986Y+012543X0200Y         S0      
317m4299            VIA   -    MD0100PA01X+134049Y+138430X0180Y         S0      
317m4299            J13   -O6   D0122PA01X+134839Y+150902X0282Y    R180 S3      
327m4299            C577  -2          A01X+134039Y+137939X0120Y0150R090 S1      
317m4300            VIA   -    MD0100PA01X+154705Y+138430X0180Y         S0      
317m4300            J14   -S3   D0122PA01X+149563Y+148933X0282Y    R180 S3      
327m4300            C740  -2          A01X+154695Y+137939X0120Y0150R090 S1      
317PRSNTB2_NIC1_N   VIA   -    M      A01X+026196Y+045846X0200Y         S2      
017PRSNTB2_NIC1_N   VIA   -    M      A18X+026196Y+045846X0260Y         S2      
017PRSNTB2_NIC1_N         -    MD0100PA00X+026196Y+045846                       
327PRSNTB2_NIC1_N   J21   -A12        A01X+027030Y+045604X0140Y0480R090 S1      
327PRSNTB2_NIC1_N   R92   -2          A01X+025228Y+046286X0198Y0197     S1      
327PRSNTB2_NIC1_N   R58   -1   M      A01X+025228Y+045886X0198Y0197R180 S1      
327m4301            J40   -B9         A01X+117900Y+009287X0150Y0500R090 S1      
317m4301            VIA   -    M      A01X+118373Y+009287X0200Y         S2      
017m4301            VIA   -    M      A18X+118373Y+009287X0260Y         S2      
017m4301                  -    MD0100PA00X+118373Y+009287                       
327m4301            R440  -2          A01X+119956Y+009820X0198Y0197R270 S1      
327m4301            R439  -2   M      A01X+119556Y+009820X0198Y0197R270 S1      
327m4302            J20   -B30        A01X+018127Y+049352X0140Y0480R270 S1      
327m4302            C42   -2          A01X+015570Y+049417X0120Y0150     S1      
317m4303            VIA   -    MD0100PA01X+024162Y+136010X0180Y         S0      
317m4303            J11   -D1   D0122PA01X+028311Y+160705X0282Y    R180 S3      
327m4303            C129  -2          A01X+024152Y+135519X0120Y0150R090 S1      
317m4304            VIA   -    MD0080PA01X+108917Y+107520X0160Y    R270 S0      
327m4304            J38   -A26        A01X+095616Y+013303X0150Y0500R090 S1      
317m4304            VIA   -    MD0100PA01X+094256Y+013252X0200Y         S0      
327m4304            PEX2  -BJ9        A01X+108917Y+107520X0180Y         S1      
317m4305            VIA   -    MD0100PA01X+123373Y+136010X0180Y         S0      
317m4305            J13   -C1   D0122PA01X+130508Y+161217X0282Y    R180 S3      
327m4305            C552  -2          A01X+123383Y+135519X0120Y0150R090 S1      
317m4306            J14   -Y1   D0122PA01X+147831Y+145862X0282Y    R180 S3      
317m4306            VIA   -    MD0080PA01X+163228Y+124350X0160Y         S0      
327m4306            PEX3  -D32        A01X+163228Y+124350X0180Y         S1      
317NIC1_SLOT_ID0    VIA   -    M      A01X+029909Y+039791X0200Y         S2      
017NIC1_SLOT_ID0    VIA   -    M      A18X+029909Y+039791X0260Y         S2      
017NIC1_SLOT_ID0          -    MD0100PA00X+029909Y+039791                       
327NIC1_SLOT_ID0    J21   -OB7        A01X+028842Y+039622X0140Y0480R090 S1      
327NIC1_SLOT_ID0    R77   -1          A18X+030371Y+039392X0198Y0197R180 S2      
327NIC1_SLOT_ID0    R76   -1   M      A18X+030371Y+039791X0198Y0197R180 S2      
327P3V3_SSD10       R898  -1          A01X+115110Y+023613X0198Y0197R270 S1      
317P3V3_SSD10       VIA   -    MD0100PA00X+115110Y+023871X0200Y    R090 S0      
327P3V3_SSD10       PU66  -1          A01X+114111Y+021324X0110Y0240     S1      
327P3V3_SSD10       PU66  -2          A01X+114307Y+021324X0110Y0240     S1      
327P3V3_SSD10       PU66  -3          A01X+114504Y+021324X0110Y0240     S1      
327P3V3_SSD10       PU66  -4          A01X+114701Y+021324X0110Y0240     S1      
327P3V3_SSD10       PU66  -5          A01X+114898Y+021324X0110Y0240     S1      
327P3V3_SSD10       VIA   -           A18X+114446Y+019873X0260Y         S2      
327P3V3_SSD10       PC573 -1          A01X+114464Y+020064X0400Y0500     S1      
327P3V3_SSD10       PC572 -1          A01X+114357Y+020686X0198Y0197R180 S1      
327P3V3_SSD10       PD72  -C          A01X+114943Y+018984X0670Y0990R090 S1      
317P3V3_SSD10       VIA   -    MD0100PA00X+114848Y+020175X0200Y    R090 S0      
317P3V3_SSD10       VIA   -    MD0100PA00X+114882Y+020681X0200Y    R180 S0      
317P3V3_SSD10       VIA   -    MD0100PA00X+114704Y+021051X0200Y    R180 S0      
317P3V3_SSD10       VIA   -    MD0100PA00X+114454Y+021051X0200Y    R180 S0      
317P3V3_SSD10       VIA   -    MD0100PA00X+114632Y+020681X0200Y    R180 S0      
317P3V3_SSD10       VIA   -    MD0100PA00X+115148Y+020205X0200Y    R090 S0      
317P3V3_SSD10       VIA   -    MD0100PA00X+115196Y+019518X0200Y    R180 S0      
317P3V3_SSD10       VIA   -    MD0100PA00X+114696Y+019518X0200Y    R180 S0      
317P3V3_SSD10       VIA   -    MD0100PA00X+114446Y+019518X0200Y    R180 S0      
317P3V3_SSD10       VIA   -    M      A01X+115148Y+019925X0200Y    R090 S2      
017P3V3_SSD10       VIA   -    M      A18X+115148Y+019925X0260Y    R090 S2      
017P3V3_SSD10             -    MD0100PA00X+115148Y+019925                       
317P3V3_SSD10       VIA   -    MD0100PA00X+114848Y+019925X0200Y    R090 S0      
317P3V3_SSD10       VIA   -    MD0100PA00X+114946Y+019518X0200Y    R180 S0      
327P3V3_SSD10       R6098 -1          A01X+109074Y+014754X0198Y0197     S1      
317P3V3_SSD10       VIA   -    MD0100PA00X+108796Y+014754X0200Y         S0      
327P3V3_SSD10       R5755 -1          A01X+120506Y+010824X0198Y0197R270 S1      
317P3V3_SSD10       VIA   -    MD0100PA00X+120249Y+010619X0200Y    R090 S0      
327P3V3_SSD10       R439  -1          A01X+119556Y+010135X0198Y0197R270 S1      
317P3V3_SSD10       VIA   -    MD0100PA00X+119556Y+010378X0200Y    R270 S0      
317P3V3_SSD10       VIA   -    MD0100PA00X+113587Y+011659X0200Y         S0      
317P3V3_SSD10       VIA   -    MD0100PA00X+113587Y+011959X0200Y         S0      
327P3V3_SSD10       PU129 -6_7        A01X+113133Y+011762X0295Y0354R270 S1      
327P3V3_SSD10       R5691 -2          A01X+114132Y+013484X0198Y0197     S1      
327P3V3_SSD10       PC951 -1   M      A01X+114013Y+011967X0400Y0500R090 S1      
327P3V3_SSD10       C975  -2   M      A01X+118947Y+009855X0198Y0197R270 S1      
317P3V3_SSD10       VIA   -    MD0100PA00X+119201Y+009855X0200Y    R090 S0      
327P3V3_SSD10       J40   -B11        A01X+117900Y+009760X0150Y0500R090 S1      
327P3V3_SSD10       R441  -1          A01X+114792Y+009767X0198Y0197     S1      
317P3V3_SSD10       VIA   -    M      A01X+114548Y+009767X0200Y         S2      
017P3V3_SSD10       VIA   -    M      A18X+114548Y+009767X0260Y         S2      
017P3V3_SSD10             -    MD0100PA00X+114548Y+009767                       
327P3V3_SSD10       R1703 -1          A01X+121361Y+008058X0198Y0197R180 S1      
317P3V3_SSD10       VIA   -    MD0100PA00X+121602Y+008058X0200Y         S0      
327P3V3_SSD10       R1702 -1          A01X+121361Y+006858X0198Y0197R180 S1      
317P3V3_SSD10       VIA   -    MD0100PA00X+121601Y+006858X0200Y         S0      
327P3V3_SSD10       C2732 -2   M      A01X+121978Y+005801X0198Y0197R180 S1      
327P3V3_SSD10       U136  -1          A01X+121953Y+006472X0240Y0460R180 S1      
317P3V3_SSD10       VIA   -    MD0100PA00X+121978Y+005551X0200Y         S0      
317m4307            VIA   -    MD0100PA01X+020568Y+042983X0200Y    R180 S0      
327m4307            J20   -A50        A01X+019938Y+042931X0140Y0480R270 S1      
317m4307            VIA   -    MD0080PA01X+025354Y+108268X0160Y         S0      
327m4307            PEX0  -BG30       A01X+025354Y+108268X0180Y         S1      
317m4308            J11   -V1   D0122PA01X+028311Y+147398X0282Y    R180 S3      
317m4308            VIA   -    MD0080PA01X+020118Y+124350X0160Y         S0      
327m4308            PEX0  -D16        A01X+020118Y+124350X0180Y         S1      
327m4309            C504  -2          A01X+119830Y+013241X0120Y0150R180 S1      
327m4309            J40   -B26        A01X+117900Y+013303X0150Y0500R090 S1      
317m4310            VIA   -    MD0100PA01X+130377Y+140850X0180Y         S0      
317m4310            J13   -O2   D0122PA01X+131374Y+150902X0282Y    R180 S3      
327m4310            C569  -2          A01X+130367Y+140359X0120Y0150R090 S1      
317m4311            J14   -L3   D0122PA01X+149563Y+156610X0282Y    R180 S3      
317m4311            VIA   -    MD0080PA01X+160984Y+124724X0160Y         S0      
327m4311            PEX3  -C26        A01X+160984Y+124724X0180Y         S1      
327NIC1_BIF0_N      J21   -B7         A01X+028842Y+044423X0140Y0480R090 S1      
317NIC1_BIF0_N      VIA   -    M      A01X+027878Y+043516X0200Y         S2      
017NIC1_BIF0_N      VIA   -    M      A18X+027878Y+043516X0260Y         S2      
017NIC1_BIF0_N            -    MD0100PA00X+027878Y+043516                       
327NIC1_BIF0_N      R80   -1          A18X+024408Y+042703X0198Y0197     S2      
327NIC1_BIF0_N      R81   -1   M      A18X+024797Y+042702X0198Y0197R180 S2      
327m4312            U38   -1          A18X+158372Y+055189X0240Y0240R180 S2      
327m4312            R309  -1   M      A18X+156207Y+054497X0198Y0197R180 S2      
317m4312            VIA   -    M      A01X+155659Y+054553X0200Y         S2      
017m4312            VIA   -    M      A18X+155659Y+054553X0260Y         S2      
017m4312                  -    MD0100PA00X+155659Y+054553                       
327m4312            J26   -B12        A01X+155253Y+054947X0140Y0480R270 S1      
327P3V3_SSD11       R901  -1          A01X+125346Y+023613X0198Y0197R270 S1      
317P3V3_SSD11       VIA   -    MD0100PA00X+125346Y+023871X0200Y    R090 S0      
327P3V3_SSD11       PU69  -1          A01X+124347Y+021324X0110Y0240     S1      
327P3V3_SSD11       PU69  -2          A01X+124544Y+021324X0110Y0240     S1      
327P3V3_SSD11       PU69  -3          A01X+124740Y+021324X0110Y0240     S1      
327P3V3_SSD11       PU69  -4          A01X+124937Y+021324X0110Y0240     S1      
327P3V3_SSD11       PU69  -5          A01X+125134Y+021324X0110Y0240     S1      
327P3V3_SSD11       VIA   -           A18X+124683Y+019873X0260Y         S2      
327P3V3_SSD11       PC586 -1          A01X+124700Y+020064X0400Y0500     S1      
327P3V3_SSD11       PC585 -1          A01X+124593Y+020686X0198Y0197R180 S1      
327P3V3_SSD11       PD75  -C          A01X+125179Y+018984X0670Y0990R090 S1      
317P3V3_SSD11       VIA   -    MD0100PA00X+124691Y+021051X0200Y    R180 S0      
317P3V3_SSD11       VIA   -    MD0100PA00X+124868Y+020681X0200Y    R180 S0      
317P3V3_SSD11       VIA   -    MD0100PA00X+125118Y+020681X0200Y    R180 S0      
317P3V3_SSD11       VIA   -    MD0100PA00X+125084Y+020175X0200Y    R090 S0      
317P3V3_SSD11       VIA   -    MD0100PA00X+125384Y+020205X0200Y    R090 S0      
317P3V3_SSD11       VIA   -    MD0100PA00X+124941Y+021051X0200Y    R180 S0      
317P3V3_SSD11       VIA   -    MD0100PA00X+124683Y+019518X0200Y    R180 S0      
317P3V3_SSD11       VIA   -    MD0100PA00X+125084Y+019925X0200Y    R090 S0      
317P3V3_SSD11       VIA   -    MD0100PA00X+124933Y+019518X0200Y    R180 S0      
317P3V3_SSD11       VIA   -    M      A01X+125384Y+019925X0200Y    R090 S2      
017P3V3_SSD11       VIA   -    M      A18X+125384Y+019925X0260Y    R090 S2      
017P3V3_SSD11             -    MD0100PA00X+125384Y+019925                       
317P3V3_SSD11       VIA   -    MD0100PA00X+125433Y+019518X0200Y    R180 S0      
317P3V3_SSD11       VIA   -    MD0100PA00X+125183Y+019518X0200Y    R180 S0      
327P3V3_SSD11       R6099 -1          A01X+119310Y+014754X0198Y0197     S1      
317P3V3_SSD11       VIA   -    MD0100PA00X+119032Y+014754X0200Y         S0      
327P3V3_SSD11       R5757 -1          A01X+130742Y+010824X0198Y0197R270 S1      
317P3V3_SSD11       VIA   -    MD0100PA00X+130485Y+010619X0200Y    R090 S0      
327P3V3_SSD11       R442  -1          A01X+129792Y+010135X0198Y0197R270 S1      
317P3V3_SSD11       VIA   -    MD0100PA00X+129792Y+010378X0200Y    R270 S0      
317P3V3_SSD11       VIA   -    MD0100PA00X+123823Y+011659X0200Y         S0      
317P3V3_SSD11       VIA   -    MD0100PA00X+123823Y+011959X0200Y         S0      
327P3V3_SSD11       PU130 -6_7        A01X+123369Y+011762X0295Y0354R270 S1      
327P3V3_SSD11       PC953 -1   M      A01X+124250Y+011967X0400Y0500R090 S1      
327P3V3_SSD11       R5688 -2          A01X+124368Y+013484X0198Y0197     S1      
327P3V3_SSD11       C976  -2   M      A01X+129184Y+009855X0198Y0197R270 S1      
317P3V3_SSD11       VIA   -    MD0100PA00X+129437Y+009855X0200Y    R090 S0      
327P3V3_SSD11       J41   -B11        A01X+128136Y+009760X0150Y0500R090 S1      
327P3V3_SSD11       R444  -1          A01X+125028Y+009767X0198Y0197     S1      
317P3V3_SSD11       VIA   -    M      A01X+124785Y+009767X0200Y         S2      
017P3V3_SSD11       VIA   -    M      A18X+124785Y+009767X0260Y         S2      
017P3V3_SSD11             -    MD0100PA00X+124785Y+009767                       
327P3V3_SSD11       R1706 -1          A01X+132285Y+003994X0198Y0197R090 S1      
317P3V3_SSD11       VIA   -    MD0100PA00X+132285Y+003753X0200Y    R270 S0      
327P3V3_SSD11       R1705 -1          A01X+131085Y+003994X0198Y0197R090 S1      
317P3V3_SSD11       VIA   -    MD0100PA00X+131085Y+003754X0200Y    R270 S0      
327P3V3_SSD11       U137  -1          A01X+130699Y+003402X0240Y0460R090 S1      
327P3V3_SSD11       C2734 -2   M      A01X+130028Y+003377X0198Y0197R090 S1      
317P3V3_SSD11       VIA   -    MD0100PA00X+129778Y+003377X0200Y    R270 S0      
327m4313            C51   -2          A01X+015570Y+043342X0120Y0150     S1      
327m4313            J20   -B48        A01X+018127Y+043404X0140Y0480R270 S1      
317m4314            J11   -T6   D0122PA01X+032642Y+148343X0282Y    R180 S3      
317m4314            VIA   -    MD0080PA01X+021988Y+125472X0160Y         S0      
327m4314            PEX0  -A21        A01X+021988Y+125472X0180Y         S1      
327m4315            J41   -B26        A01X+128136Y+013303X0150Y0500R090 S1      
327m4315            C512  -2          A01X+130066Y+013241X0120Y0150R180 S1      
317m4316            J13   -U7   D0122PA01X+135705Y+147910X0282Y    R180 S3      
317m4316            VIA   -    MD0080PA01X+113780Y+124724X0160Y         S0      
327m4316            PEX2  -C22        A01X+113780Y+124724X0180Y         S1      
317m4317            VIA   -    MD0100PA01X+158377Y+138430X0180Y         S0      
317m4317            J14   -F8   D0122PA01X+153894Y+159602X0282Y    R180 S3      
327m4317            C746  -2          A01X+158367Y+137939X0120Y0150R090 S1      
327NIC1_BIF2_N      VIA   -    M      A18X+025800Y+043300X0260Y         S2      
317NIC1_BIF2_N      VIA   -    MD0100PA00X+027883Y+044484X0200Y         S0      
327NIC1_BIF2_N      R84   -1          A18X+024408Y+043503X0198Y0197     S2      
327NIC1_BIF2_N      R85   -1   M      A18X+024793Y+043503X0198Y0197R180 S2      
327NIC1_BIF2_N      J21   -B9         A01X+028842Y+044896X0140Y0480R090 S1      
317m4318            VIA   -    MD0100PA01X+020568Y+049404X0200Y    R180 S0      
327m4318            J20   -A30        A01X+019938Y+049352X0140Y0480R270 S1      
317m4318            VIA   -    MD0080PA01X+027598Y+108268X0160Y         S0      
327m4318            PEX0  -BG36       A01X+027598Y+108268X0180Y         S1      
317m4319            VIA   -    MD0100PA01X+033954Y+136010X0180Y         S0      
317m4319            J11   -O4   D0122PA01X+030909Y+150902X0282Y    R180 S3      
327m4319            C151  -2          A01X+033944Y+135519X0120Y0150R090 S1      
327m4320            C490  -2          A01X+098317Y+012530X0120Y0150R180 S1      
327m4320            J38   -B23        A01X+097427Y+012594X0150Y0500R090 S1      
317m4321            J13   -U1   D0122PA01X+130508Y+147910X0282Y    R180 S3      
317m4321            VIA   -    MD0080PA01X+111535Y+124724X0160Y         S0      
327m4321            PEX2  -C16        A01X+111535Y+124724X0180Y         S1      
317m4322            VIA   -    MD0100PA01X+153821Y+140850X0180Y         S0      
317m4322            J14   -Q2   D0122PA01X+148697Y+149878X0282Y    R180 S3      
327m4322            C743  -2          A01X+153831Y+140359X0120Y0150R090 S1      
317NCSI_NIC1_RXD0   VIA   -    M      A01X+029600Y+040350X0200Y         S2      
017NCSI_NIC1_RXD0   VIA   -    M      A18X+029600Y+040350X0260Y         S2      
017NCSI_NIC1_RXD0         -    MD0100PA00X+029600Y+040350                       
327NCSI_NIC1_RXD0   J21   -OB9        A01X+028842Y+040094X0140Y0480R090 S1      
327NCSI_NIC1_RXD0   R67   -1          A18X+030371Y+040592X0198Y0197R180 S2      
327m4323            C53   -2          A01X+014530Y+042636X0120Y0150     S1      
327m4323            J20   -B51        A01X+018127Y+042695X0140Y0480R270 S1      
317m4324            J11   -T4   D0122PA01X+030909Y+148343X0282Y    R180 S3      
317m4324            VIA   -    MD0080PA01X+021240Y+125472X0160Y         S0      
327m4324            PEX0  -A19        A01X+021240Y+125472X0180Y         S1      
317m4325            VIA   -    MD0080PA01X+111535Y+108268X0160Y    R270 S0      
327m4325            PEX2  -BG16       A01X+111535Y+108268X0180Y         S1      
327m4325            J39   -A17        A01X+105852Y+011177X0150Y0500R090 S1      
317m4325            VIA   -    MD0100PA01X+105222Y+011126X0200Y         S0      
317m4326            J13   -U4   D0122PA01X+133106Y+147831X0282Y    R180 S3      
317m4326            VIA   -    MD0080PA01X+112657Y+125098X0160Y         S0      
327m4326            PEX2  -B19        A01X+112657Y+125098X0180Y         S1      
317m4327            VIA   -    MD0100PA01X+020568Y+053478X0200Y    R180 S0      
327m4327            J20   -A18        A01X+019938Y+053530X0140Y0480R270 S1      
317m4327            VIA   -    MD0080PA01X+029094Y+108642X0160Y         S0      
327m4327            PEX0  -BF40       A01X+029094Y+108642X0180Y         S1      
317m4328            J11   -U3   D0122PA01X+030043Y+147910X0282Y    R180 S3      
317m4328            VIA   -    MD0080PA01X+020866Y+124724X0160Y         S0      
327m4328            PEX0  -C18        A01X+020866Y+124724X0180Y         S1      
327m4329            J41   -B24        A01X+128136Y+012831X0150Y0500R090 S1      
327m4329            C513  -2          A01X+129026Y+012890X0120Y0150R180 S1      
317m4330            J13   -U8   D0122PA01X+136571Y+147831X0282Y    R180 S3      
317m4330            VIA   -    MD0080PA01X+114154Y+125098X0160Y         S0      
327m4330            PEX2  -B23        A01X+114154Y+125098X0180Y         S1      
327m4331            R351  -1          A01X+157224Y+065316X0198Y0197R090 S1      
317m4331            VIA   -    M      A01X+157189Y+064938X0200Y         S2      
017m4331            VIA   -    M      A18X+157189Y+064938X0260Y         S2      
017m4331                  -    MD0100PA00X+157189Y+064938                       
317m4331            VIA   -    MD0100PA00X+156532Y+057772X0200Y         S0      
327m4331            J26   -B10        A01X+155253Y+055419X0140Y0480R270 S1      
327m4332            J20   -B26        A01X+018127Y+051640X0140Y0480R270 S1      
327m4332            C40   -2          A01X+014530Y+051702X0120Y0150     S1      
317m4333            VIA   -    MD0100PA01X+025386Y+138430X0180Y         S0      
317m4333            J11   -C2   D0122PA01X+029177Y+161138X0282Y    R180 S3      
327m4333            C131  -2          A01X+025376Y+137939X0120Y0150R090 S1      
317m4334            VIA   -    MD0080PA01X+112657Y+107520X0160Y    R270 S0      
327m4334            J40   -A20        A01X+116088Y+011886X0150Y0500R090 S1      
317m4334            VIA   -    MD0100PA01X+114728Y+011834X0200Y         S0      
327m4334            PEX2  -BJ19       A01X+112657Y+107520X0180Y         S1      
317m4335            VIA   -    MD0100PA01X+125821Y+136010X0180Y         S0      
317m4335            J13   -C3   D0122PA01X+132240Y+161217X0282Y    R180 S3      
327m4335            C556  -2          A01X+125831Y+135519X0120Y0150R090 S1      
327NIC6_LD_N        VIA   -    M      A01X+152948Y+062595X0300Y         S1      
327NIC6_LD_N        J26   -OB3        A01X+155253Y+061874X0140Y0480R270 S1      
327NIC6_LD_N        R317  -1          A01X+152484Y+062360X0198Y0197R180 S1      
327m4336            C55   -2          A01X+015570Y+041925X0120Y0150     S1      
327m4336            J20   -B54        A01X+018127Y+041986X0140Y0480R270 S1      
317m4337            VIA   -    MD0100PA01X+031506Y+136010X0180Y         S0      
317m4337            J11   -P1   D0122PA01X+028311Y+150468X0282Y    R180 S3      
327m4337            C145  -2          A01X+031496Y+135519X0120Y0150R090 S1      
327m4338            C496  -2          A01X+109594Y+013241X0120Y0150R180 S1      
327m4338            J39   -B26        A01X+107663Y+013303X0150Y0500R090 S1      
317m4339            J13   -I7   D0122PA01X+135705Y+158146X0282Y    R180 S3      
317m4339            VIA   -    MD0080PA01X+110787Y+124724X0160Y         S0      
327m4339            PEX2  -C14        A01X+110787Y+124724X0180Y         S1      
327NIC6_BIF0_N      VIA   -    M      A01X+153024Y+056437X0300Y         S1      
327NIC6_BIF0_N      J26   -B7         A01X+155253Y+056128X0140Y0480R270 S1      
327NIC6_BIF0_N      R336  -1   M      A01X+152240Y+056257X0198Y0197     S1      
327NIC6_BIF0_N      R335  -1          A01X+151852Y+056256X0198Y0197R180 S1      
327m4340            J20   -B24        A01X+018127Y+052112X0140Y0480R270 S1      
327m4340            C37   -2          A01X+015570Y+052053X0120Y0150     S1      
317m4341            VIA   -    MD0100PA01X+035518Y+138430X0180Y         S0      
317m4341            J11   -N6   D0122PA01X+032642Y+151413X0282Y    R180 S3      
327m4341            C156  -2          A01X+035528Y+137939X0120Y0150R090 S1      
327m4342            J41   -B23        A01X+128136Y+012594X0150Y0500R090 S1      
327m4342            C514  -2          A01X+129026Y+012530X0120Y0150R180 S1      
317m4343            J13   -J5   D0122PA01X+133972Y+157634X0282Y    R180 S3      
317m4343            VIA   -    MD0080PA01X+110039Y+124350X0160Y         S0      
327m4343            PEX2  -D12        A01X+110039Y+124350X0180Y         S1      
317m4344            VIA   -    M      A01X+158035Y+061632X0200Y         S2      
017m4344            VIA   -    M      A18X+158035Y+061632X0260Y         S2      
017m4344                  -    MD0100PA00X+158035Y+061632                       
327m4344            R307  -1          A18X+156478Y+061840X0198Y0197R180 S2      
327m4344            J26   -OA5        A01X+157064Y+061402X0140Y0480R270 S1      
317m4345            VIA   -    MD0080PA01X+026102Y+108642X0160Y         S0      
327m4345            PEX0  -BF32       A01X+026102Y+108642X0180Y         S1      
317m4345            VIA   -    MD0100PA01X+020568Y+044060X0200Y    R180 S0      
327m4345            J20   -A45        A01X+019938Y+044112X0140Y0480R270 S1      
317m4346            VIA   -    MD0080PA01X+110413Y+107520X0160Y    R270 S0      
327m4346            J39   -A26        A01X+105852Y+013303X0150Y0500R090 S1      
317m4346            VIA   -    MD0100PA01X+104492Y+013252X0200Y         S0      
327m4346            PEX2  -BJ13       A01X+110413Y+107520X0180Y         S1      
317m4347            VIA   -    MD0100PA01X+128269Y+140850X0180Y         S0      
317m4347            J13   -C7   D0122PA01X+135705Y+161217X0282Y    R180 S3      
327m4347            C564  -2          A01X+128279Y+140359X0120Y0150R090 S1      
327m4348            J26   -B45        A01X+155253Y+044112X0140Y0480R270 S1      
327m4348            C682  -2          A01X+151656Y+044053X0120Y0150     S1      
327NIC6_SLOT_ID0    VIA   -    M      A01X+152948Y+060619X0300Y         S1      
327NIC6_SLOT_ID0    R332  -1          A01X+152480Y+060759X0198Y0197R180 S1      
327NIC6_SLOT_ID0    R331  -1   M      A01X+152484Y+060360X0198Y0197R180 S1      
327NIC6_SLOT_ID0    J26   -OB7        A01X+155253Y+060929X0140Y0480R270 S1      
327m4349            C54   -2          A01X+014530Y+042996X0120Y0150     S1      
327m4349            J20   -B50        A01X+018127Y+042931X0140Y0480R270 S1      
317m4350            VIA   -    MD0100PA01X+033070Y+138430X0180Y         S0      
317m4350            J11   -O3   D0122PA01X+030043Y+150980X0282Y    R180 S3      
327m4350            C150  -2          A01X+033080Y+137939X0120Y0150R090 S1      
317m4351            VIA   -    MD0080PA01X+111909Y+107894X0160Y    R270 S0      
327m4351            J40   -A27        A01X+116088Y+013539X0150Y0500R090 S1      
317m4351            VIA   -    MD0100PA01X+114728Y+013592X0200Y         S0      
327m4351            PEX2  -BH17       A01X+111909Y+107894X0180Y         S1      
317m4352            VIA   -    MD0100PA01X+135273Y+136010X0180Y         S0      
317m4352            J13   -P7   D0122PA01X+135705Y+150468X0282Y    R180 S3      
327m4352            C579  -2          A01X+135263Y+135519X0120Y0150R090 S1      
327m4353            J26   -B20        A01X+155253Y+053057X0140Y0480R270 S1      
327m4353            C669  -2          A01X+151656Y+053119X0120Y0150     S1      
327m4354            R352  -1          A01X+157624Y+065316X0198Y0197R090 S1      
317m4354            VIA   -    MD0100PA00X+157488Y+064589X0200Y         S0      
327m4354            J26   -A11        A01X+157064Y+055183X0140Y0480R270 S1      
317m4354            VIA   -    M      A01X+157786Y+055412X0200Y    R180 S2      
017m4354            VIA   -    M      A18X+157786Y+055412X0260Y    R180 S2      
017m4354                  -    MD0100PA00X+157786Y+055412                       
317m4355            VIA   -    MD0100PA01X+021298Y+040517X0200Y    R180 S0      
327m4355            J20   -A60        A01X+019938Y+040569X0140Y0480R270 S1      
317m4355            VIA   -    MD0080PA01X+024232Y+107894X0160Y         S0      
327m4355            PEX0  -BH27       A01X+024232Y+107894X0180Y         S1      
317m4356            VIA   -    MD0100PA01X+031846Y+140850X0180Y         S0      
317m4356            J11   -N2   D0122PA01X+029177Y+151413X0282Y    R180 S3      
327m4356            C148  -2          A01X+031856Y+140359X0120Y0150R090 S1      
327m4357            C491  -2          A01X+099357Y+012184X0120Y0150R180 S1      
327m4357            J38   -B21        A01X+097427Y+012122X0150Y0500R090 S1      
317m4358            VIA   -    MD0100PA01X+130717Y+140850X0180Y         S0      
317m4358            J13   -N2   D0122PA01X+131374Y+151413X0282Y    R180 S3      
327m4358            C570  -2          A01X+130727Y+140359X0120Y0150R090 S1      
327m4359            J26   -B31        A01X+155253Y+049116X0140Y0480R270 S1      
327m4359            C674  -2          A01X+152696Y+049057X0120Y0150     S1      
327m4360            VIA   -    M      A01X+152982Y+063798X0300Y         S1      
327m4360            R310  -1          A01X+152484Y+064197X0198Y0197R180 S1      
327m4360            R328  -1   M      A01X+152484Y+063797X0198Y0197R180 S1      
327m4360            J26   -OB1        A01X+155253Y+062346X0140Y0480R270 S1      
317m4361            VIA   -    MD0100PA01X+021298Y+041934X0200Y    R180 S0      
327m4361            J20   -A54        A01X+019938Y+041986X0140Y0480R270 S1      
317m4361            VIA   -    MD0080PA01X+024980Y+107894X0160Y         S0      
327m4361            PEX0  -BH29       A01X+024980Y+107894X0180Y         S1      
317m4362            VIA   -    MD0080PA01X+110787Y+108642X0160Y    R270 S0      
327m4362            J39   -A24        A01X+105852Y+012831X0150Y0500R090 S1      
317m4362            VIA   -    MD0100PA01X+105222Y+012883X0200Y         S0      
327m4362            PEX2  -BF14       A01X+110787Y+108642X0180Y         S1      
317m4363            VIA   -    MD0100PA01X+132825Y+140850X0180Y         S0      
317m4363            J13   -P5   D0122PA01X+133972Y+150468X0282Y    R180 S3      
327m4363            C575  -2          A01X+132815Y+140359X0120Y0150R090 S1      
327m4364            J26   -B66        A01X+155253Y+039152X0140Y0480R270 S1      
327m4364            C696  -2          A01X+152696Y+039090X0120Y0150     S1      
317NCSI_NIC6_TXD0   VIA   -    M      A01X+157926Y+060457X0200Y         S2      
017NCSI_NIC6_TXD0   VIA   -    M      A18X+157926Y+060457X0260Y         S2      
017NCSI_NIC6_TXD0         -    MD0100PA00X+157926Y+060457                       
327NCSI_NIC6_TXD0   R324  -1          A18X+156794Y+059840X0198Y0197     S2      
327NCSI_NIC6_TXD0   J26   -OA9        A01X+157064Y+060457X0140Y0480R270 S1      
327m4365            C59   -2          A01X+015570Y+040507X0120Y0150     S1      
327m4365            J20   -B60        A01X+018127Y+040569X0140Y0480R270 S1      
317m4366            VIA   -    MD0080PA01X+109665Y+107520X0160Y    R270 S0      
327m4366            J38   -A20        A01X+095616Y+011886X0150Y0500R090 S1      
317m4366            VIA   -    MD0100PA01X+094256Y+011834X0200Y         S0      
327m4366            PEX2  -BJ11       A01X+109665Y+107520X0180Y         S1      
317m4367            VIA   -    MD0100PA01X+128269Y+136010X0180Y         S0      
317m4367            J13   -B6   D0122PA01X+134839Y+161650X0282Y    R180 S3      
327m4367            C562  -2          A01X+128279Y+135519X0120Y0150R090 S1      
317m4368            VIA   -    MD0080PA01X+162106Y+107520X0160Y         S0      
327m4368            PEX3  -BJ29       A01X+162106Y+107520X0180Y         S1      
317m4368            VIA   -    MD0100PA01X+158424Y+042274X0200Y    R180 S0      
327m4368            J26   -A53        A01X+157064Y+042222X0140Y0480R270 S1      
327PRSNTB2_NIC6_N   VIA   -    M      A01X+158492Y+054947X0300Y         S1      
327PRSNTB2_NIC6_N   J26   -A12        A01X+157064Y+054947X0140Y0480R270 S1      
327PRSNTB2_NIC6_N   R347  -2          A01X+158968Y+054580X0198Y0197R180 S1      
327PRSNTB2_NIC6_N   R312  -1   M      A01X+158968Y+054980X0198Y0197     S1      
327m4369            J20   -B23        A01X+018127Y+052348X0140Y0480R270 S1      
327m4369            C38   -2          A01X+015570Y+052413X0120Y0150     S1      
317m4370            VIA   -    MD0100PA01X+032730Y+138430X0180Y         S0      
317m4370            J11   -P3   D0122PA01X+030043Y+150468X0282Y    R180 S3      
327m4370            C149  -2          A01X+032720Y+137939X0120Y0150R090 S1      
327m4371            C506  -2          A01X+118790Y+012530X0120Y0150R180 S1      
327m4371            J40   -B23        A01X+117900Y+012594X0150Y0500R090 S1      
317m4372            J13   -J7   D0122PA01X+135705Y+157634X0282Y    R180 S3      
317m4372            VIA   -    MD0080PA01X+110787Y+124350X0160Y         S0      
327m4372            PEX2  -D14        A01X+110787Y+124350X0180Y         S1      
317m4373            VIA   -    MD0080PA01X+165846Y+107894X0160Y         S0      
327m4373            PEX3  -BH39       A01X+165846Y+107894X0180Y         S1      
317m4373            VIA   -    MD0100PA01X+158424Y+052769X0200Y    R180 S0      
327m4373            J26   -A21        A01X+157064Y+052821X0140Y0480R270 S1      
317m4374            VIA   -    MD0100PA01X+034294Y+136010X0180Y         S0      
317m4374            J11   -N4   D0122PA01X+030909Y+151413X0282Y    R180 S3      
327m4374            C152  -2          A01X+034304Y+135519X0120Y0150R090 S1      
327m4375            C510  -2          A01X+118790Y+011112X0120Y0150R180 S1      
327m4375            J40   -B17        A01X+117900Y+011177X0150Y0500R090 S1      
317m4376            J13   -V1   D0122PA01X+130508Y+147398X0282Y    R180 S3      
317m4376            VIA   -    MD0080PA01X+111535Y+124350X0160Y         S0      
327m4376            PEX2  -D16        A01X+111535Y+124350X0180Y         S1      
327m4377            J26   -B56        A01X+155253Y+041514X0140Y0480R270 S1      
327m4377            C691  -2          A01X+151656Y+041579X0120Y0150     S1      
327m4378            VIA   -    M      A01X+153028Y+059139X0300Y         S1      
327m4378            R321  -1          A01X+152480Y+059159X0198Y0197R180 S1      
327m4378            J26   -OB14       A01X+155253Y+059276X0140Y0480R270 S1      
317m4379            J11   -U6   D0122PA01X+032642Y+147831X0282Y    R180 S3      
317m4379            VIA   -    MD0080PA01X+021988Y+125098X0160Y         S0      
327m4379            PEX0  -B21        A01X+021988Y+125098X0180Y         S1      
327m4380            C498  -2          A01X+108553Y+012530X0120Y0150R180 S1      
327m4380            J39   -B23        A01X+107663Y+012594X0150Y0500R090 S1      
317m4381            VIA   -    MD0100PA01X+132825Y+136010X0180Y         S0      
317m4381            J13   -O4   D0122PA01X+133106Y+150902X0282Y    R180 S3      
327m4381            C573  -2          A01X+132815Y+135519X0120Y0150R090 S1      
327m4382            J26   -B18        A01X+155253Y+053530X0140Y0480R270 S1      
327m4382            C666  -2          A01X+152696Y+053471X0120Y0150     S1      
317m4383            VIA   -    MD0100PA01X+026610Y+140850X0180Y         S0      
317m4383            J11   -C4   D0122PA01X+030909Y+161138X0282Y    R180 S3      
327m4383            C135  -2          A01X+026600Y+140359X0120Y0150R090 S1      
317m4384            VIA   -    MD0080PA01X+110787Y+108268X0160Y    R270 S0      
327m4384            J39   -A23        A01X+105852Y+012594X0150Y0500R090 S1      
317m4384            VIA   -    MD0100PA01X+105222Y+012543X0200Y         S0      
327m4384            PEX2  -BG14       A01X+110787Y+108268X0180Y         S1      
317m4385            J13   -U5   D0122PA01X+133972Y+147910X0282Y    R180 S3      
317m4385            VIA   -    MD0080PA01X+113031Y+124724X0160Y         S0      
327m4385            PEX2  -C20        A01X+113031Y+124724X0180Y         S1      
327m4386            J26   -B26        A01X+155253Y+051640X0140Y0480R270 S1      
327m4386            C673  -2          A01X+151656Y+051702X0120Y0150     S1      
317NCSI_NIC6_TXD1   VIA   -    M      A01X+157476Y+060693X0200Y         S2      
017NCSI_NIC6_TXD1   VIA   -    M      A18X+157476Y+060693X0260Y         S2      
017NCSI_NIC6_TXD1         -    MD0100PA00X+157476Y+060693                       
327NCSI_NIC6_TXD1   R325  -1          A18X+156794Y+060240X0198Y0197     S2      
327NCSI_NIC6_TXD1   J26   -OA8        A01X+157064Y+060693X0140Y0480R270 S1      
317m4387            J11   -U2   D0122PA01X+029177Y+147831X0282Y    R180 S3      
317m4387            VIA   -    MD0080PA01X+020492Y+125098X0160Y         S0      
327m4387            PEX0  -B17        A01X+020492Y+125098X0180Y         S1      
317m4388            VIA   -    MD0080PA01X+110413Y+107894X0160Y    R270 S0      
327m4388            J39   -A27        A01X+105852Y+013539X0150Y0500R090 S1      
317m4388            VIA   -    MD0100PA01X+104492Y+013592X0200Y         S0      
327m4388            PEX2  -BH13       A01X+110413Y+107894X0180Y         S1      
317m4389            J13   -I2   D0122PA01X+131374Y+158067X0282Y    R180 S3      
317m4389            VIA   -    MD0080PA01X+108917Y+125098X0160Y         S0      
327m4389            PEX2  -B9         A01X+108917Y+125098X0180Y         S1      
317m4390            VIA   -    MD0080PA01X+162480Y+108642X0160Y         S0      
327m4390            PEX3  -BF30       A01X+162480Y+108642X0180Y         S1      
317m4390            VIA   -    MD0100PA01X+157694Y+042643X0200Y    R180 S0      
327m4390            J26   -A51        A01X+157064Y+042695X0140Y0480R270 S1      
317m4391            VIA   -    M      A01X+076935Y+032452X0200Y         S2      
017m4391            VIA   -    M      A18X+076935Y+032452X0260Y         S2      
017m4391                  -    MD0100PA00X+076935Y+032452                       
327m4391            Q4    -6          A01X+076440Y+032185X0170Y0240R270 S1      
327m4391            R204  -1   M      A01X+076935Y+032189X0198Y0197R270 S1      
327m4391            U26   -1          A01X+077736Y+032884X0220Y0530R090 S1      
317m4392            J11   -V5   D0122PA01X+031776Y+147398X0282Y    R180 S3      
317m4392            VIA   -    MD0080PA01X+021614Y+124350X0160Y         S0      
327m4392            PEX0  -D20        A01X+021614Y+124350X0180Y         S1      
327m4393            C495  -2          A01X+109594Y+013601X0120Y0150R180 S1      
327m4393            J39   -B27        A01X+107663Y+013539X0150Y0500R090 S1      
317m4394            J13   -J3   D0122PA01X+132240Y+157634X0282Y    R180 S3      
317m4394            VIA   -    MD0080PA01X+109291Y+124350X0160Y         S0      
327m4394            PEX2  -D10        A01X+109291Y+124350X0180Y         S1      
327m4395            J26   -B17        A01X+155253Y+053766X0140Y0480R270 S1      
327m4395            C667  -2          A01X+152696Y+053831X0120Y0150     S1      
317m4396            VIA   -    M      A01X+157976Y+059550X0200Y         S2      
017m4396            VIA   -    M      A18X+157976Y+059550X0260Y         S2      
017m4396                  -    MD0100PA00X+157976Y+059550                       
327m4396            J26   -OA14       A01X+157064Y+059276X0140Y0480R270 S1      
327m4396            R326  -1          A18X+156794Y+059440X0198Y0197     S2      
317m4397            J11   -I1   D0122PA01X+028311Y+158146X0282Y    R180 S3      
317m4397            VIA   -    MD0080PA01X+017126Y+124724X0160Y         S0      
327m4397            PEX0  -C8         A01X+017126Y+124724X0180Y         S1      
317m4398            VIA   -    MD0080PA01X+112283Y+108642X0160Y    R270 S0      
327m4398            J40   -A24        A01X+116088Y+012831X0150Y0500R090 S1      
317m4398            VIA   -    MD0100PA01X+115458Y+012883X0200Y         S0      
327m4398            PEX2  -BF18       A01X+112283Y+108642X0180Y         S1      
317m4399            VIA   -    MD0100PA01X+124597Y+138430X0180Y         S0      
317m4399            J13   -B2   D0122PA01X+131374Y+161650X0282Y    R180 S3      
327m4399            C554  -2          A01X+124607Y+137939X0120Y0150R090 S1      
317m4400            VIA   -    MD0080PA01X+163976Y+108268X0160Y         S0      
327m4400            PEX3  -BG34       A01X+163976Y+108268X0180Y         S1      
317m4400            VIA   -    MD0100PA01X+157694Y+047987X0200Y    R180 S0      
327m4400            J26   -A36        A01X+157064Y+047935X0140Y0480R270 S1      
317m4401            VIA   -    MD0100PA01X+026950Y+136010X0180Y         S0      
317m4401            J11   -C3   D0122PA01X+030043Y+161217X0282Y    R180 S3      
327m4401            C134  -2          A01X+026960Y+135519X0120Y0150R090 S1      
327m4402            J41   -B20        A01X+128136Y+011886X0150Y0500R090 S1      
327m4402            C516  -2          A01X+130066Y+011824X0120Y0150R180 S1      
317m4403            VIA   -    MD0100PA01X+129153Y+138430X0180Y         S0      
317m4403            J13   -C8   D0122PA01X+136571Y+161138X0282Y    R180 S3      
327m4403            C565  -2          A01X+129143Y+137939X0120Y0150R090 S1      
317m4404            VIA   -    MD0080PA01X+161732Y+108642X0160Y         S0      
327m4404            PEX3  -BF28       A01X+161732Y+108642X0180Y         S1      
317m4404            VIA   -    MD0100PA01X+157694Y+041226X0200Y    R180 S0      
327m4404            J26   -A57        A01X+157064Y+041278X0140Y0480R270 S1      
327PRSNTB1_NIC6_N   VIA   -    M      A01X+158485Y+046280X0300Y         S1      
327PRSNTB1_NIC6_N   J26   -A42        A01X+157064Y+046518X0140Y0480R270 S1      
327PRSNTB1_NIC6_N   R346  -2          A01X+158948Y+045880X0198Y0197R180 S1      
327PRSNTB1_NIC6_N   R311  -1   M      A01X+158948Y+046280X0198Y0197     S1      
317m4405            J11   -V3   D0122PA01X+030043Y+147398X0282Y    R180 S3      
317m4405            VIA   -    MD0080PA01X+020866Y+124350X0160Y         S0      
327m4405            PEX0  -D18        A01X+020866Y+124350X0180Y         S1      
327m4406            C487  -2          A01X+099357Y+013601X0120Y0150R180 S1      
327m4406            J38   -B27        A01X+097427Y+013539X0150Y0500R090 S1      
317m4407            J13   -H2   D0122PA01X+131374Y+158579X0282Y    R180 S3      
317m4407            VIA   -    MD0080PA01X+108917Y+125472X0160Y         S0      
327m4407            PEX2  -A9         A01X+108917Y+125472X0180Y         S1      
327m4408            J26   -B40        A01X+155253Y+046990X0140Y0480R270 S1      
327m4408            C680  -2          A01X+151656Y+046929X0120Y0150     S1      
317RST_HP_NIC3_N    VIA   -    M      A01X+075480Y+033956X0200Y         S2      
017RST_HP_NIC3_N    VIA   -    M      A18X+075480Y+033956X0260Y         S2      
017RST_HP_NIC3_N          -    MD0100PA00X+075480Y+033956                       
327RST_HP_NIC3_N    U25   -2          A01X+076037Y+034488X0160Y0360R270 S1      
327RST_HP_NIC3_N    U26   -4          A01X+076771Y+033632X0220Y0530R090 S1      
327NIC6_BIF1_N      VIA   -    M      A01X+153024Y+055937X0300Y         S1      
327NIC6_BIF1_N      R337  -1          A01X+151852Y+055856X0198Y0197R180 S1      
327NIC6_BIF1_N      R338  -1   M      A01X+152237Y+055856X0198Y0197     S1      
327NIC6_BIF1_N      J26   -B8         A01X+155253Y+055892X0140Y0480R270 S1      
327m4409            C505  -2          A01X+118790Y+012890X0120Y0150R180 S1      
327m4409            J40   -B24        A01X+117900Y+012831X0150Y0500R090 S1      
317m4410            VIA   -    MD0100PA01X+135613Y+140850X0180Y         S0      
317m4410            J13   -N8   D0122PA01X+136571Y+151413X0282Y    R180 S3      
327m4410            C582  -2          A01X+135623Y+140359X0120Y0150R090 S1      
327m4411            J26   -B59        A01X+155253Y+040805X0140Y0480R270 S1      
327m4411            C693  -2          A01X+152696Y+040867X0120Y0150     S1      
317m4412            J11   -U7   D0122PA01X+033508Y+147910X0282Y    R180 S3      
317m4412            VIA   -    MD0080PA01X+022362Y+124724X0160Y         S0      
327m4412            PEX0  -C22        A01X+022362Y+124724X0180Y         S1      
317m4413            VIA   -    MD0080PA01X+114528Y+108642X0160Y    R270 S0      
327m4413            PEX2  -BF24       A01X+114528Y+108642X0180Y         S1      
327m4413            J41   -A18        A01X+126325Y+011413X0150Y0500R090 S1      
317m4413            VIA   -    MD0100PA01X+125695Y+011466X0200Y         S0      
317m4414            VIA   -    MD0100PA01X+127929Y+136010X0180Y         S0      
317m4414            J13   -C6   D0122PA01X+134839Y+161138X0282Y    R180 S3      
327m4414            C561  -2          A01X+127919Y+135519X0120Y0150R090 S1      
327m4415            J26   -B62        A01X+155253Y+040096X0140Y0480R270 S1      
327m4415            C695  -2          A01X+151896Y+040161X0120Y0150     S1      
327m4416            VIA   -    M      A01X+158494Y+055460X0300Y         S1      
327m4416            J26   -A9         A01X+157064Y+055656X0140Y0480R270 S1      
327m4416            R343  -1          A01X+159828Y+054970X0198Y0197     S1      
317m4417            J11   -I4   D0122PA01X+030909Y+158067X0282Y    R180 S3      
317m4417            VIA   -    MD0080PA01X+018248Y+125098X0160Y         S0      
327m4417            PEX0  -B11        A01X+018248Y+125098X0180Y         S1      
317m4418            VIA   -    MD0080PA01X+111161Y+107520X0160Y    R270 S0      
327m4418            J39   -A20        A01X+105852Y+011886X0150Y0500R090 S1      
317m4418            VIA   -    MD0100PA01X+104492Y+011834X0200Y         S0      
327m4418            PEX2  -BJ15       A01X+111161Y+107520X0180Y         S1      
317m4419            VIA   -    MD0100PA01X+130377Y+136010X0180Y         S0      
317m4419            J13   -P1   D0122PA01X+130508Y+150468X0282Y    R180 S3      
327m4419            C567  -2          A01X+130367Y+135519X0120Y0150R090 S1      
317m4420            VIA   -    MD0080PA01X+166220Y+108268X0160Y         S0      
327m4420            PEX3  -BG40       A01X+166220Y+108268X0180Y         S1      
317m4420            VIA   -    MD0100PA01X+157694Y+053818X0200Y    R180 S0      
327m4420            J26   -A17        A01X+157064Y+053766X0140Y0480R270 S1      
317m4421            VIA   -    M      A01X+158042Y+061007X0200Y         S2      
017m4421            VIA   -    M      A18X+158042Y+061007X0260Y         S2      
017m4421                  -    MD0100PA00X+158042Y+061007                       
327m4421            R327  -1          A18X+156794Y+060640X0198Y0197     S2      
327m4421            J26   -OA7        A01X+157064Y+060929X0140Y0480R270 S1      
317m4422            VIA   -    MD0100PA01X+024502Y+136010X0180Y         S0      
317m4422            J11   -C1   D0122PA01X+028311Y+161217X0282Y    R180 S3      
327m4422            C130  -2          A01X+024512Y+135519X0120Y0150R090 S1      
327m4423            C497  -2          A01X+108553Y+012890X0120Y0150R180 S1      
327m4423            J39   -B24        A01X+107663Y+012831X0150Y0500R090 S1      
317m4424            VIA   -    MD0100PA01X+131941Y+138430X0180Y         S0      
317m4424            J13   -O3   D0122PA01X+132240Y+150980X0282Y    R180 S3      
327m4424            C572  -2          A01X+131951Y+137939X0120Y0150R090 S1      
327m4425            J26   -B65        A01X+155253Y+039388X0140Y0480R270 S1      
327m4425            C697  -2          A01X+152696Y+039450X0120Y0150     S1      
327m4426            VIA   -    M      A01X+153028Y+063089X0300Y         S1      
327m4426            R308  -1          A01X+152484Y+062760X0198Y0197R180 S1      
327m4426            J26   -OB2        A01X+155253Y+062110X0140Y0480R270 S1      
317m4427            J11   -U5   D0122PA01X+031776Y+147910X0282Y    R180 S3      
317m4427            VIA   -    MD0080PA01X+021614Y+124724X0160Y         S0      
327m4427            PEX0  -C20        A01X+021614Y+124724X0180Y         S1      
327m4428            J41   -B18        A01X+128136Y+011413X0150Y0500R090 S1      
327m4428            C517  -2          A01X+129026Y+011472X0120Y0150R180 S1      
317m4429            J13   -V7   D0122PA01X+135705Y+147398X0282Y    R180 S3      
317m4429            VIA   -    MD0080PA01X+113780Y+124350X0160Y         S0      
327m4429            PEX2  -D22        A01X+113780Y+124350X0180Y         S1      
317m4430            VIA   -    MD0080PA01X+162106Y+107894X0160Y         S0      
327m4430            PEX3  -BH29       A01X+162106Y+107894X0180Y         S1      
317m4430            VIA   -    MD0100PA01X+158424Y+041934X0200Y    R180 S0      
327m4430            J26   -A54        A01X+157064Y+041986X0140Y0480R270 S1      
327m4431            VIA   -    M      A01X+158526Y+061950X0300Y         S1      
327m4431            J26   -OA2        A01X+157064Y+062110X0140Y0480R270 S1      
327m4431            R354  -1          A01X+159008Y+062140X0198Y0197     S1      
317m4432            VIA   -    MD0100PA01X+036402Y+136010X0180Y         S0      
317m4432            J11   -P7   D0122PA01X+033508Y+150468X0282Y    R180 S3      
327m4432            C157  -2          A01X+036392Y+135519X0120Y0150R090 S1      
317m4433            VIA   -    MD0080PA01X+066949Y+107520X0160Y    R270 S0      
327m4433            J36   -A20        A01X+070380Y+011886X0150Y0500R090 S1      
317m4433            VIA   -    MD0100PA01X+069020Y+011834X0200Y         S0      
327m4433            PEX1  -BJ19       A01X+066949Y+107520X0180Y         S1      
317m4434            VIA   -    MD0080PA01X+110039Y+108268X0160Y    R270 S0      
327m4434            PEX2  -BG12       A01X+110039Y+108268X0180Y         S1      
327m4434            J38   -A17        A01X+095616Y+011177X0150Y0500R090 S1      
317m4434            VIA   -    MD0100PA01X+094986Y+011126X0200Y         S0      
317m4435            VIA   -    MD0100PA01X+125481Y+136010X0180Y         S0      
317m4435            J13   -D3   D0122PA01X+132240Y+160705X0282Y    R180 S3      
327m4435            C555  -2          A01X+125471Y+135519X0120Y0150R090 S1      
317m4436            VIA   -    MD0080PA01X+164724Y+108642X0160Y         S0      
327m4436            PEX3  -BF36       A01X+164724Y+108642X0180Y         S1      
317m4436            VIA   -    MD0100PA01X+157694Y+049064X0200Y    R180 S0      
327m4436            J26   -A31        A01X+157064Y+049116X0140Y0480R270 S1      
317NIC6_SLOT_ID1    VIA   -    M      A01X+157500Y+061259X0200Y         S2      
017NIC6_SLOT_ID1    VIA   -    M      A18X+157500Y+061259X0260Y         S2      
017NIC6_SLOT_ID1          -    MD0100PA00X+157500Y+061259                       
327NIC6_SLOT_ID1    R334  -1          A18X+156794Y+061440X0198Y0197     S2      
327NIC6_SLOT_ID1    R333  -1   M      A18X+156794Y+061040X0198Y0197     S2      
327NIC6_SLOT_ID1    J26   -OA6        A01X+157064Y+061165X0140Y0480R270 S1      
317m4437            VIA   -    MD0100PA01X+026610Y+136010X0180Y         S0      
317m4437            J11   -D3   D0122PA01X+030043Y+160705X0282Y    R180 S3      
327m4437            C133  -2          A01X+026600Y+135519X0120Y0150R090 S1      
317m4438            VIA   -    MD0080PA01X+066949Y+107894X0160Y    R270 S0      
327m4438            J36   -A21        A01X+070380Y+012122X0150Y0500R090 S1      
317m4438            VIA   -    MD0100PA01X+069020Y+012174X0200Y         S0      
327m4438            PEX1  -BH19       A01X+066949Y+107894X0180Y         S1      
317m4439            VIA   -    MD0100PA01X+125821Y+140850X0180Y         S0      
317m4439            J13   -B4   D0122PA01X+133106Y+161650X0282Y    R180 S3      
327m4439            C558  -2          A01X+125831Y+140359X0120Y0150R090 S1      
327m4440            J26   -B30        A01X+155253Y+049352X0140Y0480R270 S1      
327m4440            C675  -2          A01X+152696Y+049417X0120Y0150     S1      
327NCSI_NIC6_RXD1   VIA   -    M      A01X+153030Y+060126X0300Y         S1      
327NCSI_NIC6_RXD1   R323  -1          A01X+152480Y+059959X0198Y0197R180 S1      
327NCSI_NIC6_RXD1   J26   -OB8        A01X+155253Y+060693X0140Y0480R270 S1      
317m4441            J11   -V7   D0122PA01X+033508Y+147398X0282Y    R180 S3      
317m4441            VIA   -    MD0080PA01X+022362Y+124350X0160Y         S0      
327m4441            PEX0  -D22        A01X+022362Y+124350X0180Y         S1      
327m4442            C298  -2          A01X+073081Y+011472X0120Y0150R180 S1      
327m4442            J36   -B18        A01X+072191Y+011413X0150Y0500R090 S1      
317m4443            VIA   -    MD0100PA01X+127929Y+140850X0180Y         S0      
317m4443            J13   -D7   D0122PA01X+135705Y+160705X0282Y    R180 S3      
327m4443            C563  -2          A01X+127919Y+140359X0120Y0150R090 S1      
317m4444            VIA   -    MD0080PA01X+164724Y+108268X0160Y         S0      
327m4444            PEX3  -BG36       A01X+164724Y+108268X0180Y         S1      
317m4444            VIA   -    MD0100PA01X+157694Y+049404X0200Y    R180 S0      
327m4444            J26   -A30        A01X+157064Y+049352X0140Y0480R270 S1      
327NIC6_DATA_IN     VIA   -    M      A01X+153031Y+062100X0300Y         S1      
327NIC6_DATA_IN     R318  -1          A01X+152484Y+061960X0198Y0197R180 S1      
327NIC6_DATA_IN     J26   -OB4        A01X+155253Y+061638X0140Y0480R270 S1      
327PU_CLKREQ9       J39   -A11        A01X+105852Y+009760X0150Y0500R090 S1      
317PU_CLKREQ9       VIA   -    M      A01X+105198Y+009767X0200Y         S2      
017PU_CLKREQ9       VIA   -    M      A18X+105198Y+009767X0260Y         S2      
017PU_CLKREQ9             -    MD0100PA00X+105198Y+009767                       
327PU_CLKREQ9       R438  -2          A01X+104871Y+009767X0198Y0197     S1      
317m4445            J11   -H4   D0122PA01X+030909Y+158579X0282Y    R180 S3      
317m4445            VIA   -    MD0080PA01X+018248Y+125472X0160Y         S0      
327m4445            PEX0  -A11        A01X+018248Y+125472X0180Y         S1      
327m4446            C278  -2          A01X+052609Y+012890X0120Y0150R180 S1      
327m4446            J34   -B24        A01X+051718Y+012831X0150Y0500R090 S1      
317m4447            J13   -U3   D0122PA01X+132240Y+147910X0282Y    R180 S3      
317m4447            VIA   -    MD0080PA01X+112283Y+124724X0160Y         S0      
327m4447            PEX2  -C18        A01X+112283Y+124724X0180Y         S1      
317m4448            VIA   -    MD0080PA01X+161732Y+108268X0160Y         S0      
327m4448            PEX3  -BG28       A01X+161732Y+108268X0180Y         S1      
317m4448            VIA   -    MD0100PA01X+157694Y+041566X0200Y    R180 S0      
327m4448            J26   -A56        A01X+157064Y+041514X0140Y0480R270 S1      
317m4449            VIA   -    MD0100PA01X+150149Y+140850X0180Y         S0      
317m4449            J14   -N6   D0122PA01X+152161Y+151413X0282Y    R180 S3      
327m4449            C789  -2          A01X+150159Y+140359X0120Y0150R090 S1      
327PRSNTB3_NIC6_N   VIA   -    M      A01X+153019Y+038260X0300Y         S1      
327PRSNTB3_NIC6_N   R348  -2          A01X+152544Y+037860X0198Y0197     S1      
327PRSNTB3_NIC6_N   R314  -1   M      A01X+152544Y+038260X0198Y0197R180 S1      
327PRSNTB3_NIC6_N   J26   -B70        A01X+155253Y+038207X0140Y0480R270 S1      
327m4450            J39   -B9         A01X+107663Y+009287X0150Y0500R090 S1      
317m4450            VIA   -    M      A01X+108136Y+009287X0200Y         S2      
017m4450            VIA   -    M      A18X+108136Y+009287X0260Y         S2      
017m4450                  -    MD0100PA00X+108136Y+009287                       
327m4450            R437  -2          A01X+109720Y+009820X0198Y0197R270 S1      
327m4450            R436  -2   M      A01X+109320Y+009820X0198Y0197R270 S1      
327m4451            C276  -2          A01X+053649Y+013601X0120Y0150R180 S1      
327m4451            J34   -B27        A01X+051718Y+013539X0150Y0500R090 S1      
317m4452            J13   -I4   D0122PA01X+133106Y+158067X0282Y    R180 S3      
317m4452            VIA   -    MD0080PA01X+109665Y+125098X0160Y         S0      
327m4452            PEX2  -B11        A01X+109665Y+125098X0180Y         S1      
327m4453            J26   -B36        A01X+155253Y+047935X0140Y0480R270 S1      
327m4453            C679  -2          A01X+152696Y+048000X0120Y0150     S1      
317m4454            J14   -I1   D0122PA01X+147831Y+158146X0282Y    R180 S3      
317m4454            VIA   -    MD0080PA01X+154252Y+124724X0160Y         S0      
327m4454            PEX3  -C8         A01X+154252Y+124724X0180Y         S1      
327m4455            U23   -1          A18X+073267Y+045163X0240Y0240R270 S2      
327m4455            R156  -1          A18X+073932Y+046324X0198Y0197     S2      
317m4455            VIA   -    M      A01X+073932Y+045857X0200Y         S2      
017m4455            VIA   -    M      A18X+073932Y+045857X0260Y         S2      
017m4455                  -    MD0100PA00X+073932Y+045857                       
327m4455            J23   -B12        A01X+074550Y+045604X0140Y0480R090 S1      
327m4456            VIA   -    M      A01X+158526Y+062540X0300Y         S1      
327m4456            J26   -OA1        A01X+157064Y+062346X0140Y0480R270 S1      
327m4456            R353  -1          A01X+159008Y+062540X0198Y0197     S1      
327PU_CLKREQ8       J38   -A11        A01X+095616Y+009760X0150Y0500R090 S1      
317PU_CLKREQ8       VIA   -    M      A01X+094962Y+009767X0200Y         S2      
017PU_CLKREQ8       VIA   -    M      A18X+094962Y+009767X0260Y         S2      
017PU_CLKREQ8             -    MD0100PA00X+094962Y+009767                       
327PU_CLKREQ8       R435  -2          A01X+094635Y+009767X0198Y0197     S1      
317m4457            VIA   -    MD0100PA01X+026950Y+140850X0180Y         S0      
317m4457            J11   -B4   D0122PA01X+030909Y+161650X0282Y    R180 S3      
327m4457            C136  -2          A01X+026960Y+140359X0120Y0150R090 S1      
327m4458            C304  -2          A01X+084357Y+012184X0120Y0150R180 S1      
327m4458            J37   -B21        A01X+082427Y+012122X0150Y0500R090 S1      
317m4459            J13   -T2   D0122PA01X+131374Y+148343X0282Y    R180 S3      
317m4459            VIA   -    MD0080PA01X+111909Y+125472X0160Y         S0      
327m4459            PEX2  -A17        A01X+111909Y+125472X0180Y         S1      
327m4460            J26   -B47        A01X+155253Y+043640X0140Y0480R270 S1      
327m4460            C685  -2          A01X+152696Y+043702X0120Y0150     S1      
317m4461            J14   -H4   D0122PA01X+150429Y+158579X0282Y    R180 S3      
317m4461            VIA   -    MD0080PA01X+155374Y+125472X0160Y         S0      
327m4461            PEX3  -A11        A01X+155374Y+125472X0180Y         S1      
327PRSNTB3_NIC3_N   VIA   -    M      A01X+076784Y+062291X0300Y    R180 S1      
327PRSNTB3_NIC3_N   J23   -B70        A01X+074550Y+062344X0140Y0480R090 S1      
327PRSNTB3_NIC3_N   R195  -2          A01X+077260Y+062691X0198Y0197R180 S1      
327PRSNTB3_NIC3_N   R161  -1   M      A01X+077260Y+062291X0198Y0197     S1      
327NIC6_DATA_OUT    VIA   -    M      A01X+152950Y+061607X0300Y         S1      
327NIC6_DATA_OUT    R319  -1          A01X+152484Y+061560X0198Y0197R180 S1      
327NIC6_DATA_OUT    J26   -OB5        A01X+155253Y+061402X0140Y0480R270 S1      
327m4462            J38   -B9         A01X+097427Y+009287X0150Y0500R090 S1      
317m4462            VIA   -    M      A01X+097900Y+009287X0200Y         S2      
017m4462            VIA   -    M      A18X+097900Y+009287X0260Y         S2      
017m4462                  -    MD0100PA00X+097900Y+009287                       
327m4462            R434  -2          A01X+099483Y+009820X0198Y0197R270 S1      
327m4462            R433  -2   M      A01X+099083Y+009820X0198Y0197R270 S1      
317m4463            VIA   -    MD0100PA01X+034294Y+140850X0180Y         S0      
317m4463            J11   -O5   D0122PA01X+031776Y+150980X0282Y    R180 S3      
327m4463            C154  -2          A01X+034304Y+140359X0120Y0150R090 S1      
317m4464            VIA   -    MD0080PA01X+068071Y+108268X0160Y    R270 S0      
327m4464            J37   -A23        A01X+080616Y+012594X0150Y0500R090 S1      
317m4464            VIA   -    MD0100PA01X+079986Y+012543X0200Y         S0      
327m4464            PEX1  -BG22       A01X+068071Y+108268X0180Y         S1      
317m4465            VIA   -    MD0080PA01X+122008Y+108268X0160Y         S0      
327m4465            PEX2  -BG44       A01X+122008Y+108268X0180Y         S1      
327m4465            J25   -A56        A01X+118448Y+059037X0140Y0480R090 S1      
317m4465            VIA   -    MD0100PA01X+117818Y+058986X0200Y         S0      
317m4466            VIA   -    MD0100PA01X+131601Y+138430X0180Y         S0      
317m4466            J13   -P3   D0122PA01X+132240Y+150468X0282Y    R180 S3      
327m4466            C571  -2          A01X+131591Y+137939X0120Y0150R090 S1      
327m4467            J26   -B48        A01X+155253Y+043404X0140Y0480R270 S1      
327m4467            C684  -2          A01X+152696Y+043342X0120Y0150     S1      
317m4468            VIA   -    MD0100PA01X+147701Y+138430X0180Y         S0      
317m4468            J14   -B2   D0122PA01X+148697Y+161650X0282Y    R180 S3      
327m4468            C765  -2          A01X+147711Y+137939X0120Y0150R090 S1      
317m4469            VIA   -    M      A01X+072344Y+039150X0200Y         S2      
017m4469            VIA   -    M      A18X+072344Y+039150X0260Y         S2      
017m4469                  -    MD0100PA00X+072344Y+039150                       
327m4469            R154  -1          A01X+068778Y+038872X0198Y0197     S1      
327m4469            J23   -OA5        A01X+072739Y+039150X0140Y0480R090 S1      
327NIC6_CLK         VIA   -    M      A01X+153031Y+061113X0300Y         S1      
327NIC6_CLK         R320  -1          A01X+152484Y+061160X0198Y0197R180 S1      
327NIC6_CLK         J26   -OB6        A01X+155253Y+061165X0140Y0480R270 S1      
317m4470            VIA   -    MD0100PA01X+036742Y+136010X0180Y         S0      
317m4470            J11   -O7   D0122PA01X+033508Y+150980X0282Y    R180 S3      
327m4470            C158  -2          A01X+036752Y+135519X0120Y0150R090 S1      
327m4471            C279  -2          A01X+052609Y+012530X0120Y0150R180 S1      
327m4471            J34   -B23        A01X+051718Y+012594X0150Y0500R090 S1      
327m4472            J25   -B44        A01X+120259Y+056203X0140Y0480R090 S1      
327m4472            C438  -2          A01X+122816Y+056138X0120Y0150R180 S1      
317m4473            J13   -I3   D0122PA01X+132240Y+158146X0282Y    R180 S3      
317m4473            VIA   -    MD0080PA01X+109291Y+124724X0160Y         S0      
327m4473            PEX2  -C10        A01X+109291Y+124724X0180Y         S1      
327m4474            J26   -B21        A01X+155253Y+052821X0140Y0480R270 S1      
327m4474            C668  -2          A01X+151656Y+052759X0120Y0150     S1      
317m4475            J14   -U6   D0122PA01X+152161Y+147831X0282Y    R180 S3      
317m4475            VIA   -    MD0080PA01X+159114Y+125098X0160Y         S0      
327m4475            PEX3  -B21        A01X+159114Y+125098X0180Y         S1      
317m4476            VIA   -    M      A01X+157472Y+061840X0200Y         S2      
017m4476            VIA   -    M      A18X+157472Y+061840X0260Y         S2      
017m4476                  -    MD0100PA00X+157472Y+061840                       
327m4476            R307  -2          A18X+156794Y+061840X0198Y0197R180 S2      
327m4476            J26   -OA4        A01X+157064Y+061638X0140Y0480R270 S1      
317m4477            J11   -I3   D0122PA01X+030043Y+158146X0282Y    R180 S3      
317m4477            VIA   -    MD0080PA01X+017874Y+124724X0160Y         S0      
327m4477            PEX0  -C10        A01X+017874Y+124724X0180Y         S1      
327m4478            C306  -2          A01X+083317Y+011472X0120Y0150R180 S1      
327m4478            J37   -B18        A01X+082427Y+011413X0150Y0500R090 S1      
327m4479            J25   -B53        A01X+120259Y+058329X0140Y0480R090 S1      
327m4479            C432  -2          A01X+123856Y+058266X0120Y0150R180 S1      
317m4480            VIA   -    MD0100PA01X+135273Y+140850X0180Y         S0      
317m4480            J13   -O8   D0122PA01X+136571Y+150902X0282Y    R180 S3      
327m4480            C581  -2          A01X+135263Y+140359X0120Y0150R090 S1      
317m4481            VIA   -    MD0080PA01X+160610Y+107520X0160Y         S0      
327m4481            PEX3  -BJ25       A01X+160610Y+107520X0180Y         S1      
317m4481            VIA   -    MD0100PA01X+158424Y+039440X0200Y    R180 S0      
327m4481            J26   -A65        A01X+157064Y+039388X0140Y0480R270 S1      
317m4482            VIA   -    MD0100PA01X+147701Y+136010X0180Y         S0      
317m4482            J14   -N2   D0122PA01X+148697Y+151413X0282Y    R180 S3      
327m4482            C781  -2          A01X+147711Y+135519X0120Y0150R090 S1      
317NCSI_NIC3_TXD0   VIA   -    M      A01X+071742Y+040433X0200Y         S2      
017NCSI_NIC3_TXD0   VIA   -    M      A18X+071742Y+040433X0260Y         S2      
017NCSI_NIC3_TXD0         -    MD0100PA00X+071742Y+040433                       
327NCSI_NIC3_TXD0   R171  -1          A01X+069092Y+040872X0198Y0197R180 S1      
327NCSI_NIC3_TXD0   J23   -OA9        A01X+072739Y+040094X0140Y0480R090 S1      
327PRSNTB0_NIC6_N   VIA   -    M      A01X+153028Y+046518X0300Y         S1      
327PRSNTB0_NIC6_N   R345  -2          A01X+152544Y+045960X0198Y0197     S1      
327PRSNTB0_NIC6_N   R313  -1   M      A01X+152544Y+046360X0198Y0197R180 S1      
327PRSNTB0_NIC6_N   J26   -B42        A01X+155253Y+046518X0140Y0480R270 S1      
317m4483            VIA   -    MD0080PA01X+065827Y+108642X0160Y    R270 S0      
327m4483            PEX1  -BF16       A01X+065827Y+108642X0180Y         S1      
327m4483            J35   -A18        A01X+060144Y+011413X0150Y0500R090 S1      
317m4483            VIA   -    MD0100PA01X+059514Y+011466X0200Y         S0      
317m4484            VIA   -    MD0080PA01X+123878Y+112382X0160Y    R270 S0      
317m4484            VIA   -    MD0100PA01X+117088Y+048860X0200Y         S0      
327m4484            J25   -A26        A01X+118448Y+048911X0140Y0480R090 S1      
327m4484            PEX2  -AT49       A01X+123878Y+112382X0180Y         S1      
317m4485            J13   -J1   D0122PA01X+130508Y+157634X0282Y    R180 S3      
317m4485            VIA   -    MD0080PA01X+108543Y+124350X0160Y         S0      
327m4485            PEX2  -D8         A01X+108543Y+124350X0180Y         S1      
327m4486            J26   -B54        A01X+155253Y+041986X0140Y0480R270 S1      
327m4486            C688  -2          A01X+152696Y+041925X0120Y0150     S1      
317m4487            VIA   -    MD0100PA01X+146137Y+136010X0180Y         S0      
317m4487            J14   -D1   D0122PA01X+147831Y+160705X0282Y    R180 S3      
327m4487            C762  -2          A01X+146127Y+135519X0120Y0150R090 S1      
317NCSI_NIC3_RXD1   VIA   -    M      A01X+075109Y+039858X0200Y         S2      
017NCSI_NIC3_RXD1   VIA   -    M      A18X+075109Y+039858X0260Y         S2      
017NCSI_NIC3_RXD1         -    MD0100PA00X+075109Y+039858                       
327NCSI_NIC3_RXD1   J23   -OB8        A01X+074550Y+039858X0140Y0480R090 S1      
327NCSI_NIC3_RXD1   R170  -1          A18X+076079Y+040192X0198Y0197R180 S2      
327NCSI_NIC6_RXD0   VIA   -    M      A01X+152946Y+059632X0300Y         S1      
327NCSI_NIC6_RXD0   J26   -OB9        A01X+155253Y+060457X0140Y0480R270 S1      
327NCSI_NIC6_RXD0   R322  -1          A01X+152480Y+059559X0198Y0197R180 S1      
327PRSNT_SSD8_N     J38   -A12        A01X+095616Y+009996X0150Y0500R090 S1      
317PRSNT_SSD8_N     VIA   -    M      A01X+094922Y+010341X0200Y         S2      
017PRSNT_SSD8_N     VIA   -    M      A18X+094922Y+010341X0260Y         S2      
017PRSNT_SSD8_N           -    MD0100PA00X+094922Y+010341                       
327PRSNT_SSD8_N     R4069 -2          A01X+094614Y+010341X0198Y0197R270 S1      
317m4488            VIA   -    MD0080PA01X+067323Y+108268X0160Y    R270 S0      
327m4488            PEX1  -BG20       A01X+067323Y+108268X0180Y         S1      
327m4488            J36   -A17        A01X+070380Y+011177X0150Y0500R090 S1      
317m4488            VIA   -    MD0100PA01X+069750Y+011126X0200Y         S0      
327m4489            J25   -B27        A01X+120259Y+049148X0140Y0480R090 S1      
327m4489            C447  -2          A01X+123856Y+049209X0120Y0150R180 S1      
317m4490            J13   -T8   D0122PA01X+136571Y+148343X0282Y    R180 S3      
317m4490            VIA   -    MD0080PA01X+114154Y+125472X0160Y         S0      
327m4490            PEX2  -A23        A01X+114154Y+125472X0180Y         S1      
327m4491            J26   -B24        A01X+155253Y+052112X0140Y0480R270 S1      
327m4491            C670  -2          A01X+152696Y+052053X0120Y0150     S1      
317m4492            J14   -I8   D0122PA01X+153894Y+158067X0282Y    R180 S3      
317m4492            VIA   -    MD0080PA01X+156870Y+125098X0160Y         S0      
327m4492            PEX3  -B15        A01X+156870Y+125098X0180Y         S1      
327NIC6_BIF2_N      VIA   -    M      A01X+153030Y+055267X0300Y         S1      
327NIC6_BIF2_N      J26   -B9         A01X+155253Y+055656X0140Y0480R270 S1      
327NIC6_BIF2_N      R339  -1          A01X+151852Y+055456X0198Y0197R180 S1      
327NIC6_BIF2_N      R340  -1   M      A01X+152237Y+055456X0198Y0197     S1      
327m4493            C300  -2          A01X+084357Y+013601X0120Y0150R180 S1      
327m4493            J37   -B27        A01X+082427Y+013539X0150Y0500R090 S1      
327m4494            J25   -B17        A01X+120259Y+046785X0140Y0480R090 S1      
327m4494            C454  -2          A01X+122816Y+046721X0120Y0150R180 S1      
317m4495            VIA   -    MD0100PA01X+123033Y+136010X0180Y         S0      
317m4495            J13   -D1   D0122PA01X+130508Y+160705X0282Y    R180 S3      
327m4495            C551  -2          A01X+123023Y+135519X0120Y0150R090 S1      
327m4496            J26   -B53        A01X+155253Y+042222X0140Y0480R270 S1      
327m4496            C689  -2          A01X+152696Y+042285X0120Y0150     S1      
317m4497            J14   -U4   D0122PA01X+150429Y+147831X0282Y    R180 S3      
317m4497            VIA   -    MD0080PA01X+158366Y+125098X0160Y         S0      
327m4497            PEX3  -B19        A01X+158366Y+125098X0180Y         S1      
317m4498            VIA   -    M      A01X+072340Y+037966X0200Y         S2      
017m4498            VIA   -    M      A18X+072340Y+037966X0260Y         S2      
017m4498                  -    MD0100PA00X+072340Y+037966                       
327m4498            R200  -1          A01X+069092Y+038072X0198Y0197R180 S1      
327m4498            J23   -OA1        A01X+072739Y+038205X0140Y0480R090 S1      
327m4499            C299  -2          A01X+073081Y+011112X0120Y0150R180 S1      
327m4499            J36   -B17        A01X+072191Y+011177X0150Y0500R090 S1      
317m4500            VIA   -    MD0080PA01X+122756Y+108268X0160Y         S0      
327m4500            PEX2  -BG46       A01X+122756Y+108268X0180Y         S1      
327m4500            J25   -A50        A01X+118448Y+057620X0140Y0480R090 S1      
317m4500            VIA   -    MD0100PA01X+117818Y+057568X0200Y         S0      
317m4501            J13   -H8   D0122PA01X+136571Y+158579X0282Y    R180 S3      
317m4501            VIA   -    MD0080PA01X+111161Y+125472X0160Y         S0      
327m4501            PEX2  -A15        A01X+111161Y+125472X0180Y         S1      
327m4502            J26   -B23        A01X+155253Y+052348X0140Y0480R270 S1      
327m4502            C671  -2          A01X+152696Y+052413X0120Y0150     S1      
317m4503            J14   -H2   D0122PA01X+148697Y+158579X0282Y    R180 S3      
317m4503            VIA   -    MD0080PA01X+154626Y+125472X0160Y         S0      
327m4503            PEX3  -A9         A01X+154626Y+125472X0180Y         S1      
317m4504            VIA   -    M      A01X+071961Y+045111X0200Y         S2      
017m4504            VIA   -    M      A18X+071961Y+045111X0260Y         S2      
017m4504                  -    MD0100PA00X+071961Y+045111                       
327m4504            R190  -1          A01X+070936Y+045387X0198Y0197R180 S1      
327m4504            J23   -A9         A01X+072739Y+044896X0140Y0480R090 S1      
327m4505            C294  -2          A01X+073081Y+012890X0120Y0150R180 S1      
327m4505            J36   -B24        A01X+072191Y+012831X0150Y0500R090 S1      
327m4506            J25   -B51        A01X+120259Y+057856X0140Y0480R090 S1      
327m4506            C433  -2          A01X+122816Y+057915X0120Y0150R180 S1      
317m4507            J13   -H6   D0122PA01X+134839Y+158579X0282Y    R180 S3      
317m4507            VIA   -    MD0080PA01X+110413Y+125472X0160Y         S0      
327m4507            PEX2  -A13        A01X+110413Y+125472X0180Y         S1      
317m4508            VIA   -    MD0080PA01X+162854Y+107520X0160Y         S0      
327m4508            PEX3  -BJ31       A01X+162854Y+107520X0180Y         S1      
317m4508            VIA   -    MD0100PA01X+158424Y+043692X0200Y    R180 S0      
327m4508            J26   -A47        A01X+157064Y+043640X0140Y0480R270 S1      
317m4509            J14   -U7   D0122PA01X+153028Y+147910X0282Y    R180 S3      
317m4509            VIA   -    MD0080PA01X+159488Y+124724X0160Y         S0      
327m4509            PEX3  -C22        A01X+159488Y+124724X0180Y         S1      
317NIC3_DATA_IN     VIA   -    M      A01X+075609Y+038650X0200Y         S2      
017NIC3_DATA_IN     VIA   -    M      A18X+075609Y+038650X0260Y         S2      
017NIC3_DATA_IN           -    MD0100PA00X+075609Y+038650                       
327NIC3_DATA_IN     J23   -OB4        A01X+074550Y+038913X0140Y0480R090 S1      
327NIC3_DATA_IN     R165  -1          A18X+076079Y+038191X0198Y0197R180 S2      
317m4510            VIA   -    MD0080PA01X+020118Y+108642X0160Y    R270 S0      
327m4510            PEX0  -BF16       A01X+020118Y+108642X0180Y         S1      
327m4510            J31   -A18        A01X+014435Y+011413X0150Y0500R090 S1      
317m4510            VIA   -    MD0100PA01X+013805Y+011466X0200Y         S0      
327m4511            C287  -2          A01X+062845Y+012530X0120Y0150R180 S1      
327m4511            J35   -B23        A01X+061955Y+012594X0150Y0500R090 S1      
317m4512            VIA   -    MD0080PA01X+122756Y+113504X0160Y    R270 S0      
327m4512            J25   -A18        A01X+118448Y+047022X0140Y0480R090 S1      
317m4512            VIA   -    MD0100PA01X+117818Y+047074X0200Y         S0      
327m4512            PEX2  -AN46       A01X+122756Y+113504X0180Y         S1      
317m4513            J13   -U2   D0122PA01X+131374Y+147831X0282Y    R180 S3      
317m4513            VIA   -    MD0080PA01X+111909Y+125098X0160Y         S0      
327m4513            PEX2  -B17        A01X+111909Y+125098X0180Y         S1      
327m4514            J26   -B60        A01X+155253Y+040569X0140Y0480R270 S1      
327m4514            C692  -2          A01X+152696Y+040507X0120Y0150     S1      
317m4515            J14   -V3   D0122PA01X+149563Y+147398X0282Y    R180 S3      
317m4515            VIA   -    MD0080PA01X+157992Y+124350X0160Y         S0      
327m4515            PEX3  -D18        A01X+157992Y+124350X0180Y         S1      
317NCSI_NIC3_RXD0   VIA   -    M      A01X+075309Y+040350X0200Y         S2      
017NCSI_NIC3_RXD0   VIA   -    M      A18X+075309Y+040350X0260Y         S2      
017NCSI_NIC3_RXD0         -    MD0100PA00X+075309Y+040350                       
327NCSI_NIC3_RXD0   J23   -OB9        A01X+074550Y+040094X0140Y0480R090 S1      
327NCSI_NIC3_RXD0   R169  -1          A18X+076079Y+040592X0198Y0197R180 S2      
317m4516            VIA   -    MD0080PA01X+063583Y+108268X0160Y    R270 S0      
327m4516            PEX1  -BG10       A01X+063583Y+108268X0180Y         S1      
327m4516            J34   -A23        A01X+049908Y+012594X0150Y0500R090 S1      
317m4516            VIA   -    MD0100PA01X+049278Y+012543X0200Y         S0      
317m4517            VIA   -    MD0080PA01X+123130Y+112756X0160Y    R270 S0      
327m4517            PEX2  -AR47       A01X+123130Y+112756X0180Y         S1      
327m4517            J25   -A23        A01X+118448Y+048203X0140Y0480R090 S1      
317m4517            VIA   -    MD0100PA01X+117818Y+048151X0200Y         S0      
317m4518            VIA   -    MD0100PA01X+127045Y+138430X0180Y         S0      
317m4518            J13   -C5   D0122PA01X+133972Y+161217X0282Y    R180 S3      
327m4518            C560  -2          A01X+127055Y+137939X0120Y0150R090 S1      
317m4519            VIA   -    MD0080PA01X+165098Y+107894X0160Y         S0      
327m4519            PEX3  -BH37       A01X+165098Y+107894X0180Y         S1      
317m4519            VIA   -    MD0100PA01X+158424Y+051352X0200Y    R180 S0      
327m4519            J26   -A27        A01X+157064Y+051404X0140Y0480R270 S1      
317m4520            VIA   -    MD0100PA01X+148925Y+138430X0180Y         S0      
317m4520            J14   -N4   D0122PA01X+150429Y+151413X0282Y    R180 S3      
327m4520            C785  -2          A01X+148935Y+137939X0120Y0150R090 S1      
317m4521            VIA   -    MD0080PA01X+017874Y+108642X0160Y    R270 S0      
327m4521            PEX0  -BF10       A01X+017874Y+108642X0180Y         S1      
327m4521            J30   -A24        A01X+004199Y+012831X0150Y0500R090 S1      
317m4521            VIA   -    MD0100PA01X+003569Y+012883X0200Y         S0      
327m4522            C281  -2          A01X+053649Y+011824X0120Y0150R180 S1      
327m4522            J34   -B20        A01X+051718Y+011886X0150Y0500R090 S1      
327m4523            J25   -B60        A01X+120259Y+059982X0140Y0480R090 S1      
327m4523            C427  -2          A01X+123856Y+060044X0120Y0150R180 S1      
317m4524            VIA   -    MD0100PA01X+135613Y+136010X0180Y         S0      
317m4524            J13   -O7   D0122PA01X+135705Y+150980X0282Y    R180 S3      
327m4524            C580  -2          A01X+135623Y+135519X0120Y0150R090 S1      
317m4525            VIA   -    MD0080PA01X+160984Y+108268X0160Y         S0      
327m4525            PEX3  -BG26       A01X+160984Y+108268X0180Y         S1      
317m4525            VIA   -    MD0100PA01X+157694Y+040148X0200Y    R180 S0      
327m4525            J26   -A62        A01X+157064Y+040096X0140Y0480R270 S1      
317m4526            VIA   -    MD0080PA01X+157244Y+124350X0160Y         S0      
327m4526            PEX3  -D16        A01X+157244Y+124350X0180Y         S1      
317m4526            J14   -V1   D0122PA01X+147831Y+147398X0282Y    R180 S3      
317m4527            VIA   -    M      A01X+071710Y+041096X0200Y         S2      
017m4527            VIA   -    M      A18X+071710Y+041096X0260Y         S2      
017m4527                  -    MD0100PA00X+071710Y+041096                       
327m4527            R173  -1          A01X+069092Y+041272X0198Y0197R180 S1      
327m4527            J23   -OA14       A01X+072739Y+041276X0140Y0480R090 S1      
327m4528            C305  -2          A01X+084357Y+011824X0120Y0150R180 S1      
327m4528            J37   -B20        A01X+082427Y+011886X0150Y0500R090 S1      
317m4529            VIA   -    MD0080PA01X+120886Y+107520X0160Y         S0      
327m4529            J25   -A65        A01X+118448Y+061163X0140Y0480R090 S1      
317m4529            VIA   -    MD0100PA01X+117088Y+061112X0200Y         S0      
327m4529            PEX2  -BJ41       A01X+120886Y+107520X0180Y         S1      
317m4530            VIA   -    MD0100PA01X+130717Y+136010X0180Y         S0      
317m4530            J13   -O1   D0122PA01X+130508Y+150980X0282Y    R180 S3      
327m4530            C568  -2          A01X+130727Y+135519X0120Y0150R090 S1      
327m4531            J26   -B27        A01X+155253Y+051404X0140Y0480R270 S1      
327m4531            C672  -2          A01X+151656Y+051342X0120Y0150     S1      
317m4532            J14   -U2   D0122PA01X+148697Y+147831X0282Y    R180 S3      
317m4532            VIA   -    MD0080PA01X+157618Y+125098X0160Y         S0      
327m4532            PEX3  -B17        A01X+157618Y+125098X0180Y         S1      
317PRSNTB2_NIC3_N   VIA   -    M      A01X+071905Y+045846X0200Y         S2      
017PRSNTB2_NIC3_N   VIA   -    M      A18X+071905Y+045846X0260Y         S2      
017PRSNTB2_NIC3_N         -    MD0100PA00X+071905Y+045846                       
327PRSNTB2_NIC3_N   R194  -2          A01X+070936Y+046286X0198Y0197     S1      
327PRSNTB2_NIC3_N   R160  -1   M      A01X+070936Y+045886X0198Y0197R180 S1      
327PRSNTB2_NIC3_N   J23   -A12        A01X+072739Y+045604X0140Y0480R090 S1      
317m4533            VIA   -    MD0080PA01X+067323Y+108642X0160Y    R270 S0      
327m4533            PEX1  -BF20       A01X+067323Y+108642X0180Y         S1      
327m4533            J36   -A18        A01X+070380Y+011413X0150Y0500R090 S1      
317m4533            VIA   -    MD0100PA01X+069750Y+011466X0200Y         S0      
327m4534            J25   -B31        A01X+120259Y+051435X0140Y0480R090 S1      
327m4534            C445  -2          A01X+122816Y+051494X0120Y0150R180 S1      
317m4535            VIA   -    MD0100PA01X+133165Y+140850X0180Y         S0      
317m4535            J13   -O5   D0122PA01X+133972Y+150980X0282Y    R180 S3      
327m4535            C576  -2          A01X+133175Y+140359X0120Y0150R090 S1      
327m4536            J26   -B63        A01X+155253Y+039860X0140Y0480R270 S1      
327m4536            C694  -2          A01X+151896Y+039801X0120Y0150     S1      
317m4537            VIA   -    MD0100PA01X+152257Y+138430X0180Y         S0      
317m4537            J14   -C8   D0122PA01X+153894Y+161138X0282Y    R180 S3      
327m4537            C776  -2          A01X+152247Y+137939X0120Y0150R090 S1      
327m4538            VIA   -    M      A01X+070830Y+038788X0300Y         S1      
327m4538            R154  -2          A01X+069092Y+038872X0198Y0197     S1      
327m4538            J23   -OA4        A01X+072739Y+038913X0140Y0480R090 S1      
317m4539            VIA   -    MD0080PA01X+019744Y+107520X0160Y    R270 S0      
327m4539            J31   -A20        A01X+014435Y+011886X0150Y0500R090 S1      
317m4539            VIA   -    MD0100PA01X+013075Y+011834X0200Y         S0      
327m4539            PEX0  -BJ15       A01X+019744Y+107520X0180Y         S1      
317m4540            VIA   -    MD0080PA01X+066575Y+108642X0160Y    R270 S0      
327m4540            J36   -A24        A01X+070380Y+012831X0150Y0500R090 S1      
317m4540            VIA   -    MD0100PA01X+069750Y+012883X0200Y         S0      
327m4540            PEX1  -BF18       A01X+066575Y+108642X0180Y         S1      
317m4541            VIA   -    MD0080PA01X+121634Y+107894X0160Y         S0      
327m4541            PEX2  -BH43       A01X+121634Y+107894X0180Y         S1      
327m4541            J25   -A60        A01X+118448Y+059982X0140Y0480R090 S1      
317m4541            VIA   -    MD0100PA01X+117088Y+060034X0200Y         S0      
317m4542            J13   -V3   D0122PA01X+132240Y+147398X0282Y    R180 S3      
317m4542            VIA   -    MD0080PA01X+112283Y+124350X0160Y         S0      
327m4542            PEX2  -D18        A01X+112283Y+124350X0180Y         S1      
327m4543            J26   -B39        A01X+155253Y+047226X0140Y0480R270 S1      
327m4543            C681  -2          A01X+151656Y+047289X0120Y0150     S1      
317m4544            J14   -U8   D0122PA01X+153894Y+147831X0282Y    R180 S3      
317m4544            VIA   -    MD0080PA01X+159862Y+125098X0160Y         S0      
327m4544            PEX3  -B23        A01X+159862Y+125098X0180Y         S1      
317m4545            VIA   -    MD0080PA01X+021614Y+108268X0160Y    R270 S0      
327m4545            PEX0  -BG20       A01X+021614Y+108268X0180Y         S1      
327m4545            J32   -A17        A01X+024671Y+011177X0150Y0500R090 S1      
317m4545            VIA   -    MD0100PA01X+024041Y+011126X0200Y         S0      
317m4546            VIA   -    MD0080PA01X+065079Y+108642X0160Y    R270 S0      
327m4546            J35   -A24        A01X+060144Y+012831X0150Y0500R090 S1      
317m4546            VIA   -    MD0100PA01X+059514Y+012883X0200Y         S0      
327m4546            PEX1  -BF14       A01X+065079Y+108642X0180Y         S1      
317m4547            VIA   -    MD0080PA01X+120886Y+107894X0160Y         S0      
327m4547            PEX2  -BH41       A01X+120886Y+107894X0180Y         S1      
327m4547            J25   -A66        A01X+118448Y+061400X0140Y0480R090 S1      
317m4547            VIA   -    MD0100PA01X+117088Y+061452X0200Y         S0      
317m4548            J13   -H4   D0122PA01X+133106Y+158579X0282Y    R180 S3      
317m4548            VIA   -    MD0080PA01X+109665Y+125472X0160Y         S0      
327m4548            PEX2  -A11        A01X+109665Y+125472X0180Y         S1      
317m4549            VIA   -    MD0080PA01X+163602Y+107894X0160Y         S0      
327m4549            PEX3  -BH33       A01X+163602Y+107894X0180Y         S1      
317m4549            VIA   -    MD0100PA01X+158424Y+046938X0200Y    R180 S0      
327m4549            J26   -A40        A01X+157064Y+046990X0140Y0480R270 S1      
317m4550            J14   -V7   D0122PA01X+153028Y+147398X0282Y    R180 S3      
317m4550            VIA   -    MD0080PA01X+159488Y+124350X0160Y         S0      
327m4550            PEX3  -D22        A01X+159488Y+124350X0180Y         S1      
317m4551            VIA   -    M      A01X+075509Y+040900X0200Y         S2      
017m4551            VIA   -    M      A18X+075509Y+040900X0260Y         S2      
017m4551                  -    MD0100PA00X+075509Y+040900                       
327m4551            J23   -OB14       A01X+074550Y+041276X0140Y0480R090 S1      
327m4551            R168  -1          A18X+076079Y+040992X0198Y0197R180 S2      
327PRSNT_SSD9_N     J39   -A12        A01X+105852Y+009996X0150Y0500R090 S1      
317PRSNT_SSD9_N     VIA   -    M      A01X+105158Y+010341X0200Y         S2      
017PRSNT_SSD9_N     VIA   -    M      A18X+105158Y+010341X0260Y         S2      
017PRSNT_SSD9_N           -    MD0100PA00X+105158Y+010341                       
327PRSNT_SSD9_N     R4071 -2          A01X+104851Y+010341X0198Y0197R270 S1      
317m4552            VIA   -    MD0080PA01X+019744Y+107894X0160Y    R270 S0      
327m4552            PEX0  -BH15       A01X+019744Y+107894X0180Y         S1      
327m4552            J31   -A21        A01X+014435Y+012122X0150Y0500R090 S1      
317m4552            VIA   -    MD0100PA01X+013075Y+012174X0200Y         S0      
317m4553            VIA   -    MD0080PA01X+064705Y+107520X0160Y    R270 S0      
327m4553            J35   -A26        A01X+060144Y+013303X0150Y0500R090 S1      
317m4553            VIA   -    MD0100PA01X+058784Y+013252X0200Y         S0      
327m4553            PEX1  -BJ13       A01X+064705Y+107520X0180Y         S1      
327m4554            J25   -B37        A01X+120259Y+052852X0140Y0480R090 S1      
327m4554            C441  -2          A01X+122816Y+052911X0120Y0150R180 S1      
317m4555            VIA   -    MD0100PA01X+124257Y+138430X0180Y         S0      
317m4555            J13   -C2   D0122PA01X+131374Y+161138X0282Y    R180 S3      
327m4555            C553  -2          A01X+124247Y+137939X0120Y0150R090 S1      
317m4556            VIA   -    MD0080PA01X+165846Y+107520X0160Y         S0      
327m4556            PEX3  -BJ39       A01X+165846Y+107520X0180Y         S1      
317m4556            VIA   -    MD0100PA01X+158424Y+053109X0200Y    R180 S0      
327m4556            J26   -A20        A01X+157064Y+053057X0140Y0480R270 S1      
317m4557            J14   -J1   D0122PA01X+147831Y+157634X0282Y    R180 S3      
317m4557            VIA   -    MD0080PA01X+154252Y+124350X0160Y         S0      
327m4557            PEX3  -D8         A01X+154252Y+124350X0180Y         S1      
327m4558            VIA   -    M      A01X+070990Y+040072X0300Y    R180 S1      
327m4558            R174  -1          A01X+069092Y+040072X0198Y0197R180 S1      
327m4558            J23   -OA7        A01X+072739Y+039622X0140Y0480R090 S1      
317m4559            VIA   -    MD0080PA01X+022736Y+107894X0160Y    R270 S0      
327m4559            J33   -A21        A01X+034907Y+012122X0150Y0500R090 S1      
317m4559            VIA   -    MD0100PA01X+033547Y+012174X0200Y         S0      
327m4559            PEX0  -BH23       A01X+022736Y+107894X0180Y         S1      
317m4560            VIA   -    MD0080PA01X+065453Y+107894X0160Y    R270 S0      
327m4560            PEX1  -BH15       A01X+065453Y+107894X0180Y         S1      
327m4560            J35   -A21        A01X+060144Y+012122X0150Y0500R090 S1      
317m4560            VIA   -    MD0100PA01X+058784Y+012174X0200Y         S0      
327m4561            J25   -B39        A01X+120259Y+053325X0140Y0480R090 S1      
327m4561            C440  -2          A01X+123856Y+053262X0120Y0150R180 S1      
317m4562            J13   -T4   D0122PA01X+133106Y+148343X0282Y    R180 S3      
317m4562            VIA   -    MD0080PA01X+112657Y+125472X0160Y         S0      
327m4562            PEX2  -A19        A01X+112657Y+125472X0180Y         S1      
317m4563            VIA   -    MD0080PA01X+165472Y+108268X0160Y         S0      
327m4563            PEX3  -BG38       A01X+165472Y+108268X0180Y         S1      
317m4563            VIA   -    MD0100PA01X+157694Y+052400X0200Y    R180 S0      
327m4563            J26   -A23        A01X+157064Y+052348X0140Y0480R270 S1      
317m4564            J14   -I4   D0122PA01X+150429Y+158067X0282Y    R180 S3      
317m4564            VIA   -    MD0080PA01X+155374Y+125098X0160Y         S0      
327m4564            PEX3  -B11        A01X+155374Y+125098X0180Y         S1      
327RST_HP_NIC0_N    VIA   -    M      A18X+021846Y+060878X0260Y         S2      
327RST_HP_NIC0_N    U10   -2          A18X+022802Y+060522X0160Y0360R270 S2      
327RST_HP_NIC0_N    U11   -4          A18X+022780Y+061606X0220Y0530R090 S2      
317m4565            VIA   -    MD0100PA00X+072210Y+045388X0200Y         S0      
327m4565            J23   -A11        A01X+072739Y+045368X0140Y0480R090 S1      
317m4565            VIA   -    M      A01X+077286Y+034794X0200Y    R180 S2      
017m4565            VIA   -    M      A18X+077286Y+034794X0260Y    R180 S2      
017m4565                  -    MD0100PA00X+077286Y+034794                       
327m4565            R199  -1          A01X+077450Y+034547X0198Y0197R270 S1      
317m4566            VIA   -    MD0080PA01X+068445Y+107894X0160Y    R270 S0      
327m4566            J37   -A21        A01X+080616Y+012122X0150Y0500R090 S1      
317m4566            VIA   -    MD0100PA01X+079256Y+012174X0200Y         S0      
327m4566            PEX1  -BH23       A01X+068445Y+107894X0180Y         S1      
317m4567            VIA   -    MD0080PA01X+122382Y+107520X0160Y         S0      
327m4567            PEX2  -BJ45       A01X+122382Y+107520X0180Y         S1      
327m4567            J25   -A53        A01X+118448Y+058329X0140Y0480R090 S1      
317m4567            VIA   -    MD0100PA01X+117088Y+058277X0200Y         S0      
317m4568            VIA   -    MD0080PA01X+164350Y+107520X0160Y         S0      
327m4568            PEX3  -BJ35       A01X+164350Y+107520X0180Y         S1      
317m4568            VIA   -    MD0100PA01X+158424Y+048695X0200Y    R180 S0      
327m4568            J26   -A33        A01X+157064Y+048644X0140Y0480R270 S1      
317m4569            J14   -J5   D0122PA01X+151295Y+157634X0282Y    R180 S3      
317m4569            VIA   -    MD0080PA01X+155748Y+124350X0160Y         S0      
327m4569            PEX3  -D12        A01X+155748Y+124350X0180Y         S1      
317m4570            VIA   -    MD0080PA01X+021240Y+107520X0160Y    R270 S0      
327m4570            J32   -A20        A01X+024671Y+011886X0150Y0500R090 S1      
317m4570            VIA   -    MD0100PA01X+023311Y+011834X0200Y         S0      
327m4570            PEX0  -BJ19       A01X+021240Y+107520X0180Y         S1      
327m4571            C290  -2          A01X+062845Y+011472X0120Y0150R180 S1      
327m4571            J35   -B18        A01X+061955Y+011413X0150Y0500R090 S1      
327m4572            J25   -B34        A01X+120259Y+052144X0140Y0480R090 S1      
327m4572            C443  -2          A01X+123856Y+052205X0120Y0150R180 S1      
317m4573            VIA   -    MD0080PA01X+162480Y+108268X0160Y         S0      
327m4573            PEX3  -BG30       A01X+162480Y+108268X0180Y         S1      
317m4573            VIA   -    MD0100PA01X+157694Y+042983X0200Y    R180 S0      
327m4573            J26   -A50        A01X+157064Y+042931X0140Y0480R270 S1      
317m4574            VIA   -    MD0100PA01X+146137Y+138430X0180Y         S0      
317m4574            J14   -P1   D0122PA01X+147831Y+150468X0282Y    R180 S3      
327m4574            C778  -2          A01X+146127Y+137939X0120Y0150R090 S1      
327m4575            VIA   -    M      A18X+024670Y+062636X0260Y         S2      
327m4575            Q1    -6          A18X+023823Y+063312X0170Y0240R270 S2      
327m4575            U11   -1          A18X+023745Y+062354X0220Y0530R090 S2      
327m4575            R51   -1   M      A18X+024670Y+063311X0198Y0197R270 S2      
317m4576            VIA   -    MD0080PA01X+020118Y+108268X0160Y    R270 S0      
327m4576            PEX0  -BG16       A01X+020118Y+108268X0180Y         S1      
327m4576            J31   -A17        A01X+014435Y+011177X0150Y0500R090 S1      
317m4576            VIA   -    MD0100PA01X+013805Y+011126X0200Y         S0      
317m4577            VIA   -    MD0080PA01X+068071Y+108642X0160Y    R270 S0      
327m4577            PEX1  -BF22       A01X+068071Y+108642X0180Y         S1      
327m4577            J37   -A24        A01X+080616Y+012831X0150Y0500R090 S1      
317m4577            VIA   -    MD0100PA01X+079986Y+012883X0200Y         S0      
327m4578            C429  -2          A01X+122816Y+059332X0120Y0150R180 S1      
327m4578            J25   -B57        A01X+120259Y+059274X0140Y0480R090 S1      
317m4579            VIA   -    MD0080PA01X+165098Y+107520X0160Y         S0      
327m4579            PEX3  -BJ37       A01X+165098Y+107520X0180Y         S1      
317m4579            VIA   -    MD0100PA01X+158424Y+051692X0200Y    R180 S0      
327m4579            J26   -A26        A01X+157064Y+051640X0140Y0480R270 S1      
317m4580            VIA   -    MD0100PA01X+151373Y+140850X0180Y         S0      
317m4580            J14   -C7   D0122PA01X+153028Y+161217X0282Y    R180 S3      
327m4580            C775  -2          A01X+151383Y+140359X0120Y0150R090 S1      
317m4581            VIA   -    MD0080PA01X+022362Y+108268X0160Y    R270 S0      
327m4581            J33   -A23        A01X+034907Y+012594X0150Y0500R090 S1      
317m4581            VIA   -    MD0100PA01X+034277Y+012543X0200Y         S0      
327m4581            PEX0  -BG22       A01X+022362Y+108268X0180Y         S1      
327m4582            C297  -2          A01X+074121Y+011824X0120Y0150R180 S1      
327m4582            J36   -B20        A01X+072191Y+011886X0150Y0500R090 S1      
317m4583            VIA   -    MD0080PA01X+122756Y+112008X0160Y    R270 S0      
327m4583            J25   -A31        A01X+118448Y+051435X0140Y0480R090 S1      
317m4583            VIA   -    MD0100PA01X+117818Y+051487X0200Y         S0      
327m4583            PEX2  -AU46       A01X+122756Y+112008X0180Y         S1      
327m4584            J26   -B44        A01X+155253Y+044348X0140Y0480R270 S1      
327m4584            C683  -2          A01X+151656Y+044413X0120Y0150     S1      
317m4585            J14   -T8   D0122PA01X+153894Y+148343X0282Y    R180 S3      
317m4585            VIA   -    MD0080PA01X+159862Y+125472X0160Y         S0      
327m4585            PEX3  -A23        A01X+159862Y+125472X0180Y         S1      
317m4586            VIA   -    MD0080PA01X+023110Y+108642X0160Y    R270 S0      
327m4586            J33   -A18        A01X+034907Y+011413X0150Y0500R090 S1      
317m4586            VIA   -    MD0100PA01X+034277Y+011466X0200Y         S0      
327m4586            PEX0  -BF24       A01X+023110Y+108642X0180Y         S1      
317m4587            VIA   -    MD0080PA01X+063583Y+108642X0160Y    R270 S0      
327m4587            PEX1  -BF10       A01X+063583Y+108642X0180Y         S1      
327m4587            J34   -A24        A01X+049908Y+012831X0150Y0500R090 S1      
317m4587            VIA   -    MD0100PA01X+049278Y+012883X0200Y         S0      
317m4588            VIA   -    MD0080PA01X+123130Y+107520X0160Y         S0      
327m4588            PEX2  -BJ47       A01X+123130Y+107520X0180Y         S1      
327m4588            J25   -A47        A01X+118448Y+056911X0140Y0480R090 S1      
317m4588            VIA   -    MD0100PA01X+117088Y+056860X0200Y         S0      
317m4589            VIA   -    MD0080PA01X+163602Y+107520X0160Y         S0      
327m4589            PEX3  -BJ33       A01X+163602Y+107520X0180Y         S1      
317m4589            VIA   -    MD0100PA01X+158424Y+047278X0200Y    R180 S0      
327m4589            J26   -A39        A01X+157064Y+047226X0140Y0480R270 S1      
317m4590            VIA   -    MD0100PA01X+147701Y+140850X0180Y         S0      
317m4590            J14   -O3   D0122PA01X+149563Y+150980X0282Y    R180 S3      
327m4590            C783  -2          A01X+147711Y+140359X0120Y0150R090 S1      
327NIC3_SLOT_ID1    VIA   -    M      A01X+070205Y+039386X0300Y    R180 S1      
327NIC3_SLOT_ID1    R180  -1          A01X+069092Y+039672X0198Y0197R180 S1      
327NIC3_SLOT_ID1    R181  -1   M      A01X+069092Y+039272X0198Y0197R180 S1      
327NIC3_SLOT_ID1    J23   -OA6        A01X+072739Y+039386X0140Y0480R090 S1      
317m4591            VIA   -    MD0080PA01X+065827Y+108268X0160Y    R270 S0      
327m4591            PEX1  -BG16       A01X+065827Y+108268X0180Y         S1      
327m4591            J35   -A17        A01X+060144Y+011177X0150Y0500R090 S1      
317m4591            VIA   -    MD0100PA01X+059514Y+011126X0200Y         S0      
317m4592            VIA   -    MD0080PA01X+123504Y+113130X0160Y    R270 S0      
317m4592            VIA   -    MD0100PA01X+117088Y+047782X0200Y         S0      
327m4592            J25   -A21        A01X+118448Y+047730X0140Y0480R090 S1      
327m4592            PEX2  -AP48       A01X+123504Y+113130X0180Y         S1      
317m4593            VIA   -    MD0080PA01X+163228Y+108642X0160Y         S0      
327m4593            PEX3  -BF32       A01X+163228Y+108642X0180Y         S1      
317m4593            VIA   -    MD0100PA01X+157694Y+044060X0200Y    R180 S0      
327m4593            J26   -A45        A01X+157064Y+044112X0140Y0480R270 S1      
317m4594            J14   -V5   D0122PA01X+151295Y+147398X0282Y    R180 S3      
317m4594            VIA   -    MD0080PA01X+158740Y+124350X0160Y         S0      
327m4594            PEX3  -D20        A01X+158740Y+124350X0180Y         S1      
317m4595            VIA   -    M      A01X+072190Y+038450X0200Y         S2      
017m4595            VIA   -    M      A18X+072190Y+038450X0260Y         S2      
017m4595                  -    MD0100PA00X+072190Y+038450                       
327m4595            R201  -1          A01X+069092Y+038472X0198Y0197R180 S1      
327m4595            J23   -OA2        A01X+072739Y+038441X0140Y0480R090 S1      
317m4596            VIA   -    MD0080PA01X+023110Y+108268X0160Y    R270 S0      
327m4596            J33   -A17        A01X+034907Y+011177X0150Y0500R090 S1      
317m4596            VIA   -    MD0100PA01X+034277Y+011126X0200Y         S0      
327m4596            PEX0  -BG24       A01X+023110Y+108268X0180Y         S1      
327m4597            C282  -2          A01X+052609Y+011472X0120Y0150R180 S1      
327m4597            J34   -B18        A01X+051718Y+011413X0150Y0500R090 S1      
327m4598            J25   -B26        A01X+120259Y+048911X0140Y0480R090 S1      
327m4598            C448  -2          A01X+123856Y+048849X0120Y0150R180 S1      
317m4599            VIA   -    MD0080PA01X+163976Y+108642X0160Y         S0      
327m4599            PEX3  -BF34       A01X+163976Y+108642X0180Y         S1      
317m4599            VIA   -    MD0100PA01X+157694Y+047647X0200Y    R180 S0      
327m4599            J26   -A37        A01X+157064Y+047699X0140Y0480R270 S1      
317m4600            VIA   -    MD0100PA01X+148925Y+136010X0180Y         S0      
317m4600            J14   -C3   D0122PA01X+149563Y+161217X0282Y    R180 S3      
327m4600            C767  -2          A01X+148935Y+135519X0120Y0150R090 S1      
317NCSI_NIC3_TXD1   VIA   -    M      A01X+072344Y+039858X0200Y         S2      
017NCSI_NIC3_TXD1   VIA   -    M      A18X+072344Y+039858X0260Y         S2      
017NCSI_NIC3_TXD1         -    MD0100PA00X+072344Y+039858                       
327NCSI_NIC3_TXD1   R172  -1          A01X+069092Y+040472X0198Y0197R180 S1      
327NCSI_NIC3_TXD1   J23   -OA8        A01X+072739Y+039858X0140Y0480R090 S1      
317m4601            VIA   -    MD0080PA01X+063209Y+107520X0160Y    R270 S0      
327m4601            J34   -A26        A01X+049908Y+013303X0150Y0500R090 S1      
317m4601            VIA   -    MD0100PA01X+048548Y+013252X0200Y         S0      
327m4601            PEX1  -BJ9        A01X+063209Y+107520X0180Y         S1      
317m4602            VIA   -    MD0100PA01X+117818Y+056151X0200Y         S0      
327m4602            J25   -A44        A01X+118448Y+056203X0140Y0480R090 S1      
317m4602            VIA   -    MD0080PA01X+123878Y+108268X0160Y    R270 S0      
327m4602            PEX2  -BG49       A01X+123878Y+108268X0180Y         S1      
327m4603            J26   -B50        A01X+155253Y+042931X0140Y0480R270 S1      
327m4603            C687  -2          A01X+151656Y+042996X0120Y0150     S1      
317m4604            J14   -U5   D0122PA01X+151295Y+147910X0282Y    R180 S3      
317m4604            VIA   -    MD0080PA01X+158740Y+124724X0160Y         S0      
327m4604            PEX3  -C20        A01X+158740Y+124724X0180Y         S1      
317m4605            VIA   -    M      A01X+075278Y+038205X0200Y         S2      
017m4605            VIA   -    M      A18X+075278Y+038205X0260Y         S2      
017m4605                  -    MD0100PA00X+075278Y+038205                       
327m4605            R157  -1          A18X+073466Y+038450X0198Y0197     S2      
327m4605            R175  -1   M      A18X+073801Y+038450X0198Y0197R180 S2      
327m4605            J23   -OB1        A01X+074550Y+038205X0140Y0480R090 S1      
317m4606            VIA   -    MD0080PA01X+065453Y+107520X0160Y    R270 S0      
327m4606            J35   -A20        A01X+060144Y+011886X0150Y0500R090 S1      
317m4606            VIA   -    MD0100PA01X+058784Y+011834X0200Y         S0      
327m4606            PEX1  -BJ15       A01X+065453Y+107520X0180Y         S1      
317m4607            VIA   -    MD0080PA01X+123504Y+111634X0160Y    R270 S0      
327m4607            J25   -A34        A01X+118448Y+052144X0140Y0480R090 S1      
317m4607            VIA   -    MD0100PA01X+117088Y+052196X0200Y         S0      
327m4607            PEX2  -AV48       A01X+123504Y+111634X0180Y         S1      
327m4608            J26   -B57        A01X+155253Y+041278X0140Y0480R270 S1      
327m4608            C690  -2          A01X+151656Y+041219X0120Y0150     S1      
317m4609            J14   -I3   D0122PA01X+149563Y+158146X0282Y    R180 S3      
317m4609            VIA   -    MD0080PA01X+155000Y+124724X0160Y         S0      
327m4609            PEX3  -C10        A01X+155000Y+124724X0180Y         S1      
327NIC3_BIF2_N      VIA   -    M      A01X+076846Y+044896X0300Y         S1      
327NIC3_BIF2_N      J23   -B9         A01X+074550Y+044896X0140Y0480R090 S1      
327NIC3_BIF2_N      R186  -1          A01X+078855Y+045051X0198Y0197     S1      
327NIC3_BIF2_N      R187  -1   M      A01X+078470Y+045051X0198Y0197R180 S1      
327m4610            C284  -2          A01X+063885Y+013601X0120Y0150R180 S1      
327m4610            J35   -B27        A01X+061955Y+013539X0150Y0500R090 S1      
327m4611            C428  -2          A01X+123856Y+059684X0120Y0150R180 S1      
327m4611            J25   -B59        A01X+120259Y+059746X0140Y0480R090 S1      
327m4612            J26   -B51        A01X+155253Y+042695X0140Y0480R270 S1      
327m4612            C686  -2          A01X+151656Y+042636X0120Y0150     S1      
317m4613            J14   -I5   D0122PA01X+151295Y+158146X0282Y    R180 S3      
317m4613            VIA   -    MD0080PA01X+155748Y+124724X0160Y         S0      
327m4613            PEX3  -C12        A01X+155748Y+124724X0180Y         S1      
327m4614            VIA   -    M      A18X+074559Y+038800X0260Y         S2      
317m4614            VIA   -    MD0100PA00X+074961Y+038441X0200Y         S0      
327m4614            R155  -1          A18X+074116Y+038800X0198Y0197     S2      
327m4614            J23   -OB2        A01X+074550Y+038441X0140Y0480R090 S1      
317m4615            VIA   -    MD0080PA01X+065079Y+108268X0160Y    R270 S0      
327m4615            J35   -A23        A01X+060144Y+012594X0150Y0500R090 S1      
317m4615            VIA   -    MD0100PA01X+059514Y+012543X0200Y         S0      
327m4615            PEX1  -BG14       A01X+065079Y+108268X0180Y         S1      
327m4616            J25   -B24        A01X+120259Y+048439X0140Y0480R090 S1      
327m4616            C449  -2          A01X+122816Y+048498X0120Y0150R180 S1      
317m4617            VIA   -    MD0080PA01X+162854Y+107894X0160Y         S0      
327m4617            PEX3  -BH31       A01X+162854Y+107894X0180Y         S1      
317m4617            VIA   -    MD0100PA01X+158424Y+043352X0200Y    R180 S0      
327m4617            J26   -A48        A01X+157064Y+043404X0140Y0480R270 S1      
317m4618            J14   -I7   D0122PA01X+153028Y+158146X0282Y    R180 S3      
317m4618            VIA   -    MD0080PA01X+156496Y+124724X0160Y         S0      
327m4618            PEX3  -C14        A01X+156496Y+124724X0180Y         S1      
327m4619            R198  -1          A01X+077850Y+034547X0198Y0197R270 S1      
317m4619            VIA   -    M      A01X+077850Y+034802X0200Y    R180 S2      
017m4619            VIA   -    M      A18X+077850Y+034802X0260Y    R180 S2      
017m4619                  -    MD0100PA00X+077850Y+034802                       
317m4619            VIA   -    MD0100PA00X+073560Y+044996X0200Y         S0      
327m4619            J23   -B10        A01X+074550Y+045132X0140Y0480R090 S1      
317m4620            VIA   -    MD0080PA01X+063957Y+107894X0160Y    R270 S0      
327m4620            J34   -A21        A01X+049908Y+012122X0150Y0500R090 S1      
317m4620            VIA   -    MD0100PA01X+048548Y+012174X0200Y         S0      
327m4620            PEX1  -BH11       A01X+063957Y+107894X0180Y         S1      
317m4621            VIA   -    MD0080PA01X+122382Y+107894X0160Y         S0      
327m4621            PEX2  -BH45       A01X+122382Y+107894X0180Y         S1      
327m4621            J25   -A54        A01X+118448Y+058565X0140Y0480R090 S1      
317m4621            VIA   -    MD0100PA01X+117088Y+058617X0200Y         S0      
327m4622            J26   -B37        A01X+155253Y+047699X0140Y0480R270 S1      
327m4622            C678  -2          A01X+152696Y+047640X0120Y0150     S1      
317m4623            VIA   -    MD0100PA01X+151033Y+140850X0180Y         S0      
317m4623            J14   -D7   D0122PA01X+153028Y+160705X0282Y    R180 S3      
327m4623            C774  -2          A01X+151023Y+140359X0120Y0150R090 S1      
317NIC3_DATA_OUT    VIA   -    M      A01X+075509Y+039150X0200Y         S2      
017NIC3_DATA_OUT    VIA   -    M      A18X+075509Y+039150X0260Y         S2      
017NIC3_DATA_OUT          -    MD0100PA00X+075509Y+039150                       
327NIC3_DATA_OUT    J23   -OB5        A01X+074550Y+039150X0140Y0480R090 S1      
327NIC3_DATA_OUT    R166  -1          A18X+076079Y+038591X0198Y0197R180 S2      
317m4624            VIA   -    MD0080PA01X+021614Y+108642X0160Y    R270 S0      
327m4624            PEX0  -BF20       A01X+021614Y+108642X0180Y         S1      
327m4624            J32   -A18        A01X+024671Y+011413X0150Y0500R090 S1      
317m4624            VIA   -    MD0100PA01X+024041Y+011466X0200Y         S0      
317m4625            VIA   -    MD0080PA01X+064705Y+107894X0160Y    R270 S0      
327m4625            J35   -A27        A01X+060144Y+013539X0150Y0500R090 S1      
317m4625            VIA   -    MD0100PA01X+058784Y+013592X0200Y         S0      
327m4625            PEX1  -BH13       A01X+064705Y+107894X0180Y         S1      
317m4626            VIA   -    MD0080PA01X+123504Y+110886X0160Y    R270 S0      
327m4626            PEX2  -AY48       A01X+123504Y+110886X0180Y         S1      
327m4626            J25   -A40        A01X+118448Y+053561X0140Y0480R090 S1      
317m4626            VIA   -    MD0100PA01X+117088Y+053613X0200Y         S0      
317m4627            VIA   -    MD0080PA01X+165472Y+108642X0160Y         S0      
327m4627            PEX3  -BF38       A01X+165472Y+108642X0180Y         S1      
317m4627            VIA   -    MD0100PA01X+157694Y+052060X0200Y    R180 S0      
327m4627            J26   -A24        A01X+157064Y+052112X0140Y0480R270 S1      
317m4628            VIA   -    MD0100PA01X+151033Y+138430X0180Y         S0      
317m4628            J14   -P7   D0122PA01X+153028Y+150468X0282Y    R180 S3      
327m4628            C790  -2          A01X+151023Y+137939X0120Y0150R090 S1      
327NCSI_NIC0_RXD1   VIA   -    M      A01X+015904Y+060126X0300Y         S1      
327NCSI_NIC0_RXD1   J20   -OB8        A01X+018127Y+060693X0140Y0480R270 S1      
327NCSI_NIC0_RXD1   R17   -1          A01X+015354Y+059959X0198Y0197R180 S1      
327PRSNTB0_NIC3_N   VIA   -    M      A01X+076775Y+054034X0300Y    R180 S1      
327PRSNTB0_NIC3_N   J23   -B42        A01X+074550Y+054034X0140Y0480R090 S1      
327PRSNTB0_NIC3_N   R192  -2          A01X+077260Y+054591X0198Y0197R180 S1      
327PRSNTB0_NIC3_N   R158  -1   M      A01X+077260Y+054191X0198Y0197     S1      
327m4629            C292  -2          A01X+074121Y+013601X0120Y0150R180 S1      
327m4629            J36   -B27        A01X+072191Y+013539X0150Y0500R090 S1      
317m4630            VIA   -    MD0080PA01X+123130Y+111260X0160Y    R270 S0      
327m4630            J25   -A36        A01X+118448Y+052616X0140Y0480R090 S1      
317m4630            VIA   -    MD0100PA01X+117818Y+052564X0200Y         S0      
327m4630            PEX2  -AW47       A01X+123130Y+111260X0180Y         S1      
317m4631            VIA   -    MD0080PA01X+160610Y+107894X0160Y         S0      
327m4631            PEX3  -BH25       A01X+160610Y+107894X0180Y         S1      
317m4631            VIA   -    MD0100PA01X+158424Y+039100X0200Y    R180 S0      
327m4631            J26   -A66        A01X+157064Y+039152X0140Y0480R270 S1      
317m4632            J14   -J7   D0122PA01X+153028Y+157634X0282Y    R180 S3      
317m4632            VIA   -    MD0080PA01X+156496Y+124350X0160Y         S0      
327m4632            PEX3  -D14        A01X+156496Y+124350X0180Y         S1      
327NIC0_SLOT_ID0    VIA   -    M      A01X+015822Y+060619X0300Y         S1      
327NIC0_SLOT_ID0    J20   -OB7        A01X+018127Y+060929X0140Y0480R270 S1      
327NIC0_SLOT_ID0    R26   -1          A01X+015354Y+060759X0198Y0197R180 S1      
327NIC0_SLOT_ID0    R25   -1   M      A01X+015358Y+060360X0198Y0197R180 S1      
327NIC3_BIF1_N      VIA   -    M      A01X+077410Y+044660X0300Y         S1      
327NIC3_BIF1_N      J23   -B8         A01X+074550Y+044660X0140Y0480R090 S1      
327NIC3_BIF1_N      R184  -1          A01X+078855Y+044651X0198Y0197     S1      
327NIC3_BIF1_N      R185  -1   M      A01X+078470Y+044651X0198Y0197R180 S1      
317m4633            VIA   -    MD0080PA01X+018248Y+107520X0160Y    R270 S0      
327m4633            J30   -A20        A01X+004199Y+011886X0150Y0500R090 S1      
317m4633            VIA   -    MD0100PA01X+002839Y+011834X0200Y         S0      
327m4633            PEX0  -BJ11       A01X+018248Y+107520X0180Y         S1      
327m4634            C302  -2          A01X+083317Y+012890X0120Y0150R180 S1      
327m4634            J37   -B24        A01X+082427Y+012831X0150Y0500R090 S1      
317m4635            VIA   -    MD0080PA01X+123878Y+113130X0160Y    R270 S0      
327m4635            J25   -A20        A01X+118448Y+047494X0140Y0480R090 S1      
317m4635            VIA   -    MD0100PA01X+117088Y+047442X0200Y         S0      
327m4635            PEX2  -AP49       A01X+123878Y+113130X0180Y         S1      
317m4636            VIA   -    MD0080PA01X+164350Y+107894X0160Y         S0      
327m4636            PEX3  -BH35       A01X+164350Y+107894X0180Y         S1      
317m4636            VIA   -    MD0100PA01X+158424Y+048355X0200Y    R180 S0      
327m4636            J26   -A34        A01X+157064Y+048408X0140Y0480R270 S1      
317m4637            VIA   -    MD0100PA01X+151373Y+138430X0180Y         S0      
317m4637            J14   -O7   D0122PA01X+153028Y+150980X0282Y    R180 S3      
327m4637            C791  -2          A01X+151383Y+137939X0120Y0150R090 S1      
317m4638            VIA   -    M      A01X+020467Y+055168X0200Y    R180 S2      
017m4638            VIA   -    M      A18X+020467Y+055168X0260Y    R180 S2      
017m4638                  -    MD0100PA00X+020467Y+055168                       
317m4638            VIA   -    MD0100PA00X+022229Y+059090X0200Y         S0      
327m4638            R46   -1          A01X+021794Y+061189X0198Y0197R090 S1      
327m4638            J20   -A11        A01X+019938Y+055183X0140Y0480R270 S1      
327NIC3_LD_N        R164  -1          A18X+076079Y+037791X0198Y0197R180 S2      
317NIC3_LD_N        VIA   -    M      A01X+075609Y+037791X0200Y         S2      
017NIC3_LD_N        VIA   -    M      A18X+075609Y+037791X0260Y         S2      
017NIC3_LD_N              -    MD0100PA00X+075609Y+037791                       
327NIC3_LD_N        J23   -OB3        A01X+074550Y+038677X0140Y0480R090 S1      
317m4639            VIA   -    MD0080PA01X+068445Y+107520X0160Y    R270 S0      
327m4639            J37   -A20        A01X+080616Y+011886X0150Y0500R090 S1      
317m4639            VIA   -    MD0100PA01X+079256Y+011834X0200Y         S0      
327m4639            PEX1  -BJ23       A01X+068445Y+107520X0180Y         S1      
327m4640            J25   -B36        A01X+120259Y+052616X0140Y0480R090 S1      
327m4640            C442  -2          A01X+122816Y+052551X0120Y0150R180 S1      
317m4641            VIA   -    MD0080PA01X+161358Y+107894X0160Y         S0      
327m4641            PEX3  -BH27       A01X+161358Y+107894X0180Y         S1      
317m4641            VIA   -    MD0100PA01X+158424Y+040517X0200Y    R180 S0      
327m4641            J26   -A60        A01X+157064Y+040569X0140Y0480R270 S1      
317m4642            VIA   -    MD0100PA01X+148585Y+136010X0180Y         S0      
317m4642            J14   -D3   D0122PA01X+149563Y+160705X0282Y    R180 S3      
327m4642            C766  -2          A01X+148575Y+135519X0120Y0150R090 S1      
317NCSI_NIC0_TXD0   VIA   -    M      A01X+020800Y+060457X0200Y         S2      
017NCSI_NIC0_TXD0   VIA   -    M      A18X+020800Y+060457X0260Y         S2      
017NCSI_NIC0_TXD0         -    MD0100PA00X+020800Y+060457                       
327NCSI_NIC0_TXD0   R18   -1          A18X+019668Y+059840X0198Y0197     S2      
327NCSI_NIC0_TXD0   J20   -OA9        A01X+019938Y+060457X0140Y0480R270 S1      
317NIC3_CLK         VIA   -    M      A01X+074944Y+039386X0200Y         S2      
017NIC3_CLK         VIA   -    M      A18X+074944Y+039386X0260Y         S2      
017NIC3_CLK               -    MD0100PA00X+074944Y+039386                       
327NIC3_CLK         J23   -OB6        A01X+074550Y+039386X0140Y0480R090 S1      
327NIC3_CLK         R167  -1          A18X+076079Y+038991X0198Y0197R180 S2      
327m4643            C280  -2          A01X+053649Y+012184X0120Y0150R180 S1      
327m4643            J34   -B21        A01X+051718Y+012122X0150Y0500R090 S1      
327m4644            J25   -B21        A01X+120259Y+047730X0140Y0480R090 S1      
327m4644            C451  -2          A01X+123856Y+047792X0120Y0150R180 S1      
317m4645            VIA   -    MD0080PA01X+160984Y+108642X0160Y         S0      
327m4645            PEX3  -BF26       A01X+160984Y+108642X0180Y         S1      
317m4645            VIA   -    MD0100PA01X+157694Y+039808X0200Y    R180 S0      
327m4645            J26   -A63        A01X+157064Y+039860X0140Y0480R270 S1      
317m4646            VIA   -    MD0100PA01X+149809Y+136010X0180Y         S0      
317m4646            J14   -P5   D0122PA01X+151295Y+150468X0282Y    R180 S3      
327m4646            C786  -2          A01X+149799Y+135519X0120Y0150R090 S1      
327m4647            U8    -1          A18X+021246Y+055189X0240Y0240R180 S2      
327m4647            R3    -1   M      A18X+019081Y+054497X0198Y0197R180 S2      
317m4647            VIA   -    M      A01X+018533Y+054553X0200Y         S2      
017m4647            VIA   -    M      A18X+018533Y+054553X0260Y         S2      
017m4647                  -    MD0100PA00X+018533Y+054553                       
327m4647            J20   -B12        A01X+018127Y+054947X0140Y0480R270 S1      
327NIC3_BIF0_N      VIA   -    M      A01X+077609Y+044116X0300Y         S1      
327NIC3_BIF0_N      J23   -B7         A01X+074550Y+044423X0140Y0480R090 S1      
327NIC3_BIF0_N      R182  -1          A01X+078855Y+044251X0198Y0197     S1      
327NIC3_BIF0_N      R183  -1   M      A01X+078467Y+044250X0198Y0197R180 S1      
317m4648            VIA   -    MD0080PA01X+019370Y+108268X0160Y    R270 S0      
327m4648            J31   -A23        A01X+014435Y+012594X0150Y0500R090 S1      
317m4648            VIA   -    MD0100PA01X+013805Y+012543X0200Y         S0      
327m4648            PEX0  -BG14       A01X+019370Y+108268X0180Y         S1      
327m4649            C293  -2          A01X+074121Y+013241X0120Y0150R180 S1      
327m4649            J36   -B26        A01X+072191Y+013303X0150Y0500R090 S1      
327m4650            J25   -B65        A01X+120259Y+061163X0140Y0480R090 S1      
327m4650            C424  -2          A01X+123856Y+061101X0120Y0150R180 S1      
327m4651            J26   -B33        A01X+155253Y+048644X0140Y0480R270 S1      
327m4651            C677  -2          A01X+151656Y+048706X0120Y0150     S1      
317m4652            J14   -I2   D0122PA01X+148697Y+158067X0282Y    R180 S3      
317m4652            VIA   -    MD0080PA01X+154626Y+125098X0160Y         S0      
327m4652            PEX3  -B9         A01X+154626Y+125098X0180Y         S1      
327NIC0_BIF0_N      VIA   -    M      A01X+015898Y+056437X0300Y         S1      
327NIC0_BIF0_N      R29   -1          A01X+014726Y+056256X0198Y0197R180 S1      
327NIC0_BIF0_N      R30   -1   M      A01X+015114Y+056257X0198Y0197     S1      
327NIC0_BIF0_N      J20   -B7         A01X+018127Y+056128X0140Y0480R270 S1      
317PRSNTB1_NIC3_N   VIA   -    M      A01X+071146Y+054671X0200Y         S2      
017PRSNTB1_NIC3_N   VIA   -    M      A18X+071146Y+054671X0260Y         S2      
017PRSNTB1_NIC3_N         -    MD0100PA00X+071146Y+054671                       
327PRSNTB1_NIC3_N   R159  -1          A01X+070855Y+054271X0198Y0197R180 S1      
327PRSNTB1_NIC3_N   J23   -A42        A01X+072739Y+054034X0140Y0480R090 S1      
327PRSNTB1_NIC3_N   R193  -2   M      A01X+070855Y+054671X0198Y0197     S1      
317m4653            VIA   -    MD0080PA01X+017500Y+107520X0160Y    R270 S0      
327m4653            J30   -A26        A01X+004199Y+013303X0150Y0500R090 S1      
317m4653            VIA   -    MD0100PA01X+002839Y+013252X0200Y         S0      
327m4653            PEX0  -BJ9        A01X+017500Y+107520X0180Y         S1      
317m4654            VIA   -    MD0080PA01X+068819Y+108268X0160Y    R270 S0      
327m4654            J37   -A17        A01X+080616Y+011177X0150Y0500R090 S1      
317m4654            VIA   -    MD0100PA01X+079986Y+011126X0200Y         S0      
327m4654            PEX1  -BG24       A01X+068819Y+108268X0180Y         S1      
327m4655            C425  -2          A01X+122816Y+060750X0120Y0150R180 S1      
327m4655            J25   -B63        A01X+120259Y+060691X0140Y0480R090 S1      
327m4656            J26   -B34        A01X+155253Y+048408X0140Y0480R270 S1      
327m4656            C676  -2          A01X+151656Y+048346X0120Y0150     S1      
317m4657            J14   -T6   D0122PA01X+152161Y+148343X0282Y    R180 S3      
317m4657            VIA   -    MD0080PA01X+159114Y+125472X0160Y         S0      
327m4657            PEX3  -A21        A01X+159114Y+125472X0180Y         S1      
327NIC0_LD_N        VIA   -    M      A01X+015822Y+062595X0300Y         S1      
327NIC0_LD_N        J20   -OB3        A01X+018127Y+061874X0140Y0480R270 S1      
327NIC0_LD_N        R11   -1          A01X+015358Y+062360X0198Y0197R180 S1      
317NIC3_SLOT_ID0    VIA   -    M      A01X+075617Y+039791X0200Y         S2      
017NIC3_SLOT_ID0    VIA   -    M      A18X+075617Y+039791X0260Y         S2      
017NIC3_SLOT_ID0          -    MD0100PA00X+075617Y+039791                       
327NIC3_SLOT_ID0    J23   -OB7        A01X+074550Y+039622X0140Y0480R090 S1      
327NIC3_SLOT_ID0    R179  -1          A18X+076079Y+039392X0198Y0197R180 S2      
327NIC3_SLOT_ID0    R178  -1   M      A18X+076079Y+039791X0198Y0197R180 S2      
317m4658            VIA   -    MD0080PA01X+017874Y+108268X0160Y    R270 S0      
327m4658            PEX0  -BG10       A01X+017874Y+108268X0180Y         S1      
327m4658            J30   -A23        A01X+004199Y+012594X0150Y0500R090 S1      
317m4658            VIA   -    MD0100PA01X+003569Y+012543X0200Y         S0      
327m4659            C301  -2          A01X+084357Y+013241X0120Y0150R180 S1      
327m4659            J37   -B26        A01X+082427Y+013303X0150Y0500R090 S1      
327m4660            J25   -B48        A01X+120259Y+057148X0140Y0480R090 S1      
327m4660            C435  -2          A01X+123856Y+057209X0120Y0150R180 S1      
317m4661            VIA   -    MD0080PA01X+161358Y+107520X0160Y         S0      
327m4661            PEX3  -BJ27       A01X+161358Y+107520X0180Y         S1      
317m4661            VIA   -    MD0100PA01X+158424Y+040857X0200Y    R180 S0      
327m4661            J26   -A59        A01X+157064Y+040805X0140Y0480R270 S1      
317m4662            J14   -T2   D0122PA01X+148697Y+148343X0282Y    R180 S3      
317m4662            VIA   -    MD0080PA01X+157618Y+125472X0160Y         S0      
327m4662            PEX3  -A17        A01X+157618Y+125472X0180Y         S1      
327m4663            VIA   -    M      A01X+015902Y+059139X0300Y         S1      
327m4663            R15   -1          A01X+015354Y+059159X0198Y0197R180 S1      
327m4663            J20   -OB14       A01X+018127Y+059276X0140Y0480R270 S1      
327P3V3_SSD8        PU62  -1          A01X+093705Y+019841X0110Y0240     S1      
327P3V3_SSD8        PU62  -2          A01X+093902Y+019841X0110Y0240     S1      
327P3V3_SSD8        PU62  -3          A01X+094098Y+019841X0110Y0240     S1      
327P3V3_SSD8        PU62  -4          A01X+094295Y+019841X0110Y0240     S1      
327P3V3_SSD8        PU62  -5          A01X+094492Y+019841X0110Y0240     S1      
327P3V3_SSD8        R894  -1          A01X+094704Y+022130X0198Y0197R270 S1      
317P3V3_SSD8        VIA   -    MD0100PA00X+094704Y+022388X0200Y    R090 S0      
327P3V3_SSD8        VIA   -           A18X+094041Y+018390X0260Y         S2      
327P3V3_SSD8        PC549 -1          A01X+094058Y+018582X0400Y0500     S1      
327P3V3_SSD8        PC548 -1          A01X+093951Y+019204X0198Y0197R180 S1      
327P3V3_SSD8        PD68  -C          A01X+094537Y+017501X0670Y0990R090 S1      
317P3V3_SSD8        VIA   -    MD0100PA00X+094742Y+018722X0200Y    R090 S0      
317P3V3_SSD8        VIA   -    MD0100PA00X+094442Y+018442X0200Y    R090 S0      
317P3V3_SSD8        VIA   -    MD0100PA00X+094299Y+019568X0200Y    R180 S0      
317P3V3_SSD8        VIA   -    MD0100PA00X+094049Y+019568X0200Y    R180 S0      
317P3V3_SSD8        VIA   -    MD0100PA00X+094226Y+019198X0200Y    R180 S0      
317P3V3_SSD8        VIA   -    MD0100PA00X+094476Y+019198X0200Y    R180 S0      
317P3V3_SSD8        VIA   -    MD0100PA00X+094442Y+018692X0200Y    R090 S0      
317P3V3_SSD8        VIA   -    MD0100PA00X+094791Y+018035X0200Y    R180 S0      
317P3V3_SSD8        VIA   -    M      A01X+094742Y+018442X0200Y    R090 S2      
017P3V3_SSD8        VIA   -    M      A18X+094742Y+018442X0260Y    R090 S2      
017P3V3_SSD8              -    MD0100PA00X+094742Y+018442                       
317P3V3_SSD8        VIA   -    MD0100PA00X+094291Y+018035X0200Y    R180 S0      
317P3V3_SSD8        VIA   -    MD0100PA00X+094041Y+018035X0200Y    R180 S0      
317P3V3_SSD8        VIA   -    MD0100PA00X+094541Y+018035X0200Y    R180 S0      
327P3V3_SSD8        R6086 -1          A01X+088601Y+014754X0198Y0197     S1      
317P3V3_SSD8        VIA   -    MD0100PA00X+088323Y+014754X0200Y         S0      
327P3V3_SSD8        R5759 -1          A01X+100034Y+010824X0198Y0197R270 S1      
317P3V3_SSD8        VIA   -    MD0100PA00X+099777Y+010619X0200Y    R090 S0      
327P3V3_SSD8        R433  -1          A01X+099083Y+010135X0198Y0197R270 S1      
317P3V3_SSD8        VIA   -    MD0100PA00X+099083Y+010378X0200Y    R270 S0      
317P3V3_SSD8        VIA   -    MD0100PA00X+093114Y+011659X0200Y         S0      
317P3V3_SSD8        VIA   -    MD0100PA00X+093114Y+011959X0200Y         S0      
327P3V3_SSD8        PU127 -6_7        A01X+092660Y+011762X0295Y0354R270 S1      
327P3V3_SSD8        PC941 -1   M      A01X+093541Y+011967X0400Y0500R090 S1      
327P3V3_SSD8        R5683 -2          A01X+093659Y+013484X0198Y0197     S1      
327P3V3_SSD8        C973  -2   M      A01X+098475Y+009855X0198Y0197R270 S1      
317P3V3_SSD8        VIA   -    MD0100PA00X+098728Y+009855X0200Y    R090 S0      
327P3V3_SSD8        J38   -B11        A01X+097427Y+009760X0150Y0500R090 S1      
327P3V3_SSD8        R435  -1          A01X+094320Y+009767X0198Y0197     S1      
317P3V3_SSD8        VIA   -    M      A01X+094076Y+009767X0200Y         S2      
017P3V3_SSD8        VIA   -    M      A18X+094076Y+009767X0260Y         S2      
017P3V3_SSD8              -    MD0100PA00X+094076Y+009767                       
327P3V3_SSD8        R1689 -1          A01X+100888Y+008058X0198Y0197R180 S1      
317P3V3_SSD8        VIA   -    MD0100PA00X+101130Y+008058X0200Y         S0      
327P3V3_SSD8        R1688 -1          A01X+100888Y+006858X0198Y0197R180 S1      
317P3V3_SSD8        VIA   -    MD0100PA00X+101128Y+006858X0200Y         S0      
327P3V3_SSD8        U134  -1          A01X+101480Y+006472X0240Y0460R180 S1      
327P3V3_SSD8        C2728 -2   M      A01X+101506Y+005801X0198Y0197R180 S1      
317P3V3_SSD8        VIA   -    MD0100PA00X+101506Y+005551X0200Y         S0      
327m4664            C286  -2          A01X+062845Y+012890X0120Y0150R180 S1      
327m4664            J35   -B24        A01X+061955Y+012831X0150Y0500R090 S1      
327m4665            J25   -B40        A01X+120259Y+053561X0140Y0480R090 S1      
327m4665            C439  -2          A01X+123856Y+053622X0120Y0150R180 S1      
317m4666            VIA   -    MD0080PA01X+163228Y+108268X0160Y         S0      
327m4666            PEX3  -BG32       A01X+163228Y+108268X0180Y         S1      
317m4666            VIA   -    MD0100PA01X+157694Y+044400X0200Y    R180 S0      
327m4666            J26   -A44        A01X+157064Y+044348X0140Y0480R270 S1      
317m4667            VIA   -    MD0100PA01X+148585Y+140850X0180Y         S0      
317m4667            J14   -C4   D0122PA01X+150429Y+161138X0282Y    R180 S3      
327m4667            C768  -2          A01X+148575Y+140359X0120Y0150R090 S1      
317m4668            VIA   -    M      A01X+020909Y+061632X0200Y         S2      
017m4668            VIA   -    M      A18X+020909Y+061632X0260Y         S2      
017m4668                  -    MD0100PA00X+020909Y+061632                       
327m4668            R1    -1          A18X+019352Y+061840X0198Y0197R180 S2      
327m4668            J20   -OA5        A01X+019938Y+061402X0140Y0480R270 S1      
317P3V3_SSD9        VIA   -    MD0100PA00X+104874Y+023871X0200Y    R090 S0      
327P3V3_SSD9        R896  -1          A01X+104874Y+023613X0198Y0197R270 S1      
327P3V3_SSD9        PU64  -1          A01X+103874Y+021324X0110Y0240     S1      
327P3V3_SSD9        PU64  -2          A01X+104071Y+021324X0110Y0240     S1      
327P3V3_SSD9        PU64  -3          A01X+104268Y+021324X0110Y0240     S1      
327P3V3_SSD9        PU64  -4          A01X+104465Y+021324X0110Y0240     S1      
327P3V3_SSD9        PU64  -5          A01X+104662Y+021324X0110Y0240     S1      
327P3V3_SSD9        VIA   -           A18X+104210Y+019873X0260Y         S2      
327P3V3_SSD9        PC561 -1          A01X+104228Y+020064X0400Y0500     S1      
327P3V3_SSD9        PC560 -1          A01X+104121Y+020686X0198Y0197R180 S1      
327P3V3_SSD9        PD70  -C          A01X+104706Y+018984X0670Y0990R090 S1      
317P3V3_SSD9        VIA   -    MD0100PA00X+104396Y+020681X0200Y    R180 S0      
317P3V3_SSD9        VIA   -    MD0100PA00X+104646Y+020681X0200Y    R180 S0      
317P3V3_SSD9        VIA   -    MD0100PA00X+104468Y+021051X0200Y    R180 S0      
317P3V3_SSD9        VIA   -    MD0100PA00X+104912Y+020205X0200Y    R090 S0      
317P3V3_SSD9        VIA   -    MD0100PA00X+104612Y+020175X0200Y    R090 S0      
317P3V3_SSD9        VIA   -    MD0100PA00X+104218Y+021051X0200Y    R180 S0      
317P3V3_SSD9        VIA   -    MD0100PA00X+104960Y+019518X0200Y    R180 S0      
317P3V3_SSD9        VIA   -    M      A01X+104912Y+019925X0200Y    R090 S2      
017P3V3_SSD9        VIA   -    M      A18X+104912Y+019925X0260Y    R090 S2      
017P3V3_SSD9              -    MD0100PA00X+104912Y+019925                       
317P3V3_SSD9        VIA   -    MD0100PA00X+104460Y+019518X0200Y    R180 S0      
317P3V3_SSD9        VIA   -    MD0100PA00X+104612Y+019925X0200Y    R090 S0      
317P3V3_SSD9        VIA   -    MD0100PA00X+104710Y+019518X0200Y    R180 S0      
317P3V3_SSD9        VIA   -    MD0100PA00X+104210Y+019518X0200Y    R180 S0      
317P3V3_SSD9        VIA   -    MD0100PA00X+098560Y+014754X0200Y         S0      
327P3V3_SSD9        R6087 -1          A01X+098837Y+014754X0198Y0197     S1      
317P3V3_SSD9        VIA   -    MD0100PA00X+109320Y+010378X0200Y    R270 S0      
327P3V3_SSD9        R436  -1          A01X+109320Y+010135X0198Y0197R270 S1      
317P3V3_SSD9        VIA   -    MD0100PA00X+110013Y+010619X0200Y    R090 S0      
327P3V3_SSD9        R5761 -1          A01X+110270Y+010824X0198Y0197R270 S1      
327P3V3_SSD9        R5680 -2          A01X+103895Y+013484X0198Y0197     S1      
327P3V3_SSD9        PC943 -1   M      A01X+103777Y+011967X0400Y0500R090 S1      
327P3V3_SSD9        PU128 -6_7        A01X+102897Y+011762X0295Y0354R270 S1      
317P3V3_SSD9        VIA   -    MD0100PA00X+103351Y+011959X0200Y         S0      
317P3V3_SSD9        VIA   -    MD0100PA00X+103351Y+011659X0200Y         S0      
327P3V3_SSD9        J39   -B11        A01X+107663Y+009760X0150Y0500R090 S1      
317P3V3_SSD9        VIA   -    MD0100PA00X+108964Y+009855X0200Y    R090 S0      
327P3V3_SSD9        C974  -2   M      A01X+108711Y+009855X0198Y0197R270 S1      
317P3V3_SSD9        VIA   -    M      A01X+104312Y+009767X0200Y         S2      
017P3V3_SSD9        VIA   -    M      A18X+104312Y+009767X0260Y         S2      
017P3V3_SSD9              -    MD0100PA00X+104312Y+009767                       
327P3V3_SSD9        R438  -1          A01X+104556Y+009767X0198Y0197     S1      
317P3V3_SSD9        VIA   -    MD0100PA00X+111366Y+008058X0200Y         S0      
327P3V3_SSD9        R1692 -1          A01X+111125Y+008058X0198Y0197R180 S1      
317P3V3_SSD9        VIA   -    MD0100PA00X+111365Y+006858X0200Y         S0      
327P3V3_SSD9        R1691 -1          A01X+111125Y+006858X0198Y0197R180 S1      
317P3V3_SSD9        VIA   -    MD0100PA00X+111478Y+005801X0200Y         S0      
327P3V3_SSD9        U135  -1          A01X+111717Y+006472X0240Y0460R180 S1      
327P3V3_SSD9        C2730 -2   M      A01X+111742Y+005801X0198Y0197R180 S1      
317m4669            VIA   -    MD0080PA01X+019370Y+108642X0160Y    R270 S0      
327m4669            J31   -A24        A01X+014435Y+012831X0150Y0500R090 S1      
317m4669            VIA   -    MD0100PA01X+013805Y+012883X0200Y         S0      
327m4669            PEX0  -BF14       A01X+019370Y+108642X0180Y         S1      
317m4670            VIA   -    MD0080PA01X+068819Y+108642X0160Y    R270 S0      
327m4670            J37   -A18        A01X+080616Y+011413X0150Y0500R090 S1      
317m4670            VIA   -    MD0100PA01X+079986Y+011466X0200Y         S0      
327m4670            PEX1  -BF24       A01X+068819Y+108642X0180Y         S1      
327m4671            J25   -B54        A01X+120259Y+058565X0140Y0480R090 S1      
327m4671            C431  -2          A01X+123856Y+058626X0120Y0150R180 S1      
317m4672            VIA   -    MD0080PA01X+166220Y+108642X0160Y         S0      
327m4672            PEX3  -BF40       A01X+166220Y+108642X0180Y         S1      
317m4672            VIA   -    MD0100PA01X+157694Y+053478X0200Y    R180 S0      
327m4672            J26   -A18        A01X+157064Y+053530X0140Y0480R270 S1      
317m4673            VIA   -    MD0100PA01X+149809Y+138430X0180Y         S0      
317m4673            J14   -D5   D0122PA01X+151295Y+160705X0282Y    R180 S3      
327m4673            C770  -2          A01X+149799Y+137939X0120Y0150R090 S1      
317m4674            VIA   -    M      A01X+022169Y+059498X0200Y         S2      
017m4674            VIA   -    M      A18X+022169Y+059498X0260Y         S2      
017m4674                  -    MD0100PA00X+022169Y+059498                       
327m4674            R45   -1          A01X+022181Y+061190X0198Y0197R090 S1      
317m4674            VIA   -    MD0100PA00X+019406Y+057772X0200Y         S0      
327m4674            J20   -B10        A01X+018127Y+055419X0140Y0480R270 S1      
317m4675            VIA   -    MD0080PA01X+020866Y+108268X0160Y    R270 S0      
327m4675            J32   -A23        A01X+024671Y+012594X0150Y0500R090 S1      
317m4675            VIA   -    MD0100PA01X+024041Y+012543X0200Y         S0      
327m4675            PEX0  -BG18       A01X+020866Y+108268X0180Y         S1      
327m4676            C283  -2          A01X+052609Y+011112X0120Y0150R180 S1      
327m4676            J34   -B17        A01X+051718Y+011177X0150Y0500R090 S1      
317m4677            VIA   -    MD0080PA01X+122756Y+108642X0160Y         S0      
327m4677            PEX2  -BF46       A01X+122756Y+108642X0180Y         S1      
327m4677            J25   -A51        A01X+118448Y+057856X0140Y0480R090 S1      
317m4677            VIA   -    MD0100PA01X+117818Y+057908X0200Y         S0      
317m4678            VIA   -    MD0100PA01X+151373Y+136010X0180Y         S0      
317m4678            J14   -B6   D0122PA01X+152161Y+161650X0282Y    R180 S3      
327m4678            C773  -2          A01X+151383Y+135519X0120Y0150R090 S1      
317m4679            VIA   -    M      A01X+020916Y+061007X0200Y         S2      
017m4679            VIA   -    M      A18X+020916Y+061007X0260Y         S2      
017m4679                  -    MD0100PA00X+020916Y+061007                       
327m4679            R21   -1          A18X+019668Y+060640X0198Y0197     S2      
327m4679            J20   -OA7        A01X+019938Y+060929X0140Y0480R270 S1      
327PRSNT_SSD10_N    J40   -A12        A01X+116088Y+009996X0150Y0500R090 S1      
317PRSNT_SSD10_N    VIA   -    M      A01X+115394Y+010341X0200Y         S2      
017PRSNT_SSD10_N    VIA   -    M      A18X+115394Y+010341X0260Y         S2      
017PRSNT_SSD10_N          -    MD0100PA00X+115394Y+010341                       
327PRSNT_SSD10_N    R4073 -2          A01X+115087Y+010341X0198Y0197R270 S1      
317m4680            VIA   -    MD0080PA01X+018996Y+107894X0160Y    R270 S0      
327m4680            J31   -A27        A01X+014435Y+013539X0150Y0500R090 S1      
317m4680            VIA   -    MD0100PA01X+013075Y+013592X0200Y         S0      
327m4680            PEX0  -BH13       A01X+018996Y+107894X0180Y         S1      
317m4681            VIA   -    MD0080PA01X+066575Y+108268X0160Y    R270 S0      
327m4681            J36   -A23        A01X+070380Y+012594X0150Y0500R090 S1      
317m4681            VIA   -    MD0100PA01X+069750Y+012543X0200Y         S0      
327m4681            PEX1  -BG18       A01X+066575Y+108268X0180Y         S1      
317m4682            VIA   -    MD0100PA01X+117818Y+056491X0200Y         S0      
327m4682            J25   -A45        A01X+118448Y+056439X0140Y0480R090 S1      
317m4682            VIA   -    MD0080PA01X+123504Y+108268X0160Y    R270 S0      
327m4682            PEX2  -BG48       A01X+123504Y+108268X0180Y         S1      
317m4683            VIA   -    MD0100PA01X+150149Y+136010X0180Y         S0      
317m4683            J14   -O5   D0122PA01X+151295Y+150980X0282Y    R180 S3      
327m4683            C787  -2          A01X+150159Y+135519X0120Y0150R090 S1      
327PRSNTB0_NIC0_N   VIA   -    M      A01X+015902Y+046518X0300Y         S1      
327PRSNTB0_NIC0_N   R39   -2          A01X+015418Y+045960X0198Y0197     S1      
327PRSNTB0_NIC0_N   J20   -B42        A01X+018127Y+046518X0140Y0480R270 S1      
327PRSNTB0_NIC0_N   R5    -1   M      A01X+015418Y+046360X0198Y0197R180 S1      
327m4684            C303  -2          A01X+083317Y+012530X0120Y0150R180 S1      
327m4684            J37   -B23        A01X+082427Y+012594X0150Y0500R090 S1      
327m4685            J25   -B33        A01X+120259Y+051908X0140Y0480R090 S1      
327m4685            C444  -2          A01X+123856Y+051845X0120Y0150R180 S1      
317m4686            J14   -J3   D0122PA01X+149563Y+157634X0282Y    R180 S3      
317m4686            VIA   -    MD0080PA01X+155000Y+124350X0160Y         S0      
327m4686            PEX3  -D10        A01X+155000Y+124350X0180Y         S1      
327m4687            VIA   -    M      A01X+021400Y+062540X0300Y         S1      
327m4687            R47   -1          A01X+021882Y+062540X0198Y0197     S1      
327m4687            J20   -OA1        A01X+019938Y+062346X0140Y0480R270 S1      
317m4688            VIA   -    MD0080PA01X+064331Y+108268X0160Y    R270 S0      
327m4688            PEX1  -BG12       A01X+064331Y+108268X0180Y         S1      
327m4688            J34   -A17        A01X+049908Y+011177X0150Y0500R090 S1      
317m4688            VIA   -    MD0100PA01X+049278Y+011126X0200Y         S0      
317m4689            VIA   -    MD0080PA01X+123130Y+112008X0160Y    R270 S0      
327m4689            J25   -A30        A01X+118448Y+051199X0140Y0480R090 S1      
317m4689            VIA   -    MD0100PA01X+117818Y+051147X0200Y         S0      
327m4689            PEX2  -AU47       A01X+123130Y+112008X0180Y         S1      
317m4690            VIA   -    MD0100PA01X+148925Y+140850X0180Y         S0      
317m4690            J14   -B4   D0122PA01X+150429Y+161650X0282Y    R180 S3      
327m4690            C769  -2          A01X+148935Y+140359X0120Y0150R090 S1      
327NIC0_BIF2_N      VIA   -    M      A01X+015904Y+055267X0300Y         S1      
327NIC0_BIF2_N      R33   -1          A01X+014726Y+055456X0198Y0197R180 S1      
327NIC0_BIF2_N      R34   -1   M      A01X+015111Y+055456X0198Y0197     S1      
327NIC0_BIF2_N      J20   -B9         A01X+018127Y+055656X0140Y0480R270 S1      
317m4691            VIA   -    MD0080PA01X+018248Y+107894X0160Y    R270 S0      
327m4691            J30   -A21        A01X+004199Y+012122X0150Y0500R090 S1      
317m4691            VIA   -    MD0100PA01X+002839Y+012174X0200Y         S0      
327m4691            PEX0  -BH11       A01X+018248Y+107894X0180Y         S1      
317m4692            VIA   -    MD0080PA01X+067697Y+107520X0160Y    R270 S0      
327m4692            J37   -A26        A01X+080616Y+013303X0150Y0500R090 S1      
317m4692            VIA   -    MD0100PA01X+079256Y+013252X0200Y         S0      
327m4692            PEX1  -BJ21       A01X+067697Y+107520X0180Y         S1      
317m4693            VIA   -    MD0080PA01X+123878Y+111634X0160Y    R270 S0      
327m4693            J25   -A33        A01X+118448Y+051908X0140Y0480R090 S1      
317m4693            VIA   -    MD0100PA01X+117088Y+051856X0200Y         S0      
327m4693            PEX2  -AV49       A01X+123878Y+111634X0180Y         S1      
317m4694            VIA   -    MD0100PA01X+147361Y+140850X0180Y         S0      
317m4694            J14   -P3   D0122PA01X+149563Y+150468X0282Y    R180 S3      
327m4694            C782  -2          A01X+147351Y+140359X0120Y0150R090 S1      
327m4695            VIA   -    M      A01X+015902Y+063089X0300Y         S1      
327m4695            R2    -1          A01X+015358Y+062760X0198Y0197R180 S1      
327m4695            J20   -OB2        A01X+018127Y+062110X0140Y0480R270 S1      
327m4696            C291  -2          A01X+062845Y+011112X0120Y0150R180 S1      
327m4696            J35   -B17        A01X+061955Y+011177X0150Y0500R090 S1      
327m4697            J25   -B20        A01X+120259Y+047494X0140Y0480R090 S1      
327m4697            C452  -2          A01X+123856Y+047432X0120Y0150R180 S1      
317m4698            VIA   -    MD0100PA01X+150149Y+138430X0180Y         S0      
317m4698            J14   -C5   D0122PA01X+151295Y+161217X0282Y    R180 S3      
327m4698            C771  -2          A01X+150159Y+137939X0120Y0150R090 S1      
317m4699            VIA   -    MD0080PA01X+021240Y+107894X0160Y    R270 S0      
327m4699            J32   -A21        A01X+024671Y+012122X0150Y0500R090 S1      
317m4699            VIA   -    MD0100PA01X+023311Y+012174X0200Y         S0      
327m4699            PEX0  -BH19       A01X+021240Y+107894X0180Y         S1      
327m4700            C277  -2          A01X+053649Y+013241X0120Y0150R180 S1      
327m4700            J34   -B26        A01X+051718Y+013303X0150Y0500R090 S1      
317m4701            VIA   -    MD0080PA01X+122756Y+112756X0160Y    R270 S0      
327m4701            PEX2  -AR46       A01X+122756Y+112756X0180Y         S1      
327m4701            J25   -A24        A01X+118448Y+048439X0140Y0480R090 S1      
317m4701            VIA   -    MD0100PA01X+117818Y+048491X0200Y         S0      
317m4702            VIA   -    MD0100PA01X+146477Y+138430X0180Y         S0      
317m4702            J14   -O1   D0122PA01X+147831Y+150980X0282Y    R180 S3      
327m4702            C779  -2          A01X+146487Y+137939X0120Y0150R090 S1      
317m4703            VIA   -    MD0080PA01X+064331Y+108642X0160Y    R270 S0      
327m4703            PEX1  -BF12       A01X+064331Y+108642X0180Y         S1      
327m4703            J34   -A18        A01X+049908Y+011413X0150Y0500R090 S1      
317m4703            VIA   -    MD0100PA01X+049278Y+011466X0200Y         S0      
317m4704            VIA   -    MD0080PA01X+121634Y+107520X0160Y         S0      
327m4704            PEX2  -BJ43       A01X+121634Y+107520X0180Y         S1      
327m4704            J25   -A59        A01X+118448Y+059746X0140Y0480R090 S1      
317m4704            VIA   -    MD0100PA01X+117088Y+059694X0200Y         S0      
317m4705            VIA   -    MD0100PA01X+147361Y+138430X0180Y         S0      
317m4705            J14   -C2   D0122PA01X+148697Y+161138X0282Y    R180 S3      
327m4705            C764  -2          A01X+147351Y+137939X0120Y0150R090 S1      
327m4706            VIA   -    M      A01X+015856Y+063798X0300Y         S1      
327m4706            J20   -OB1        A01X+018127Y+062346X0140Y0480R270 S1      
327m4706            R4    -1          A01X+015358Y+064197X0198Y0197R180 S1      
327m4706            R22   -1   M      A01X+015358Y+063797X0198Y0197R180 S1      
317m4707            VIA   -    MD0080PA01X+021988Y+107520X0160Y    R270 S0      
327m4707            J33   -A26        A01X+034907Y+013303X0150Y0500R090 S1      
317m4707            VIA   -    MD0100PA01X+033547Y+013252X0200Y         S0      
327m4707            PEX0  -BJ21       A01X+021988Y+107520X0180Y         S1      
327m4708            C289  -2          A01X+063885Y+011824X0120Y0150R180 S1      
327m4708            J35   -B20        A01X+061955Y+011886X0150Y0500R090 S1      
317m4709            VIA   -    MD0080PA01X+123504Y+112382X0160Y    R270 S0      
327m4709            J25   -A27        A01X+118448Y+049148X0140Y0480R090 S1      
317m4709            VIA   -    MD0100PA01X+117088Y+049200X0200Y         S0      
327m4709            PEX2  -AT48       A01X+123504Y+112382X0180Y         S1      
317m4710            VIA   -    MD0100PA01X+111931Y+136010X0180Y         S0      
317m4710            J7    -H8   D0122PA01X+119248Y+158579X0282Y    R180 S3      
327m4710            C600  -2          A01X+111941Y+135519X0120Y0150R090 S1      
317m4711            J14   -H6   D0122PA01X+152161Y+158579X0282Y    R180 S3      
317m4711            VIA   -    MD0080PA01X+156122Y+125472X0160Y         S0      
327m4711            PEX3  -A13        A01X+156122Y+125472X0180Y         S1      
327PRSNTB2_NIC0_N   VIA   -    M      A01X+021366Y+054947X0300Y         S1      
327PRSNTB2_NIC0_N   J20   -A12        A01X+019938Y+054947X0140Y0480R270 S1      
327PRSNTB2_NIC0_N   R41   -2          A01X+021842Y+054580X0198Y0197R180 S1      
327PRSNTB2_NIC0_N   R7    -1   M      A01X+021842Y+054980X0198Y0197     S1      
317RST_HP_NIC5_N    VIA   -    M      A01X+121189Y+033956X0200Y         S2      
017RST_HP_NIC5_N    VIA   -    M      A18X+121189Y+033956X0260Y         S2      
017RST_HP_NIC5_N          -    MD0100PA00X+121189Y+033956                       
327RST_HP_NIC5_N    U35   -2          A01X+121746Y+034488X0160Y0360R270 S1      
327RST_HP_NIC5_N    U36   -4          A01X+122480Y+033632X0220Y0530R090 S1      
317m4712            VIA   -    MD0080PA01X+017500Y+107894X0160Y    R270 S0      
327m4712            J30   -A27        A01X+004199Y+013539X0150Y0500R090 S1      
317m4712            VIA   -    MD0100PA01X+002839Y+013592X0200Y         S0      
327m4712            PEX0  -BH9        A01X+017500Y+107894X0180Y         S1      
317m4713            VIA   -    MD0080PA01X+063209Y+107894X0160Y    R270 S0      
327m4713            J34   -A27        A01X+049908Y+013539X0150Y0500R090 S1      
317m4713            VIA   -    MD0100PA01X+048548Y+013592X0200Y         S0      
327m4713            PEX1  -BH9        A01X+063209Y+107894X0180Y         S1      
327m4714            J25   -B18        A01X+120259Y+047022X0140Y0480R090 S1      
327m4714            C453  -2          A01X+122816Y+047081X0120Y0150R180 S1      
317m4715            J7    -C2   D0122PA01X+114051Y+161138X0282Y    R180 S3      
317m4715            VIA   -    MD0080PA01X+106299Y+119114X0160Y         S0      
327m4715            PEX2  -V2         A01X+106299Y+119114X0180Y         S1      
317m4716            J14   -I6   D0122PA01X+152161Y+158067X0282Y    R180 S3      
317m4716            VIA   -    MD0080PA01X+156122Y+125098X0160Y         S0      
327m4716            PEX3  -B13        A01X+156122Y+125098X0180Y         S1      
317NIC0_SLOT_ID1    VIA   -    M      A01X+020374Y+061259X0200Y         S2      
017NIC0_SLOT_ID1    VIA   -    M      A18X+020374Y+061259X0260Y         S2      
017NIC0_SLOT_ID1          -    MD0100PA00X+020374Y+061259                       
327NIC0_SLOT_ID1    R28   -1          A18X+019668Y+061440X0198Y0197     S2      
327NIC0_SLOT_ID1    R27   -1   M      A18X+019668Y+061040X0198Y0197     S2      
327NIC0_SLOT_ID1    J20   -OA6        A01X+019938Y+061165X0140Y0480R270 S1      
317m4717            VIA   -    M      A01X+122644Y+032452X0200Y         S2      
017m4717            VIA   -    M      A18X+122644Y+032452X0260Y         S2      
017m4717                  -    MD0100PA00X+122644Y+032452                       
327m4717            U36   -1          A01X+123445Y+032884X0220Y0530R090 S1      
327m4717            Q6    -6          A01X+122149Y+032185X0170Y0240R270 S1      
327m4717            R306  -1   M      A01X+122644Y+032189X0198Y0197R270 S1      
327PRSNT_SSD11_N    J41   -A12        A01X+126325Y+009996X0150Y0500R090 S1      
317PRSNT_SSD11_N    VIA   -    M      A01X+125631Y+010341X0200Y         S2      
017PRSNT_SSD11_N    VIA   -    M      A18X+125631Y+010341X0260Y         S2      
017PRSNT_SSD11_N          -    MD0100PA00X+125631Y+010341                       
327PRSNT_SSD11_N    R4075 -2          A01X+125323Y+010341X0198Y0197R270 S1      
317m4718            VIA   -    MD0080PA01X+063957Y+107520X0160Y    R270 S0      
327m4718            J34   -A20        A01X+049908Y+011886X0150Y0500R090 S1      
317m4718            VIA   -    MD0100PA01X+048548Y+011834X0200Y         S0      
327m4718            PEX1  -BJ11       A01X+063957Y+107520X0180Y         S1      
327m4719            J25   -B66        A01X+120259Y+061400X0140Y0480R090 S1      
327m4719            C423  -2          A01X+123856Y+061461X0120Y0150R180 S1      
317m4720            VIA   -    MD0100PA01X+108259Y+138430X0180Y         S0      
317m4720            J7    -H4   D0122PA01X+115783Y+158579X0282Y    R180 S3      
327m4720            C608  -2          A01X+108269Y+137939X0120Y0150R090 S1      
317m4721            VIA   -    MD0100PA01X+148585Y+138430X0180Y         S0      
317m4721            J14   -O4   D0122PA01X+150429Y+150902X0282Y    R180 S3      
327m4721            C784  -2          A01X+148575Y+137939X0120Y0150R090 S1      
317m4722            VIA   -    MD0080PA01X+066201Y+107894X0160Y    R270 S0      
327m4722            J36   -A27        A01X+070380Y+013539X0150Y0500R090 S1      
317m4722            VIA   -    MD0100PA01X+069020Y+013592X0200Y         S0      
327m4722            PEX1  -BH17       A01X+066201Y+107894X0180Y         S1      
317m4723            VIA   -    MD0080PA01X+123130Y+107894X0160Y         S0      
317m4723            VIA   -    MD0100PA01X+117088Y+057200X0200Y         S0      
327m4723            J25   -A48        A01X+118448Y+057148X0140Y0480R090 S1      
327m4723            PEX2  -BH47       A01X+123130Y+107894X0180Y         S1      
317m4724            VIA   -    MD0100PA01X+147361Y+136010X0180Y         S0      
317m4724            J14   -O2   D0122PA01X+148697Y+150902X0282Y    R180 S3      
327m4724            C780  -2          A01X+147351Y+135519X0120Y0150R090 S1      
317m4725            VIA   -    MD0080PA01X+020492Y+107520X0160Y    R270 S0      
327m4725            J32   -A26        A01X+024671Y+013303X0150Y0500R090 S1      
317m4725            VIA   -    MD0100PA01X+023311Y+013252X0200Y         S0      
327m4725            PEX0  -BJ17       A01X+020492Y+107520X0180Y         S1      
317m4726            VIA   -    MD0080PA01X+067697Y+107894X0160Y    R270 S0      
327m4726            J37   -A27        A01X+080616Y+013539X0150Y0500R090 S1      
317m4726            VIA   -    MD0100PA01X+079256Y+013592X0200Y         S0      
327m4726            PEX1  -BH21       A01X+067697Y+107894X0180Y         S1      
327m4727            J25   -B50        A01X+120259Y+057620X0140Y0480R090 S1      
327m4727            C434  -2          A01X+122816Y+057555X0120Y0150R180 S1      
317m4728            J7    -C3   D0122PA01X+114917Y+161217X0282Y    R180 S3      
317m4728            VIA   -    MD0080PA01X+106673Y+119488X0160Y         S0      
327m4728            PEX2  -U3         A01X+106673Y+119488X0180Y         S1      
317m4729            J14   -U3   D0122PA01X+149563Y+147910X0282Y    R180 S3      
317m4729            VIA   -    MD0080PA01X+157992Y+124724X0160Y         S0      
327m4729            PEX3  -C18        A01X+157992Y+124724X0180Y         S1      
317NCSI_NIC0_TXD1   VIA   -    M      A01X+020350Y+060693X0200Y         S2      
017NCSI_NIC0_TXD1   VIA   -    M      A18X+020350Y+060693X0260Y         S2      
017NCSI_NIC0_TXD1         -    MD0100PA00X+020350Y+060693                       
327NCSI_NIC0_TXD1   R19   -1          A18X+019668Y+060240X0198Y0197     S2      
327NCSI_NIC0_TXD1   J20   -OA8        A01X+019938Y+060693X0140Y0480R270 S1      
327m4730            C307  -2          A01X+083317Y+011112X0120Y0150R180 S1      
327m4730            J37   -B17        A01X+082427Y+011177X0150Y0500R090 S1      
317m4731            VIA   -    MD0080PA01X+122008Y+108642X0160Y         S0      
327m4731            PEX2  -BF44       A01X+122008Y+108642X0180Y         S1      
327m4731            J25   -A57        A01X+118448Y+059274X0140Y0480R090 S1      
317m4731            VIA   -    MD0100PA01X+117818Y+059326X0200Y         S0      
317m4732            VIA   -    MD0100PA01X+149809Y+140850X0180Y         S0      
317m4732            J14   -O6   D0122PA01X+152161Y+150902X0282Y    R180 S3      
327m4732            C788  -2          A01X+149799Y+140359X0120Y0150R090 S1      
327m4733            VIA   -    M      A01X+021400Y+061950X0300Y         S1      
327m4733            R48   -1          A01X+021882Y+062140X0198Y0197     S1      
327m4733            J20   -OA2        A01X+019938Y+062110X0140Y0480R270 S1      
327m4734            C295  -2          A01X+073081Y+012530X0120Y0150R180 S1      
327m4734            J36   -B23        A01X+072191Y+012594X0150Y0500R090 S1      
327m4735            J25   -B30        A01X+120259Y+051199X0140Y0480R090 S1      
327m4735            C446  -2          A01X+122816Y+051134X0120Y0150R180 S1      
317m4736            VIA   -    MD0100PA01X+111591Y+136010X0180Y         S0      
317m4736            J7    -I8   D0122PA01X+119248Y+158067X0282Y    R180 S3      
327m4736            C599  -2          A01X+111581Y+135519X0120Y0150R090 S1      
317m4737            VIA   -    MD0100PA01X+151033Y+136010X0180Y         S0      
317m4737            J14   -C6   D0122PA01X+152161Y+161138X0282Y    R180 S3      
327m4737            C772  -2          A01X+151023Y+135519X0120Y0150R090 S1      
327NIC0_CLK         VIA   -    M      A01X+015905Y+061113X0300Y         S1      
327NIC0_CLK         R14   -1          A01X+015358Y+061160X0198Y0197R180 S1      
327NIC0_CLK         J20   -OB6        A01X+018127Y+061165X0140Y0480R270 S1      
327m4738            C296  -2          A01X+074121Y+012184X0120Y0150R180 S1      
327m4738            J36   -B21        A01X+072191Y+012122X0150Y0500R090 S1      
317m4739            VIA   -    MD0080PA01X+121260Y+108642X0160Y         S0      
327m4739            PEX2  -BF42       A01X+121260Y+108642X0180Y         S1      
317m4739            VIA   -    MD0100PA01X+117818Y+060743X0200Y         S0      
327m4739            J25   -A63        A01X+118448Y+060691X0140Y0480R090 S1      
317m4740            J14   -T4   D0122PA01X+150429Y+148343X0282Y    R180 S3      
317m4740            VIA   -    MD0080PA01X+158366Y+125472X0160Y         S0      
327m4740            PEX3  -A19        A01X+158366Y+125472X0180Y         S1      
317m4741            VIA   -    M      A01X+020850Y+059550X0200Y         S2      
017m4741            VIA   -    M      A18X+020850Y+059550X0260Y         S2      
017m4741                  -    MD0100PA00X+020850Y+059550                       
327m4741            R20   -1          A18X+019668Y+059440X0198Y0197     S2      
327m4741            J20   -OA14       A01X+019938Y+059276X0140Y0480R270 S1      
327m4742            C288  -2          A01X+063885Y+012184X0120Y0150R180 S1      
327m4742            J35   -B21        A01X+061955Y+012122X0150Y0500R090 S1      
317m4743            VIA   -    MD0080PA01X+123878Y+110886X0160Y    R270 S0      
327m4743            J25   -A39        A01X+118448Y+053325X0140Y0480R090 S1      
317m4743            VIA   -    MD0100PA01X+117088Y+053273X0200Y         S0      
327m4743            PEX2  -AY49       A01X+123878Y+110886X0180Y         S1      
317m4744            J7    -B4   D0122PA01X+115783Y+161650X0282Y    R180 S3      
317m4744            VIA   -    MD0080PA01X+105925Y+119862X0160Y         S0      
327m4744            PEX2  -T1         A01X+105925Y+119862X0180Y         S1      
317m4745            J14   -U1   D0122PA01X+147831Y+147910X0282Y    R180 S3      
317m4745            VIA   -    MD0080PA01X+157244Y+124724X0160Y         S0      
327m4745            PEX3  -C16        A01X+157244Y+124724X0180Y         S1      
327m4746            C285  -2          A01X+063885Y+013241X0120Y0150R180 S1      
327m4746            J35   -B26        A01X+061955Y+013303X0150Y0500R090 S1      
327m4747            J25   -B23        A01X+120259Y+048203X0140Y0480R090 S1      
327m4747            C450  -2          A01X+122816Y+048138X0120Y0150R180 S1      
317m4748            VIA   -    MD0100PA01X+109143Y+136010X0180Y         S0      
317m4748            J7    -J5   D0122PA01X+116650Y+157634X0282Y    R180 S3      
327m4748            C605  -2          A01X+109133Y+135519X0120Y0150R090 S1      
317m4749            VIA   -    MD0100PA01X+146477Y+136010X0180Y         S0      
317m4749            J14   -C1   D0122PA01X+147831Y+161217X0282Y    R180 S3      
327m4749            C763  -2          A01X+146487Y+135519X0120Y0150R090 S1      
317m4750            VIA   -    MD0080PA01X+022736Y+107520X0160Y    R270 S0      
327m4750            J33   -A20        A01X+034907Y+011886X0150Y0500R090 S1      
317m4750            VIA   -    MD0100PA01X+033547Y+011834X0200Y         S0      
327m4750            PEX0  -BJ23       A01X+022736Y+107520X0180Y         S1      
317m4751            VIA   -    MD0080PA01X+066201Y+107520X0160Y    R270 S0      
327m4751            J36   -A26        A01X+070380Y+013303X0150Y0500R090 S1      
317m4751            VIA   -    MD0100PA01X+069020Y+013252X0200Y         S0      
327m4751            PEX1  -BJ17       A01X+066201Y+107520X0180Y         S1      
317m4752            VIA   -    MD0080PA01X+122756Y+111260X0160Y    R270 S0      
327m4752            J25   -A37        A01X+118448Y+052852X0140Y0480R090 S1      
317m4752            VIA   -    MD0100PA01X+117818Y+052904X0200Y         S0      
327m4752            PEX2  -AW46       A01X+122756Y+111260X0180Y         S1      
317m4753            J7    -C4   D0122PA01X+115783Y+161138X0282Y    R180 S3      
317m4753            VIA   -    MD0080PA01X+106299Y+119862X0160Y         S0      
327m4753            PEX2  -T2         A01X+106299Y+119862X0180Y         S1      
317m4754            VIA   -    MD0100PA01X+152597Y+138430X0180Y         S0      
317m4754            J14   -B8   D0122PA01X+153894Y+161650X0282Y    R180 S3      
327m4754            C777  -2          A01X+152607Y+137939X0120Y0150R090 S1      
327m4755            C430  -2          A01X+122816Y+058972X0120Y0150R180 S1      
327m4755            J25   -B56        A01X+120259Y+059037X0140Y0480R090 S1      
317m4756            VIA   -    MD0100PA01X+152597Y+136010X0180Y         S0      
317m4756            J14   -N8   D0122PA01X+153894Y+151413X0282Y    R180 S3      
327m4756            C793  -2          A01X+152607Y+135519X0120Y0150R090 S1      
327PRSNTB3_NIC0_N   VIA   -    M      A01X+015893Y+038260X0300Y         S1      
327PRSNTB3_NIC0_N   R42   -2          A01X+015418Y+037860X0198Y0197     S1      
327PRSNTB3_NIC0_N   J20   -B70        A01X+018127Y+038207X0140Y0480R270 S1      
327PRSNTB3_NIC0_N   R8    -1   M      A01X+015418Y+038260X0198Y0197R180 S1      
317m4757            VIA   -    MD0080PA01X+021988Y+107894X0160Y    R270 S0      
327m4757            J33   -A27        A01X+034907Y+013539X0150Y0500R090 S1      
317m4757            VIA   -    MD0100PA01X+033547Y+013592X0200Y         S0      
327m4757            PEX0  -BH21       A01X+021988Y+107894X0180Y         S1      
317m4758            VIA   -    MD0080PA01X+123130Y+113504X0160Y    R270 S0      
317m4758            VIA   -    MD0100PA01X+117818Y+046734X0200Y         S0      
327m4758            J25   -A17        A01X+118448Y+046785X0140Y0480R090 S1      
327m4758            PEX2  -AN47       A01X+123130Y+113504X0180Y         S1      
317m4759            VIA   -    MD0100PA01X+152257Y+136010X0180Y         S0      
317m4759            J14   -O8   D0122PA01X+153894Y+150902X0282Y    R180 S3      
327m4759            C792  -2          A01X+152247Y+135519X0120Y0150R090 S1      
327NIC0_DATA_IN     VIA   -    M      A01X+015905Y+062100X0300Y         S1      
327NIC0_DATA_IN     J20   -OB4        A01X+018127Y+061638X0140Y0480R270 S1      
327NIC0_DATA_IN     R12   -1          A01X+015358Y+061960X0198Y0197R180 S1      
317m4760            VIA   -    MD0080PA01X+018622Y+108642X0160Y    R270 S0      
327m4760            PEX0  -BF12       A01X+018622Y+108642X0180Y         S1      
327m4760            J30   -A18        A01X+004199Y+011413X0150Y0500R090 S1      
317m4760            VIA   -    MD0100PA01X+003569Y+011466X0200Y         S0      
327m4761            C426  -2          A01X+122816Y+060390X0120Y0150R180 S1      
327m4761            J25   -B62        A01X+120259Y+060455X0140Y0480R090 S1      
317m4762            VIA   -    MD0100PA01X+106695Y+136010X0180Y         S0      
317m4762            J7    -I2   D0122PA01X+114051Y+158067X0282Y    R180 S3      
327m4762            C611  -2          A01X+106685Y+135519X0120Y0150R090 S1      
317m4763            J14   -H8   D0122PA01X+153894Y+158579X0282Y    R180 S3      
317m4763            VIA   -    MD0080PA01X+156870Y+125472X0160Y         S0      
327m4763            PEX3  -A15        A01X+156870Y+125472X0180Y         S1      
327m4764            J25   -B47        A01X+120259Y+056911X0140Y0480R090 S1      
327m4764            C436  -2          A01X+123856Y+056849X0120Y0150R180 S1      
317m4765            VIA   -    MD0100PA01X+110707Y+138430X0180Y         S0      
317m4765            J7    -I7   D0122PA01X+118382Y+158146X0282Y    R180 S3      
327m4765            C602  -2          A01X+110717Y+137939X0120Y0150R090 S1      
317m4766            VIA   -    M      A01X+020346Y+061840X0200Y         S2      
017m4766            VIA   -    M      A18X+020346Y+061840X0260Y         S2      
017m4766                  -    MD0100PA00X+020346Y+061840                       
327m4766            R1    -2          A18X+019668Y+061840X0198Y0197R180 S2      
327m4766            J20   -OA4        A01X+019938Y+061638X0140Y0480R270 S1      
327NIC5_BIF2_N      VIA   -    M      A18X+117217Y+043300X0260Y         S2      
317NIC5_BIF2_N      VIA   -    MD0100PA00X+119300Y+044484X0200Y         S0      
327NIC5_BIF2_N      R288  -1          A18X+115826Y+043503X0198Y0197     S2      
327NIC5_BIF2_N      R289  -1   M      A18X+116211Y+043503X0198Y0197R180 S2      
327NIC5_BIF2_N      J25   -B9         A01X+120259Y+044896X0140Y0480R090 S1      
327m4767            J25   -B45        A01X+120259Y+056439X0140Y0480R090 S1      
327m4767            C437  -2          A01X+122816Y+056498X0120Y0150R180 S1      
327PRSNTB1_NIC0_N   VIA   -    M      A01X+021359Y+046280X0300Y         S1      
327PRSNTB1_NIC0_N   J20   -A42        A01X+019938Y+046518X0140Y0480R270 S1      
327PRSNTB1_NIC0_N   R40   -2          A01X+021822Y+045880X0198Y0197R180 S1      
327PRSNTB1_NIC0_N   R6    -1   M      A01X+021822Y+046280X0198Y0197     S1      
317m4768            VIA   -    MD0080PA01X+018622Y+108268X0160Y    R270 S0      
327m4768            PEX0  -BG12       A01X+018622Y+108268X0180Y         S1      
327m4768            J30   -A17        A01X+004199Y+011177X0150Y0500R090 S1      
317m4768            VIA   -    MD0100PA01X+003569Y+011126X0200Y         S0      
317m4769            VIA   -    MD0080PA01X+121260Y+108268X0160Y         S0      
327m4769            PEX2  -BG42       A01X+121260Y+108268X0180Y         S1      
327m4769            J25   -A62        A01X+118448Y+060455X0140Y0480R090 S1      
317m4769            VIA   -    MD0100PA01X+117818Y+060403X0200Y         S0      
327NCSI_NIC0_RXD0   VIA   -    M      A01X+015820Y+059632X0300Y         S1      
327NCSI_NIC0_RXD0   R16   -1          A01X+015354Y+059559X0198Y0197R180 S1      
327NCSI_NIC0_RXD0   J20   -OB9        A01X+018127Y+060457X0140Y0480R270 S1      
317m4770            VIA   -    MD0080PA01X+018996Y+107520X0160Y    R270 S0      
327m4770            J31   -A26        A01X+014435Y+013303X0150Y0500R090 S1      
317m4770            VIA   -    MD0100PA01X+013075Y+013252X0200Y         S0      
327m4770            PEX0  -BJ13       A01X+018996Y+107520X0180Y         S1      
317m4771            J7    -D1   D0122PA01X+113185Y+160705X0282Y    R180 S3      
317m4771            VIA   -    MD0080PA01X+107047Y+118740X0160Y         S0      
327m4771            PEX2  -W4         A01X+107047Y+118740X0180Y         S1      
317m4772            VIA   -    MD0080PA01X+020118Y+110512X0160Y    R270 S0      
327m4772            PEX0  -BA16       A01X+020118Y+110512X0180Y         S1      
327m4772            C79   -1          A01X+017346Y+011472X0120Y0150R180 S1      
317m4772            VIA   -    MD0100PA01X+017837Y+011462X0200Y    R090 S0      
317m4773            VIA   -    MD0080PA01X+072933Y+123228X0160Y    R270 S0      
317m4773            VIA   -    MD0100PA01X+053832Y+134819X0180Y         S0      
327m4773            PEX1  -G35        A01X+072933Y+123228X0180Y         S1      
327m4773            C2251 -1          A01X+053822Y+135309X0120Y0150R090 S1      
317m4774            VIA   -    MD0080PA01X+110787Y+110138X0160Y    R270 S0      
327m4774            PEX2  -BB14       A01X+110787Y+110138X0180Y         S1      
327m4774            C498  -1          A01X+108763Y+012530X0120Y0150R180 S1      
317m4774            VIA   -    MD0100PA01X+109254Y+012540X0200Y    R090 S0      
327m4775            C575  -1          A01X+132815Y+140149X0120Y0150R090 S1      
317m4775            VIA   -    MD0100PA01X+132825Y+139658X0180Y         S0      
317m4775            VIA   -    MD0080PA01X+113031Y+122480X0160Y         S0      
327m4775            PEX2  -J20        A01X+113031Y+122480X0180Y         S1      
317m4776            VIA   -    MD0080PA01X+166968Y+111634X0160Y    R270 S0      
327m4776            PEX3  -AV42       A01X+166968Y+111634X0180Y         S1      
317m4776            VIA   -    MD0100PA01X+170266Y+051855X0200Y    R090 S0      
327m4776            C655  -1          A01X+169775Y+051845X0120Y0150R180 S1      
327m4777            C776  -1          A01X+152247Y+137729X0120Y0150R090 S1      
317m4777            VIA   -    MD0100PA01X+152257Y+137238X0180Y         S0      
317m4777            VIA   -    MD0080PA01X+156870Y+123228X0160Y    R270 S0      
327m4777            PEX3  -G15        A01X+156870Y+123228X0180Y         S1      
317m4778            VIA   -    MD0080PA01X+018996Y+109390X0160Y         S0      
327m4778            PEX0  -BD13       A01X+018996Y+109390X0180Y         S1      
327m4778            C74   -1          A01X+018386Y+013241X0120Y0150R180 S1      
317m4778            VIA   -    MD0100PA01X+018877Y+013251X0200Y    R090 S0      
317m4779            VIA   -    MD0080PA01X+070689Y+123228X0160Y    R270 S0      
317m4779            VIA   -    MD0100PA01X+055056Y+134819X0180Y         S0      
327m4779            PEX1  -G29        A01X+070689Y+123228X0180Y         S1      
327m4779            C2263 -1          A01X+055046Y+135309X0120Y0150R090 S1      
327m4780            C538  -1          A01X+128279Y+137729X0120Y0150R090 S1      
317m4780            VIA   -    MD0100PA01X+128269Y+137238X0180Y         S0      
317m4780            VIA   -    MD0080PA01X+116772Y+122854X0160Y    R270 S0      
327m4780            PEX2  -H30        A01X+116772Y+122854X0180Y         S1      
327m4781            C552  -1          A01X+123383Y+135309X0120Y0150R090 S1      
317m4781            VIA   -    MD0100PA01X+123373Y+134819X0180Y         S0      
317m4781            VIA   -    MD0080PA01X+108543Y+122854X0160Y         S0      
327m4781            PEX2  -H8         A01X+108543Y+122854X0180Y         S1      
317m4782            VIA   -    MD0080PA01X+167342Y+113504X0160Y    R270 S0      
327m4782            PEX3  -AN43       A01X+167342Y+113504X0180Y         S1      
317m4782            VIA   -    MD0100PA01X+169225Y+047071X0200Y    R090 S0      
327m4782            C664  -1          A01X+168735Y+047081X0120Y0150R180 S1      
317m4783            VIA   -    MD0080PA01X+152756Y+122480X0160Y         S0      
317m4783            VIA   -    MD0100PA01X+170932Y+139658X0180Y         S0      
327m4783            PEX3  -J4         A01X+152756Y+122480X0180Y         S1      
327m4783            C800  -1          A01X+170922Y+140149X0120Y0150R090 S1      
317m4784            VIA   -    MD0080PA01X+023110Y+110512X0160Y    R270 S0      
327m4784            PEX0  -BA24       A01X+023110Y+110512X0180Y         S1      
327m4784            C95   -1          A01X+037818Y+011472X0120Y0150R180 S1      
317m4784            VIA   -    MD0100PA01X+038309Y+011462X0200Y    R090 S0      
317m4785            VIA   -    MD0080PA01X+072933Y+123602X0160Y    R270 S0      
317m4785            VIA   -    MD0100PA01X+054172Y+134819X0180Y         S0      
327m4785            PEX1  -F35        A01X+072933Y+123602X0180Y         S1      
327m4785            C2252 -1          A01X+054182Y+135309X0120Y0150R090 S1      
317m4786            VIA   -    MD0080PA01X+111535Y+110512X0160Y    R270 S0      
327m4786            PEX2  -BA16       A01X+111535Y+110512X0180Y         S1      
327m4786            C501  -1          A01X+108763Y+011472X0120Y0150R180 S1      
317m4786            VIA   -    MD0100PA01X+109254Y+011462X0200Y    R090 S0      
327m4787            C581  -1          A01X+135263Y+140149X0120Y0150R090 S1      
317m4787            VIA   -    MD0100PA01X+135273Y+139658X0180Y         S0      
317m4787            VIA   -    MD0080PA01X+114154Y+123228X0160Y    R270 S0      
327m4787            PEX2  -G23        A01X+114154Y+123228X0180Y         S1      
317m4788            VIA   -    MD0080PA01X+169587Y+110138X0160Y    R270 S0      
327m4788            PEX3  -BB49       A01X+169587Y+110138X0180Y         S1      
327m4788            C651  -1          A01X+169775Y+053262X0120Y0150R180 S1      
317m4788            VIA   -    MD0100PA01X+170266Y+053272X0200Y    R090 S0      
327m4789            C789  -1          A01X+150159Y+140149X0120Y0150R090 S1      
317m4789            VIA   -    MD0100PA01X+150149Y+139658X0180Y         S0      
317m4789            VIA   -    MD0080PA01X+159114Y+123602X0160Y    R270 S0      
327m4789            PEX3  -F21        A01X+159114Y+123602X0180Y         S1      
327m4790            C110  -1          A01X+031856Y+137729X0120Y0150R090 S1      
317m4790            VIA   -    MD0100PA01X+031846Y+137238X0180Y         S0      
317m4790            VIA   -    MD0080PA01X+026476Y+123602X0160Y    R270 S0      
327m4790            PEX0  -F33        A01X+026476Y+123602X0180Y         S1      
317m4791            VIA   -    MD0080PA01X+065079Y+110138X0160Y    R270 S0      
327m4791            PEX1  -BB14       A01X+065079Y+110138X0180Y         S1      
327m4791            C287  -1          A01X+063055Y+012530X0120Y0150R180 S1      
317m4791            VIA   -    MD0100PA01X+063545Y+012540X0200Y    R090 S0      
327m4792            C545  -1          A01X+124247Y+140149X0120Y0150R090 S1      
317m4792            VIA   -    MD0100PA01X+124257Y+139658X0180Y         S0      
317m4792            VIA   -    MD0080PA01X+115276Y+122480X0160Y    R270 S0      
327m4792            PEX2  -J26        A01X+115276Y+122480X0180Y         S1      
327m4793            C595  -1          A01X+113165Y+137729X0120Y0150R090 S1      
317m4793            VIA   -    MD0100PA01X+113155Y+137238X0180Y         S0      
317m4793            VIA   -    MD0080PA01X+106299Y+122854X0160Y    R270 S0      
327m4793            PEX2  -H2         A01X+106299Y+122854X0180Y         S1      
317m4794            VIA   -    MD0080PA01X+162106Y+109764X0160Y         S0      
327m4794            PEX3  -BC29       A01X+162106Y+109764X0180Y         S1      
317m4794            VIA   -    MD0100PA01X+151995Y+041935X0200Y    R270 S0      
327m4794            C688  -1          A01X+152486Y+041925X0120Y0150     S1      
327m4795            C780  -1          A01X+147351Y+135309X0120Y0150R090 S1      
317m4795            VIA   -    MD0100PA01X+147361Y+134819X0180Y         S0      
317m4795            VIA   -    MD0080PA01X+157618Y+123228X0160Y    R270 S0      
327m4795            PEX3  -G17        A01X+157618Y+123228X0180Y         S1      
317m4796            VIA   -    MD0080PA01X+017874Y+110512X0160Y    R270 S0      
327m4796            PEX0  -BA10       A01X+017874Y+110512X0180Y         S1      
327m4796            C67   -1          A01X+007110Y+012890X0120Y0150R180 S1      
317m4796            VIA   -    MD0100PA01X+007600Y+012880X0200Y    R090 S0      
317m4797            VIA   -    MD0080PA01X+064331Y+110138X0160Y    R270 S0      
327m4797            PEX1  -BB12       A01X+064331Y+110138X0180Y         S1      
327m4797            C283  -1          A01X+052819Y+011112X0120Y0150R180 S1      
317m4797            VIA   -    MD0100PA01X+053309Y+011122X0200Y    R090 S0      
327m4798            C536  -1          A01X+129503Y+135309X0120Y0150R090 S1      
317m4798            VIA   -    MD0100PA01X+129493Y+134819X0180Y         S0      
317m4798            VIA   -    MD0080PA01X+117146Y+123602X0160Y    R270 S0      
327m4798            PEX2  -F31        A01X+117146Y+123602X0180Y         S1      
327m4799            C551  -1          A01X+123023Y+135309X0120Y0150R090 S1      
317m4799            VIA   -    MD0100PA01X+123033Y+134819X0180Y         S0      
317m4799            VIA   -    MD0080PA01X+108543Y+122480X0160Y         S0      
327m4799            PEX2  -J8         A01X+108543Y+122480X0180Y         S1      
317m4800            VIA   -    MD0080PA01X+168838Y+109390X0160Y    R270 S0      
327m4800            PEX3  -BD47       A01X+168838Y+109390X0180Y         S1      
317m4800            VIA   -    MD0100PA01X+170266Y+056859X0200Y    R090 S0      
327m4800            C647  -1          A01X+169775Y+056849X0120Y0150R180 S1      
327m4801            C820  -1          A01X+163578Y+135309X0120Y0150R090 S1      
317m4801            VIA   -    MD0100PA01X+163588Y+134819X0180Y         S0      
317m4801            VIA   -    MD0080PA01X+153878Y+119488X0160Y         S0      
327m4801            PEX3  -U7         A01X+153878Y+119488X0180Y         S1      
317m4802            VIA   -    MD0080PA01X+020492Y+109390X0160Y    R270 S0      
327m4802            PEX0  -BD17       A01X+020492Y+109390X0180Y         S1      
327m4802            C82   -1          A01X+028622Y+013241X0120Y0150R180 S1      
317m4802            VIA   -    MD0100PA01X+029113Y+013251X0200Y    R090 S0      
317m4803            VIA   -    MD0080PA01X+063583Y+110138X0160Y    R270 S0      
327m4803            PEX1  -BB10       A01X+063583Y+110138X0180Y         S1      
327m4803            C279  -1          A01X+052819Y+012530X0120Y0150R180 S1      
317m4803            VIA   -    MD0100PA01X+053309Y+012540X0200Y    R090 S0      
327m4804            C519  -1          A01X+135263Y+137729X0120Y0150R090 S1      
317m4804            VIA   -    MD0100PA01X+135273Y+137238X0180Y         S0      
317m4804            VIA   -    MD0080PA01X+120138Y+123228X0160Y    R270 S0      
327m4804            PEX2  -G39        A01X+120138Y+123228X0180Y         S1      
327m4805            C600  -1          A01X+111941Y+135309X0120Y0150R090 S1      
317m4805            VIA   -    MD0100PA01X+111931Y+134819X0180Y         S0      
317m4805            VIA   -    MD0080PA01X+108543Y+121358X0160Y         S0      
327m4805            PEX2  -M8         A01X+108543Y+121358X0180Y         S1      
317m4806            VIA   -    MD0080PA01X+160610Y+109764X0160Y    R270 S0      
327m4806            PEX3  -BC25       A01X+160610Y+109764X0180Y         S1      
317m4806            VIA   -    MD0100PA01X+151995Y+039100X0200Y    R270 S0      
327m4806            C696  -1          A01X+152486Y+039090X0120Y0150     S1      
327m4807            C794  -1          A01X+173370Y+140149X0120Y0150R090 S1      
317m4807            VIA   -    MD0100PA01X+173380Y+139658X0180Y         S0      
317m4807            VIA   -    MD0080PA01X+153878Y+123228X0160Y    R270 S0      
327m4807            PEX3  -G7         A01X+153878Y+123228X0180Y         S1      
317m4808            VIA   -    MD0080PA01X+020118Y+110138X0160Y    R270 S0      
327m4808            PEX0  -BB16       A01X+020118Y+110138X0180Y         S1      
327m4808            C80   -1          A01X+017346Y+011112X0120Y0150R180 S1      
317m4808            VIA   -    MD0100PA01X+017837Y+011122X0200Y    R090 S0      
317m4809            VIA   -    MD0080PA01X+068071Y+110138X0160Y    R270 S0      
327m4809            PEX1  -BB22       A01X+068071Y+110138X0180Y         S1      
327m4809            C303  -1          A01X+083527Y+012530X0120Y0150R180 S1      
317m4809            VIA   -    MD0100PA01X+084018Y+012540X0200Y    R090 S0      
317m4810            VIA   -    MD0080PA01X+112283Y+110138X0160Y    R270 S0      
327m4810            PEX2  -BB18       A01X+112283Y+110138X0180Y         S1      
327m4810            C506  -1          A01X+119000Y+012530X0120Y0150R180 S1      
317m4810            VIA   -    MD0100PA01X+119490Y+012540X0200Y    R090 S0      
327m4811            C612  -1          A01X+107045Y+135309X0120Y0150R090 S1      
317m4811            VIA   -    MD0100PA01X+107035Y+134819X0180Y         S0      
317m4811            VIA   -    MD0080PA01X+108543Y+119114X0160Y         S0      
327m4811            PEX2  -V8         A01X+108543Y+119114X0180Y         S1      
317m4812            VIA   -    MD0080PA01X+162854Y+109764X0160Y         S0      
317m4812            VIA   -    MD0100PA01X+151995Y+043352X0200Y    R270 S0      
327m4812            C684  -1          A01X+152486Y+043342X0120Y0150     S1      
327m4812            PEX3  -BC31       A01X+162854Y+109764X0180Y         S1      
327m4813            C817  -1          A01X+165162Y+137729X0120Y0150R090 S1      
317m4813            VIA   -    MD0100PA01X+165152Y+137238X0180Y         S0      
317m4813            VIA   -    MD0080PA01X+153504Y+120236X0160Y         S0      
327m4813            PEX3  -R6         A01X+153504Y+120236X0180Y         S1      
317m4814            VIA   -    MD0080PA01X+018622Y+110138X0160Y    R270 S0      
327m4814            PEX0  -BB12       A01X+018622Y+110138X0180Y         S1      
327m4814            C72   -1          A01X+007110Y+011112X0120Y0150R180 S1      
317m4814            VIA   -    MD0100PA01X+007600Y+011122X0200Y    R090 S0      
317m4815            VIA   -    MD0080PA01X+071063Y+122480X0160Y    R270 S0      
317m4815            VIA   -    MD0100PA01X+055056Y+139658X0180Y         S0      
327m4815            PEX1  -J30        A01X+071063Y+122480X0180Y         S1      
327m4815            C2261 -1          A01X+055046Y+140149X0120Y0150R090 S1      
327m4816            C550  -1          A01X+123383Y+137729X0120Y0150R090 S1      
317m4816            VIA   -    MD0100PA01X+123373Y+137238X0180Y         S0      
317m4816            VIA   -    MD0080PA01X+114528Y+122854X0160Y    R270 S0      
327m4816            PEX2  -H24        A01X+114528Y+122854X0180Y         S1      
327m4817            C604  -1          A01X+109493Y+140149X0120Y0150R090 S1      
317m4817            VIA   -    MD0100PA01X+109483Y+139658X0180Y         S0      
317m4817            VIA   -    MD0080PA01X+108543Y+120610X0160Y         S0      
327m4817            PEX2  -P8         A01X+108543Y+120610X0180Y         S1      
317m4818            VIA   -    MD0080PA01X+166594Y+111634X0160Y    R270 S0      
327m4818            PEX3  -AV41       A01X+166594Y+111634X0180Y         S1      
317m4818            VIA   -    MD0100PA01X+170266Y+052195X0200Y    R090 S0      
327m4818            C654  -1          A01X+169775Y+052205X0120Y0150R180 S1      
317m4819            VIA   -    MD0080PA01X+152382Y+123602X0160Y    R270 S0      
317m4819            VIA   -    MD0100PA01X+171272Y+134819X0180Y         S0      
327m4819            PEX3  -F3         A01X+152382Y+123602X0180Y         S1      
327m4819            C803  -1          A01X+171282Y+135309X0120Y0150R090 S1      
327m4820            C126  -1          A01X+025736Y+135309X0120Y0150R090 S1      
317m4820            VIA   -    MD0100PA01X+025726Y+134819X0180Y         S0      
317m4820            VIA   -    MD0080PA01X+023484Y+123602X0160Y    R270 S0      
327m4820            PEX0  -F25        A01X+023484Y+123602X0180Y         S1      
317m4821            VIA   -    MD0080PA01X+067323Y+110138X0160Y    R270 S0      
327m4821            PEX1  -BB20       A01X+067323Y+110138X0180Y         S1      
327m4821            C299  -1          A01X+073291Y+011112X0120Y0150R180 S1      
317m4821            VIA   -    MD0100PA01X+073782Y+011122X0200Y    R090 S0      
327m4822            C613  -1          A01X+105461Y+137729X0120Y0150R090 S1      
317m4822            VIA   -    MD0100PA01X+105471Y+137238X0180Y         S0      
317m4822            VIA   -    MD0080PA01X+108169Y+118740X0160Y         S0      
327m4822            PEX2  -W7         A01X+108169Y+118740X0180Y         S1      
317m4823            VIA   -    MD0080PA01X+165098Y+109764X0160Y    R270 S0      
317m4823            VIA   -    MD0100PA01X+150955Y+051352X0200Y    R270 S0      
327m4823            C672  -1          A01X+151446Y+051342X0120Y0150     S1      
327m4823            PEX3  -BC37       A01X+165098Y+109764X0180Y         S1      
327m4824            C786  -1          A01X+149799Y+135309X0120Y0150R090 S1      
317m4824            VIA   -    MD0100PA01X+149809Y+134819X0180Y         S0      
317m4824            VIA   -    MD0080PA01X+158740Y+122480X0160Y         S0      
327m4824            PEX3  -J20        A01X+158740Y+122480X0180Y         S1      
327m4825            C118  -1          A01X+028184Y+140149X0120Y0150R090 S1      
317m4825            VIA   -    MD0100PA01X+028174Y+139658X0180Y         S0      
317m4825            VIA   -    MD0080PA01X+024980Y+123602X0160Y    R270 S0      
327m4825            PEX0  -F29        A01X+024980Y+123602X0180Y         S1      
317m4826            VIA   -    MD0080PA01X+065827Y+110138X0160Y    R270 S0      
327m4826            PEX1  -BB16       A01X+065827Y+110138X0180Y         S1      
327m4826            C291  -1          A01X+063055Y+011112X0120Y0150R180 S1      
317m4826            VIA   -    MD0100PA01X+063545Y+011122X0200Y    R090 S0      
327m4827            C572  -1          A01X+131951Y+137729X0120Y0150R090 S1      
317m4827            VIA   -    MD0100PA01X+131941Y+137238X0180Y         S0      
317m4827            VIA   -    MD0080PA01X+112283Y+122854X0160Y         S0      
327m4827            PEX2  -H18        A01X+112283Y+122854X0180Y         S1      
317m4828            VIA   -    MD0080PA01X+165472Y+110138X0160Y    R270 S0      
327m4828            C671  -1          A01X+152486Y+052413X0120Y0150     S1      
317m4828            VIA   -    MD0100PA01X+151995Y+052403X0200Y    R270 S0      
327m4828            PEX3  -BB38       A01X+165472Y+110138X0180Y         S1      
317m4829            VIA   -    MD0100PA01X+168484Y+134819X0180Y         S0      
327m4829            C808  -1          A01X+168474Y+135309X0120Y0150R090 S1      
317m4829            VIA   -    MD0080PA01X+153878Y+121732X0160Y         S0      
327m4829            PEX3  -L7         A01X+153878Y+121732X0180Y         S1      
327m4830            C98   -1          A01X+036752Y+137729X0120Y0150R090 S1      
317m4830            VIA   -    MD0100PA01X+036742Y+137238X0180Y         S0      
317m4830            VIA   -    MD0080PA01X+028720Y+123602X0160Y    R270 S0      
327m4830            PEX0  -F39        A01X+028720Y+123602X0180Y         S1      
317m4831            VIA   -    MD0080PA01X+063957Y+109390X0160Y    R270 S0      
327m4831            PEX1  -BD11       A01X+063957Y+109390X0180Y         S1      
327m4831            C281  -1          A01X+053859Y+011824X0120Y0150R180 S1      
317m4831            VIA   -    MD0100PA01X+054349Y+011834X0200Y    R090 S0      
327m4832            C566  -1          A01X+129503Y+137729X0120Y0150R090 S1      
317m4832            VIA   -    MD0100PA01X+129493Y+137238X0180Y         S0      
317m4832            VIA   -    MD0080PA01X+111161Y+123602X0160Y    R270 S0      
327m4832            PEX2  -F15        A01X+111161Y+123602X0180Y         S1      
317m4833            VIA   -    MD0080PA01X+162480Y+110512X0160Y    R270 S0      
327m4833            PEX3  -BA30       A01X+162480Y+110512X0180Y         S1      
327m4833            C686  -1          A01X+151446Y+042636X0120Y0150     S1      
317m4833            VIA   -    MD0100PA01X+150955Y+042646X0200Y    R270 S0      
327m4834            C812  -1          A01X+166026Y+140149X0120Y0150R090 S1      
317m4834            VIA   -    MD0100PA01X+166036Y+139658X0180Y         S0      
317m4834            VIA   -    MD0080PA01X+153878Y+120984X0160Y         S0      
327m4834            PEX3  -N7         A01X+153878Y+120984X0180Y         S1      
327m4835            C100  -1          A01X+035528Y+140149X0120Y0150R090 S1      
317m4835            VIA   -    MD0100PA01X+035518Y+139658X0180Y         S0      
317m4835            VIA   -    MD0080PA01X+028346Y+122854X0160Y    R270 S0      
327m4835            PEX0  -H38        A01X+028346Y+122854X0180Y         S1      
317m4836            VIA   -    MD0080PA01X+068071Y+110512X0160Y    R270 S0      
327m4836            C302  -1          A01X+083527Y+012890X0120Y0150R180 S1      
317m4836            VIA   -    MD0100PA01X+084018Y+012880X0200Y    R090 S0      
327m4836            PEX1  -BA22       A01X+068071Y+110512X0180Y         S1      
327m4837            C589  -1          A01X+115253Y+137729X0120Y0150R090 S1      
317m4837            VIA   -    MD0100PA01X+115263Y+137238X0180Y         S0      
317m4837            VIA   -    MD0080PA01X+107047Y+122480X0160Y         S0      
327m4837            PEX2  -J4         A01X+107047Y+122480X0180Y         S1      
317m4838            VIA   -    MD0080PA01X+168090Y+109390X0160Y    R270 S0      
327m4838            PEX3  -BD45       A01X+168090Y+109390X0180Y         S1      
317m4838            VIA   -    MD0100PA01X+170266Y+058276X0200Y    R090 S0      
327m4838            C643  -1          A01X+169775Y+058266X0120Y0150R180 S1      
327m4839            C824  -1          A01X+161130Y+135309X0120Y0150R090 S1      
317m4839            VIA   -    MD0100PA01X+161140Y+134819X0180Y         S0      
317m4839            VIA   -    MD0080PA01X+153878Y+118740X0160Y         S0      
327m4839            PEX3  -W7         A01X+153878Y+118740X0180Y         S1      
327m4840            C115  -1          A01X+029048Y+137729X0120Y0150R090 S1      
317m4840            VIA   -    MD0100PA01X+029058Y+137238X0180Y         S0      
317m4840            VIA   -    MD0080PA01X+025354Y+122480X0160Y    R270 S0      
327m4840            PEX0  -J30        A01X+025354Y+122480X0180Y         S1      
317m4841            VIA   -    MD0100PA01X+051384Y+134819X0180Y         S0      
327m4841            C2257 -1          A01X+051374Y+135309X0120Y0150R090 S1      
317m4841            VIA   -    MD0080PA01X+071811Y+122480X0160Y    R270 S0      
327m4841            PEX1  -J32        A01X+071811Y+122480X0180Y         S1      
327m4842            C598  -1          A01X+111941Y+140149X0120Y0150R090 S1      
317m4842            VIA   -    MD0100PA01X+111931Y+139658X0180Y         S0      
317m4842            VIA   -    MD0080PA01X+107795Y+121732X0160Y         S0      
327m4842            PEX2  -L6         A01X+107795Y+121732X0180Y         S1      
317m4843            VIA   -    MD0080PA01X+166220Y+110138X0160Y    R270 S0      
327m4843            C667  -1          A01X+152486Y+053831X0120Y0150     S1      
317m4843            VIA   -    MD0100PA01X+151995Y+053821X0200Y    R270 S0      
327m4843            PEX3  -BB40       A01X+166220Y+110138X0180Y         S1      
327m4844            C804  -1          A01X+170058Y+137729X0120Y0150R090 S1      
317m4844            VIA   -    MD0100PA01X+170048Y+137238X0180Y         S0      
317m4844            VIA   -    MD0080PA01X+152008Y+123976X0160Y         S0      
327m4844            PEX3  -E2         A01X+152008Y+123976X0180Y         S1      
317m4845            VIA   -    MD0080PA01X+017874Y+110138X0160Y    R270 S0      
327m4845            PEX0  -BB10       A01X+017874Y+110138X0180Y         S1      
327m4845            C68   -1          A01X+007110Y+012530X0120Y0150R180 S1      
317m4845            VIA   -    MD0100PA01X+007600Y+012540X0200Y    R090 S0      
317m4846            VIA   -    MD0080PA01X+067697Y+109764X0160Y    R270 S0      
327m4846            PEX1  -BC21       A01X+067697Y+109764X0180Y         S1      
327m4846            C300  -1          A01X+084567Y+013601X0120Y0150R180 S1      
317m4846            VIA   -    MD0100PA01X+085058Y+013591X0200Y    R090 S0      
317m4847            VIA   -    MD0080PA01X+123130Y+109764X0160Y    R270 S0      
327m4847            PEX2  -BC47       A01X+123130Y+109764X0180Y         S1      
317m4847            VIA   -    MD0100PA01X+124557Y+057199X0200Y    R090 S0      
327m4847            C435  -1          A01X+124066Y+057209X0120Y0150R180 S1      
327m4848            C556  -1          A01X+125831Y+135309X0120Y0150R090 S1      
317m4848            VIA   -    MD0100PA01X+125821Y+134819X0180Y         S0      
317m4848            VIA   -    MD0080PA01X+109291Y+122854X0160Y         S0      
327m4848            PEX2  -H10        A01X+109291Y+122854X0180Y         S1      
317m4849            VIA   -    MD0080PA01X+167716Y+112756X0160Y    R270 S0      
327m4849            PEX3  -AR44       A01X+167716Y+112756X0180Y         S1      
317m4849            VIA   -    MD0100PA01X+169225Y+048148X0200Y    R090 S0      
327m4849            C661  -1          A01X+168735Y+048138X0120Y0150R180 S1      
317m4850            VIA   -    MD0080PA01X+153130Y+123602X0160Y    R270 S0      
317m4850            VIA   -    MD0100PA01X+172496Y+137238X0180Y         S0      
327m4850            PEX3  -F5         A01X+153130Y+123602X0180Y         S1      
327m4850            C799  -1          A01X+172506Y+137729X0120Y0150R090 S1      
317m4851            VIA   -    MD0080PA01X+017500Y+109764X0160Y    R270 S0      
327m4851            PEX0  -BC9        A01X+017500Y+109764X0180Y         S1      
327m4851            C65   -1          A01X+008150Y+013601X0120Y0150R180 S1      
317m4851            VIA   -    MD0100PA01X+008641Y+013591X0200Y    R090 S0      
317m4852            VIA   -    MD0080PA01X+068445Y+109764X0160Y    R270 S0      
327m4852            PEX1  -BC23       A01X+068445Y+109764X0180Y         S1      
327m4852            C304  -1          A01X+084567Y+012184X0120Y0150R180 S1      
317m4852            VIA   -    MD0100PA01X+085058Y+012174X0200Y    R090 S0      
317m4853            VIA   -    MD0080PA01X+116772Y+110138X0160Y    R270 S0      
327m4853            C476  -1          A01X+105737Y+042996X0120Y0150     S1      
317m4853            VIA   -    MD0100PA01X+105246Y+042986X0200Y    R270 S0      
327m4853            PEX2  -BB30       A01X+116772Y+110138X0180Y         S1      
327m4854            C576  -1          A01X+133175Y+140149X0120Y0150R090 S1      
317m4854            VIA   -    MD0100PA01X+133165Y+139658X0180Y         S0      
317m4854            VIA   -    MD0080PA01X+113031Y+122854X0160Y         S0      
327m4854            PEX2  -H20        A01X+113031Y+122854X0180Y         S1      
317m4855            VIA   -    MD0080PA01X+164350Y+109390X0160Y    R270 S0      
327m4855            PEX3  -BD35       A01X+164350Y+109390X0180Y         S1      
317m4855            VIA   -    MD0100PA01X+150955Y+048696X0200Y    R270 S0      
327m4855            C677  -1          A01X+151446Y+048706X0120Y0150     S1      
327m4856            C806  -1          A01X+168834Y+140149X0120Y0150R090 S1      
317m4856            VIA   -    MD0100PA01X+168824Y+139658X0180Y         S0      
317m4856            VIA   -    MD0080PA01X+152008Y+122854X0160Y    R270 S0      
327m4856            PEX3  -H2         A01X+152008Y+122854X0180Y         S1      
317m4857            VIA   -    MD0080PA01X+022736Y+109764X0160Y    R270 S0      
327m4857            PEX0  -BC23       A01X+022736Y+109764X0180Y         S1      
327m4857            C93   -1          A01X+038859Y+012184X0120Y0150R180 S1      
317m4857            VIA   -    MD0100PA01X+039349Y+012174X0200Y    R090 S0      
317m4858            VIA   -    MD0080PA01X+065827Y+110512X0160Y    R270 S0      
327m4858            PEX1  -BA16       A01X+065827Y+110512X0180Y         S1      
327m4858            C290  -1          A01X+063055Y+011472X0120Y0150R180 S1      
317m4858            VIA   -    MD0100PA01X+063545Y+011462X0200Y    R090 S0      
317m4859            VIA   -    MD0080PA01X+122008Y+112008X0160Y    R270 S0      
327m4859            PEX2  -AU44       A01X+122008Y+112008X0180Y         S1      
317m4859            VIA   -    MD0100PA01X+123517Y+051144X0200Y    R090 S0      
327m4859            C446  -1          A01X+123026Y+051134X0120Y0150R180 S1      
327m4860            C599  -1          A01X+111581Y+135309X0120Y0150R090 S1      
317m4860            VIA   -    MD0100PA01X+111591Y+134819X0180Y         S0      
317m4860            VIA   -    MD0080PA01X+108917Y+121358X0160Y         S0      
327m4860            PEX2  -M9         A01X+108917Y+121358X0180Y         S1      
317m4861            VIA   -    MD0080PA01X+160984Y+110512X0160Y    R270 S0      
327m4861            PEX3  -BA26       A01X+160984Y+110512X0180Y         S1      
327m4861            C694  -1          A01X+151686Y+039801X0120Y0150     S1      
317m4861            VIA   -    MD0100PA01X+151195Y+039811X0200Y    R270 S0      
327m4862            C787  -1          A01X+150159Y+135309X0120Y0150R090 S1      
317m4862            VIA   -    MD0100PA01X+150149Y+134819X0180Y         S0      
317m4862            VIA   -    MD0080PA01X+158740Y+122854X0160Y         S0      
327m4862            PEX3  -H20        A01X+158740Y+122854X0180Y         S1      
317m4863            VIA   -    MD0080PA01X+021988Y+109390X0160Y    R270 S0      
327m4863            PEX0  -BD21       A01X+021988Y+109390X0180Y         S1      
327m4863            C90   -1          A01X+038859Y+013241X0120Y0150R180 S1      
317m4863            VIA   -    MD0100PA01X+039349Y+013251X0200Y    R090 S0      
317m4864            VIA   -    MD0080PA01X+074055Y+122854X0160Y    R270 S0      
317m4864            VIA   -    MD0100PA01X+056620Y+134819X0180Y         S0      
327m4864            PEX1  -H38        A01X+074055Y+122854X0180Y         S1      
327m4864            C2246 -1          A01X+056630Y+135309X0120Y0150R090 S1      
317m4865            VIA   -    MD0080PA01X+122382Y+109764X0160Y    R270 S0      
317m4865            VIA   -    MD0100PA01X+124557Y+058616X0200Y    R090 S0      
327m4865            C431  -1          A01X+124066Y+058626X0120Y0150R180 S1      
327m4865            PEX2  -BC45       A01X+122382Y+109764X0180Y         S1      
327m4866            C586  -1          A01X+116837Y+140149X0120Y0150R090 S1      
317m4866            VIA   -    MD0100PA01X+116827Y+139658X0180Y         S0      
317m4866            VIA   -    MD0080PA01X+107795Y+122854X0160Y         S0      
327m4866            PEX2  -H6         A01X+107795Y+122854X0180Y         S1      
317m4867            VIA   -    MD0080PA01X+164350Y+109764X0160Y    R270 S0      
327m4867            PEX3  -BC35       A01X+164350Y+109764X0180Y         S1      
317m4867            VIA   -    MD0100PA01X+150955Y+048356X0200Y    R270 S0      
327m4867            C676  -1          A01X+151446Y+048346X0120Y0150     S1      
327m4868            C775  -1          A01X+151383Y+140149X0120Y0150R090 S1      
317m4868            VIA   -    MD0100PA01X+151373Y+139658X0180Y         S0      
317m4868            VIA   -    MD0080PA01X+156496Y+122854X0160Y         S0      
327m4868            PEX3  -H14        A01X+156496Y+122854X0180Y         S1      
317m4869            VIA   -    MD0080PA01X+019370Y+110138X0160Y    R270 S0      
327m4869            PEX0  -BB14       A01X+019370Y+110138X0180Y         S1      
327m4869            C76   -1          A01X+017346Y+012530X0120Y0150R180 S1      
317m4869            VIA   -    MD0100PA01X+017837Y+012540X0200Y    R090 S0      
317m4870            VIA   -    MD0080PA01X+074055Y+122480X0160Y    R270 S0      
317m4870            VIA   -    MD0100PA01X+056280Y+134819X0180Y         S0      
327m4870            PEX1  -J38        A01X+074055Y+122480X0180Y         S1      
327m4870            C2245 -1          A01X+056270Y+135309X0120Y0150R090 S1      
317m4871            VIA   -    MD0080PA01X+122008Y+112756X0160Y    R270 S0      
327m4871            PEX2  -AR44       A01X+122008Y+112756X0180Y         S1      
317m4871            VIA   -    MD0100PA01X+123517Y+048148X0200Y    R090 S0      
327m4871            C450  -1          A01X+123026Y+048138X0120Y0150R180 S1      
327m4872            C597  -1          A01X+111581Y+140149X0120Y0150R090 S1      
317m4872            VIA   -    MD0100PA01X+111591Y+139658X0180Y         S0      
317m4872            VIA   -    MD0080PA01X+108169Y+121732X0160Y         S0      
327m4872            PEX2  -L7         A01X+108169Y+121732X0180Y         S1      
317m4873            VIA   -    MD0080PA01X+168464Y+110512X0160Y    R090 S0      
327m4873            PEX3  -BA46       A01X+168464Y+110512X0180Y         S1      
317m4873            VIA   -    MD0100PA01X+169225Y+057905X0200Y    R090 S0      
327m4873            C644  -1          A01X+168735Y+057915X0120Y0150R180 S1      
327m4874            C792  -1          A01X+152247Y+135309X0120Y0150R090 S1      
317m4874            VIA   -    MD0100PA01X+152257Y+134819X0180Y         S0      
317m4874            VIA   -    MD0080PA01X+159862Y+123228X0160Y    R270 S0      
327m4874            PEX3  -G23        A01X+159862Y+123228X0180Y         S1      
317m4875            J3    -O1   D0122PA01X+010988Y+150980X0282Y    R180 S3      
317m4875            VIA   -    MD0080PA01X+015256Y+121732X0160Y         S0      
327m4875            PEX0  -L3         A01X+015256Y+121732X0180Y         S1      
317m4876            VIA   -    MD0100PA01X+053832Y+136010X0180Y         S0      
317m4876            J12   -R4   D0122PA01X+048232Y+149366X0282Y    R180 S3      
327m4876            C2251 -2          A01X+053822Y+135519X0120Y0150R090 S1      
317m4877            VIA   -    MD0080PA01X+018248Y+109764X0160Y    R270 S0      
327m4877            PEX0  -BC11       A01X+018248Y+109764X0180Y         S1      
327m4877            C69   -1          A01X+008150Y+012184X0120Y0150R180 S1      
317m4877            VIA   -    MD0100PA01X+008641Y+012174X0200Y    R090 S0      
317m4878            VIA   -    MD0080PA01X+064705Y+109764X0160Y    R270 S0      
327m4878            PEX1  -BC13       A01X+064705Y+109764X0180Y         S1      
327m4878            C284  -1          A01X+064095Y+013601X0120Y0150R180 S1      
317m4878            VIA   -    MD0100PA01X+064586Y+013591X0200Y    R090 S0      
317m4879            VIA   -    MD0080PA01X+118642Y+109764X0160Y    R270 S0      
327m4879            PEX2  -BC35       A01X+118642Y+109764X0180Y         S1      
317m4879            VIA   -    MD0100PA01X+105246Y+048356X0200Y    R270 S0      
327m4879            C465  -1          A01X+105737Y+048346X0120Y0150     S1      
327m4880            C609  -1          A01X+106685Y+140149X0120Y0150R090 S1      
317m4880            VIA   -    MD0100PA01X+106695Y+139658X0180Y         S0      
317m4880            VIA   -    MD0080PA01X+108169Y+119488X0160Y         S0      
327m4880            PEX2  -U7         A01X+108169Y+119488X0180Y         S1      
317m4881            VIA   -    MD0080PA01X+162480Y+110138X0160Y    R270 S0      
327m4881            C687  -1          A01X+151446Y+042996X0120Y0150     S1      
317m4881            VIA   -    MD0100PA01X+150955Y+042986X0200Y    R270 S0      
327m4881            PEX3  -BB30       A01X+162480Y+110138X0180Y         S1      
317m4882            VIA   -    MD0080PA01X+152382Y+123228X0160Y    R270 S0      
317m4882            VIA   -    MD0100PA01X+170932Y+134819X0180Y         S0      
327m4882            PEX3  -G3         A01X+152382Y+123228X0180Y         S1      
327m4882            C802  -1          A01X+170922Y+135309X0120Y0150R090 S1      
327m4883            C108  -1          A01X+033080Y+135309X0120Y0150R090 S1      
317m4883            VIA   -    MD0100PA01X+033070Y+134819X0180Y         S0      
317m4883            VIA   -    MD0080PA01X+026850Y+122854X0160Y    R270 S0      
327m4883            PEX0  -H34        A01X+026850Y+122854X0180Y         S1      
317m4884            VIA   -    MD0080PA01X+073681Y+123602X0160Y    R270 S0      
317m4884            VIA   -    MD0100PA01X+055396Y+137238X0180Y         S0      
327m4884            C2248 -1          A01X+055406Y+137729X0120Y0150R090 S1      
327m4884            PEX1  -F37        A01X+073681Y+123602X0180Y         S1      
317m4885            VIA   -    MD0080PA01X+122008Y+111260X0160Y    R270 S0      
327m4885            PEX2  -AW44       A01X+122008Y+111260X0180Y         S1      
317m4885            VIA   -    MD0100PA01X+123517Y+052561X0200Y    R090 S0      
327m4885            C442  -1          A01X+123026Y+052551X0120Y0150R180 S1      
327m4886            C557  -1          A01X+125471Y+140149X0120Y0150R090 S1      
317m4886            VIA   -    MD0100PA01X+125481Y+139658X0180Y    R180 S0      
317m4886            VIA   -    MD0080PA01X+109665Y+123228X0160Y    R270 S0      
327m4886            PEX2  -G11        A01X+109665Y+123228X0180Y         S1      
317m4887            VIA   -    MD0080PA01X+161358Y+109764X0160Y    R270 S0      
327m4887            PEX3  -BC27       A01X+161358Y+109764X0180Y         S1      
317m4887            VIA   -    MD0100PA01X+151995Y+040517X0200Y    R270 S0      
327m4887            C692  -1          A01X+152486Y+040507X0120Y0150     S1      
327m4888            C782  -1          A01X+147351Y+140149X0120Y0150R090 S1      
317m4888            VIA   -    MD0100PA01X+147361Y+139658X0180Y         S0      
317m4888            VIA   -    MD0080PA01X+157992Y+122480X0160Y         S0      
327m4888            PEX3  -J18        A01X+157992Y+122480X0180Y         S1      
317m4889            VIA   -    MD0100PA01X+071197Y+136010X0180Y         S0      
317m4889            J5    -U2   D0122PA01X+063823Y+147831X0282Y    R180 S3      
327m4889            C385  -2          A01X+071187Y+135519X0120Y0150R090 S1      
327m4890            C112  -1          A01X+030632Y+140149X0120Y0150R090 S1      
317m4890            VIA   -    MD0100PA01X+030622Y+139658X0180Y         S0      
317m4890            VIA   -    MD0080PA01X+026102Y+122854X0160Y    R270 S0      
327m4890            PEX0  -H32        A01X+026102Y+122854X0180Y         S1      
317m4891            VIA   -    MD0080PA01X+069567Y+122480X0160Y    R270 S0      
317m4891            VIA   -    MD0100PA01X+052608Y+134819X0180Y         S0      
327m4891            PEX1  -J26        A01X+069567Y+122480X0180Y         S1      
327m4891            C2269 -1          A01X+052598Y+135309X0120Y0150R090 S1      
317m4892            VIA   -    MD0080PA01X+119016Y+110512X0160Y    R270 S0      
327m4892            C463  -1          A01X+106777Y+049057X0120Y0150     S1      
317m4892            VIA   -    MD0100PA01X+106286Y+049067X0200Y    R270 S0      
327m4892            PEX2  -BA36       A01X+119016Y+110512X0180Y         S1      
327m4893            C579  -1          A01X+135263Y+135309X0120Y0150R090 S1      
317m4893            VIA   -    MD0100PA01X+135273Y+134819X0180Y         S0      
317m4893            VIA   -    MD0080PA01X+113780Y+122480X0160Y         S0      
327m4893            PEX2  -J22        A01X+113780Y+122480X0180Y         S1      
317m4894            VIA   -    MD0080PA01X+164724Y+110512X0160Y    R270 S0      
327m4894            C674  -1          A01X+152486Y+049057X0120Y0150     S1      
317m4894            VIA   -    MD0100PA01X+151995Y+049067X0200Y    R270 S0      
327m4894            PEX3  -BA36       A01X+164724Y+110512X0180Y         S1      
327m4895            C770  -1          A01X+149799Y+137729X0120Y0150R090 S1      
317m4895            VIA   -    MD0100PA01X+149809Y+137238X0180Y         S0      
317m4895            VIA   -    MD0080PA01X+155748Y+122480X0160Y         S0      
327m4895            PEX3  -J12        A01X+155748Y+122480X0180Y         S1      
317m4896            VIA   -    MD0080PA01X+021614Y+110512X0160Y    R270 S0      
327m4896            PEX0  -BA20       A01X+021614Y+110512X0180Y         S1      
327m4896            C87   -1          A01X+027582Y+011472X0120Y0150R180 S1      
317m4896            VIA   -    MD0100PA01X+028073Y+011462X0200Y    R090 S0      
317m4897            VIA   -    MD0080PA01X+074429Y+123228X0160Y    R270 S0      
317m4897            VIA   -    MD0100PA01X+056280Y+139658X0180Y         S0      
327m4897            PEX1  -G39        A01X+074429Y+123228X0180Y         S1      
327m4897            C2243 -1          A01X+056270Y+140149X0120Y0150R090 S1      
317m4898            VIA   -    MD0080PA01X+116398Y+109764X0160Y         S0      
327m4898            PEX2  -BC29       A01X+116398Y+109764X0180Y         S1      
317m4898            VIA   -    MD0100PA01X+106286Y+041935X0200Y    R270 S0      
327m4898            C477  -1          A01X+106777Y+041925X0120Y0150     S1      
327m4899            C587  -1          A01X+116477Y+135309X0120Y0150R090 S1      
317m4899            VIA   -    MD0100PA01X+116487Y+134819X0180Y         S0      
317m4899            VIA   -    MD0080PA01X+107421Y+123228X0160Y    R270 S0      
327m4899            PEX2  -G5         A01X+107421Y+123228X0180Y         S1      
317m4900            VIA   -    MD0080PA01X+165098Y+109390X0160Y    R270 S0      
317m4900            VIA   -    MD0100PA01X+150955Y+051692X0200Y    R270 S0      
327m4900            C673  -1          A01X+151446Y+051702X0120Y0150     S1      
327m4900            PEX3  -BD37       A01X+165098Y+109390X0180Y         S1      
317m4901            VIA   -    MD0080PA01X+154252Y+122480X0160Y         S0      
317m4901            VIA   -    MD0100PA01X+146137Y+134819X0180Y         S0      
327m4901            PEX3  -J8         A01X+154252Y+122480X0180Y         S1      
327m4901            C762  -1          A01X+146127Y+135309X0120Y0150R090 S1      
317m4902            VIA   -    MD0100PA01X+052608Y+138430X0180Y         S0      
317m4902            J12   -S3   D0122PA01X+047366Y+148933X0282Y    R180 S3      
327m4902            C2253 -2          A01X+052598Y+137939X0120Y0150R090 S1      
317m4903            VIA   -    MD0080PA01X+021240Y+109390X0160Y    R270 S0      
327m4903            PEX0  -BD19       A01X+021240Y+109390X0180Y         S1      
327m4903            C86   -1          A01X+028622Y+011824X0120Y0150R180 S1      
317m4903            VIA   -    MD0100PA01X+029113Y+011834X0200Y    R090 S0      
317m4904            VIA   -    MD0080PA01X+066575Y+110138X0160Y    R270 S0      
327m4904            PEX1  -BB18       A01X+066575Y+110138X0180Y         S1      
327m4904            C295  -1          A01X+073291Y+012530X0120Y0150R180 S1      
317m4904            VIA   -    MD0100PA01X+073782Y+012540X0200Y    R090 S0      
317m4905            VIA   -    MD0080PA01X+122008Y+113504X0160Y    R270 S0      
327m4905            PEX2  -AN44       A01X+122008Y+113504X0180Y         S1      
317m4905            VIA   -    MD0100PA01X+123517Y+046731X0200Y    R090 S0      
327m4905            C454  -1          A01X+123026Y+046721X0120Y0150R180 S1      
327m4906            C564  -1          A01X+128279Y+140149X0120Y0150R090 S1      
317m4906            VIA   -    MD0100PA01X+128269Y+139658X0180Y         S0      
317m4906            VIA   -    MD0080PA01X+110787Y+122854X0160Y         S0      
327m4906            PEX2  -H14        A01X+110787Y+122854X0180Y         S1      
317m4907            VIA   -    MD0080PA01X+166968Y+112382X0160Y    R270 S0      
327m4907            PEX3  -AT42       A01X+166968Y+112382X0180Y         S1      
317m4907            VIA   -    MD0100PA01X+170266Y+048859X0200Y    R090 S0      
327m4907            C659  -1          A01X+169775Y+048849X0120Y0150R180 S1      
327m4908            C814  -1          A01X+166026Y+135309X0120Y0150R090 S1      
317m4908            VIA   -    MD0100PA01X+166036Y+134819X0180Y         S0      
317m4908            VIA   -    MD0080PA01X+154626Y+120610X0160Y         S0      
327m4908            PEX3  -P9         A01X+154626Y+120610X0180Y         S1      
317m4909            VIA   -    MD0100PA01X+051384Y+140850X0180Y         S0      
317m4909            J12   -R2   D0122PA01X+046500Y+149366X0282Y    R180 S3      
327m4909            C2255 -2          A01X+051374Y+140359X0120Y0150R090 S1      
317m4910            VIA   -    MD0080PA01X+020866Y+110512X0160Y    R270 S0      
327m4910            C83   -1          A01X+027582Y+012890X0120Y0150R180 S1      
317m4910            VIA   -    MD0100PA01X+028073Y+012880X0200Y    R090 S0      
327m4910            PEX0  -BA18       A01X+020866Y+110512X0180Y         S1      
317m4911            VIA   -    MD0080PA01X+064331Y+110512X0160Y    R270 S0      
327m4911            PEX1  -BA12       A01X+064331Y+110512X0180Y         S1      
327m4911            C282  -1          A01X+052819Y+011472X0120Y0150R180 S1      
317m4911            VIA   -    MD0100PA01X+053309Y+011462X0200Y    R090 S0      
317m4912            VIA   -    MD0080PA01X+120886Y+109764X0160Y    R270 S0      
327m4912            PEX2  -BC41       A01X+120886Y+109764X0180Y         S1      
317m4912            VIA   -    MD0100PA01X+124557Y+061451X0200Y    R090 S0      
327m4912            C423  -1          A01X+124066Y+061461X0120Y0150R180 S1      
327m4913            C574  -1          A01X+133175Y+135309X0120Y0150R090 S1      
317m4913            VIA   -    MD0100PA01X+133165Y+134819X0180Y         S0      
317m4913            VIA   -    MD0080PA01X+112657Y+123602X0160Y    R270 S0      
327m4913            PEX2  -F19        A01X+112657Y+123602X0180Y         S1      
317m4914            VIA   -    MD0080PA01X+167342Y+112756X0160Y    R270 S0      
327m4914            PEX3  -AR43       A01X+167342Y+112756X0180Y         S1      
317m4914            VIA   -    MD0100PA01X+169225Y+048488X0200Y    R090 S0      
327m4914            C660  -1          A01X+168735Y+048498X0120Y0150R180 S1      
317m4915            VIA   -    MD0100PA01X+168824Y+134819X0180Y         S0      
327m4915            C809  -1          A01X+168834Y+135309X0120Y0150R090 S1      
317m4915            VIA   -    MD0080PA01X+153504Y+121732X0160Y         S0      
327m4915            PEX3  -L6         A01X+153504Y+121732X0180Y         S1      
317m4916            VIA   -    MD0100PA01X+069973Y+138430X0180Y         S0      
317m4916            J5    -V1   D0122PA01X+062957Y+147398X0282Y    R180 S3      
327m4916            C386  -2          A01X+069963Y+137939X0120Y0150R090 S1      
317m4917            VIA   -    MD0080PA01X+066949Y+109764X0160Y    R270 S0      
327m4917            PEX1  -BC19       A01X+066949Y+109764X0180Y         S1      
327m4917            C296  -1          A01X+074331Y+012184X0120Y0150R180 S1      
317m4917            VIA   -    MD0100PA01X+074822Y+012174X0200Y    R090 S0      
317m4918            VIA   -    MD0080PA01X+123878Y+109016X0160Y    R270 S0      
327m4918            PEX2  -BE49       A01X+123878Y+109016X0180Y         S1      
317m4918            VIA   -    MD0100PA01X+123517Y+056148X0200Y    R090 S0      
327m4918            C438  -1          A01X+123026Y+056138X0120Y0150R180 S1      
327m4919            C585  -1          A01X+116477Y+140149X0120Y0150R090 S1      
317m4919            VIA   -    MD0100PA01X+116487Y+139658X0180Y         S0      
317m4919            VIA   -    MD0080PA01X+107795Y+122480X0160Y         S0      
327m4919            PEX2  -J6         A01X+107795Y+122480X0180Y         S1      
317m4920            VIA   -    MD0080PA01X+169213Y+109016X0160Y    R270 S0      
327m4920            PEX3  -BE48       A01X+169213Y+109016X0180Y         S1      
317m4920            VIA   -    MD0100PA01X+169225Y+056488X0200Y    R090 S0      
327m4920            C648  -1          A01X+168735Y+056498X0120Y0150R180 S1      
327m4921            C822  -1          A01X+162354Y+137729X0120Y0150R090 S1      
317m4921            VIA   -    MD0100PA01X+162364Y+137238X0180Y         S0      
317m4921            VIA   -    MD0080PA01X+154626Y+119114X0160Y         S0      
327m4921            PEX3  -V9         A01X+154626Y+119114X0180Y         S1      
317m4922            VIA   -    MD0080PA01X+072559Y+122480X0160Y    R270 S0      
317m4922            VIA   -    MD0100PA01X+052608Y+137238X0180Y         S0      
327m4922            C2253 -1          A01X+052598Y+137729X0120Y0150R090 S1      
327m4922            PEX1  -J34        A01X+072559Y+122480X0180Y         S1      
327m4923            C457  -1          A01X+105737Y+052759X0120Y0150     S1      
317m4923            VIA   -    MD0100PA01X+105246Y+052769X0200Y    R270 S0      
317m4923            VIA   -    MD0080PA01X+120138Y+109764X0160Y    R270 S0      
327m4923            PEX2  -BC39       A01X+120138Y+109764X0180Y         S1      
327m4924            C608  -1          A01X+108269Y+137729X0120Y0150R090 S1      
317m4924            VIA   -    MD0100PA01X+108259Y+137238X0180Y         S0      
317m4924            VIA   -    MD0080PA01X+108543Y+119862X0160Y         S0      
327m4924            PEX2  -T8         A01X+108543Y+119862X0180Y         S1      
317m4925            VIA   -    MD0080PA01X+163602Y+109764X0160Y    R270 S0      
317m4925            VIA   -    MD0100PA01X+150955Y+046939X0200Y    R270 S0      
327m4925            C680  -1          A01X+151446Y+046929X0120Y0150     S1      
327m4925            PEX3  -BC33       A01X+163602Y+109764X0180Y         S1      
327m4926            C818  -1          A01X+163578Y+140149X0120Y0150R090 S1      
317m4926            VIA   -    MD0100PA01X+163588Y+139658X0180Y    R180 S0      
317m4926            VIA   -    MD0080PA01X+154626Y+119862X0160Y         S0      
327m4926            PEX3  -T9         A01X+154626Y+119862X0180Y         S1      
317m4927            VIA   -    MD0100PA01X+073645Y+140840X0180Y         S0      
317m4927            J5    -U6   D0122PA01X+067287Y+147831X0282Y    R180 S3      
327m4927            C376  -2          A01X+073635Y+140350X0120Y0150R090 S1      
317m4928            VIA   -    MD0080PA01X+066201Y+109390X0160Y    R270 S0      
327m4928            PEX1  -BD17       A01X+066201Y+109390X0180Y         S1      
327m4928            C293  -1          A01X+074331Y+013241X0120Y0150R180 S1      
317m4928            VIA   -    MD0100PA01X+074822Y+013251X0200Y    R090 S0      
317m4929            VIA   -    MD0080PA01X+122382Y+109390X0160Y    R270 S0      
327m4929            PEX2  -BD45       A01X+122382Y+109390X0180Y         S1      
317m4929            VIA   -    MD0100PA01X+124557Y+058276X0200Y    R090 S0      
327m4929            C432  -1          A01X+124066Y+058266X0120Y0150R180 S1      
327m4930            C588  -1          A01X+116837Y+135309X0120Y0150R090 S1      
317m4930            VIA   -    MD0100PA01X+116827Y+134819X0180Y         S0      
317m4930            VIA   -    MD0080PA01X+107421Y+123602X0160Y    R270 S0      
327m4930            PEX2  -F5         A01X+107421Y+123602X0180Y         S1      
317m4931            VIA   -    MD0080PA01X+161358Y+109390X0160Y    R270 S0      
317m4931            VIA   -    MD0100PA01X+151995Y+040857X0200Y    R270 S0      
327m4931            C693  -1          A01X+152486Y+040867X0120Y0150     S1      
327m4931            PEX3  -BD27       A01X+161358Y+109390X0180Y         S1      
327m4932            C772  -1          A01X+151023Y+135309X0120Y0150R090 S1      
317m4932            VIA   -    MD0100PA01X+151033Y+134819X0180Y         S0      
317m4932            VIA   -    MD0080PA01X+156122Y+123228X0160Y    R270 S0      
327m4932            PEX3  -G13        A01X+156122Y+123228X0180Y         S1      
317m4933            VIA   -    MD0100PA01X+014071Y+136010X0180Y         S0      
317m4933            J3    -H8   D0122PA01X+017051Y+158579X0282Y    R180 S3      
327m4933            C178  -2          A01X+014081Y+135519X0120Y0150R090 S1      
317m4934            VIA   -    MD0100PA01X+071197Y+140850X0180Y         S0      
317m4934            J5    -V3   D0122PA01X+064689Y+147398X0282Y    R180 S3      
327m4934            C383  -2          A01X+071187Y+140359X0120Y0150R090 S1      
317m4935            VIA   -    MD0080PA01X+068819Y+110138X0160Y    R270 S0      
327m4935            PEX1  -BB24       A01X+068819Y+110138X0180Y         S1      
327m4935            C307  -1          A01X+083527Y+011112X0120Y0150R180 S1      
317m4935            VIA   -    MD0100PA01X+084018Y+011122X0200Y    R090 S0      
317m4936            VIA   -    MD0080PA01X+117520Y+110138X0160Y    R270 S0      
327m4936            PEX2  -BB32       A01X+117520Y+110138X0180Y         S1      
327m4936            C472  -1          A01X+105737Y+044413X0120Y0150     S1      
317m4936            VIA   -    MD0100PA01X+105246Y+044403X0200Y    R270 S0      
327m4937            C567  -1          A01X+130367Y+135309X0120Y0150R090 S1      
317m4937            VIA   -    MD0100PA01X+130377Y+134819X0180Y         S0      
317m4937            VIA   -    MD0080PA01X+111535Y+122480X0160Y         S0      
327m4937            PEX2  -J16        A01X+111535Y+122480X0180Y         S1      
317m4938            VIA   -    MD0080PA01X+167342Y+112008X0160Y    R270 S0      
317m4938            VIA   -    MD0100PA01X+169225Y+051484X0200Y    R090 S0      
327m4938            C656  -1          A01X+168735Y+051494X0120Y0150R180 S1      
327m4938            PEX3  -AU43       A01X+167342Y+112008X0180Y         S1      
317m4939            VIA   -    MD0080PA01X+157244Y+122480X0160Y         S0      
317m4939            VIA   -    MD0100PA01X+146137Y+137238X0180Y         S0      
327m4939            PEX3  -J16        A01X+157244Y+122480X0180Y         S1      
327m4939            C778  -1          A01X+146127Y+137729X0120Y0150R090 S1      
317m4940            VIA   -    MD0080PA01X+070315Y+122480X0160Y    R270 S0      
317m4940            VIA   -    MD0100PA01X+053832Y+137238X0180Y         S0      
327m4940            PEX1  -J28        A01X+070315Y+122480X0180Y         S1      
327m4940            C2265 -1          A01X+053822Y+137729X0120Y0150R090 S1      
317m4941            VIA   -    MD0080PA01X+119390Y+109390X0160Y    R270 S0      
317m4941            VIA   -    MD0100PA01X+105246Y+051692X0200Y    R270 S0      
327m4941            C462  -1          A01X+105737Y+051702X0120Y0150     S1      
327m4941            PEX2  -BD37       A01X+119390Y+109390X0180Y         S1      
327m4942            C601  -1          A01X+110357Y+137729X0120Y0150R090 S1      
317m4942            VIA   -    MD0100PA01X+110367Y+137238X0180Y         S0      
317m4942            VIA   -    MD0080PA01X+108169Y+120984X0160Y         S0      
327m4942            PEX2  -N7         A01X+108169Y+120984X0180Y         S1      
317m4943            VIA   -    MD0080PA01X+166594Y+109764X0160Y    R270 S0      
327m4943            PEX3  -BC41       A01X+166594Y+109764X0180Y         S1      
317m4943            VIA   -    MD0100PA01X+170266Y+061451X0200Y    R090 S0      
327m4943            C634  -1          A01X+169775Y+061461X0120Y0150R180 S1      
317m4944            J7    -N8   D0122PA01X+119248Y+151413X0282Y    R180 S3      
317m4944            VIA   -    MD0080PA01X+108169Y+125472X0160Y         S0      
327m4944            PEX2  -A7         A01X+108169Y+125472X0180Y         S1      
317m4945            VIA   -    MD0100PA01X+051724Y+140850X0180Y         S0      
317m4945            J12   -Q2   D0122PA01X+046500Y+149878X0282Y    R180 S3      
327m4945            C2256 -2          A01X+051734Y+140359X0120Y0150R090 S1      
317m4946            VIA   -    MD0080PA01X+071437Y+123228X0160Y    R270 S0      
317m4946            VIA   -    MD0100PA01X+056280Y+137238X0180Y         S0      
327m4946            PEX1  -G31        A01X+071437Y+123228X0180Y         S1      
327m4946            C2259 -1          A01X+056270Y+137729X0120Y0150R090 S1      
317m4947            VIA   -    MD0080PA01X+115276Y+110512X0160Y    R270 S0      
327m4947            PEX2  -BA26       A01X+115276Y+110512X0180Y         S1      
327m4947            C483  -1          A01X+105977Y+039801X0120Y0150     S1      
317m4947            VIA   -    MD0100PA01X+105486Y+039811X0200Y    R270 S0      
327m4948            C570  -1          A01X+130727Y+140149X0120Y0150R090 S1      
317m4948            VIA   -    MD0100PA01X+130717Y+139658X0180Y         S0      
317m4948            VIA   -    MD0080PA01X+111909Y+123602X0160Y    R270 S0      
327m4948            PEX2  -F17        A01X+111909Y+123602X0180Y         S1      
317m4949            VIA   -    MD0080PA01X+168838Y+109764X0160Y    R270 S0      
327m4949            PEX3  -BC47       A01X+168838Y+109764X0180Y         S1      
317m4949            VIA   -    MD0100PA01X+170266Y+057199X0200Y    R090 S0      
327m4949            C646  -1          A01X+169775Y+057209X0120Y0150R180 S1      
317m4950            J7    -O4   D0122PA01X+115783Y+150902X0282Y    R180 S3      
317m4950            VIA   -    MD0080PA01X+106673Y+125098X0160Y         S0      
327m4950            PEX2  -B3         A01X+106673Y+125098X0180Y         S1      
317m4951            VIA   -    MD0100PA01X+013731Y+136010X0180Y         S0      
317m4951            J3    -I8   D0122PA01X+017051Y+158067X0282Y    R180 S3      
327m4951            C177  -2          A01X+013721Y+135519X0120Y0150R090 S1      
317m4952            VIA   -    MD0100PA01X+053832Y+140850X0180Y         S0      
317m4952            J12   -S5   D0122PA01X+049098Y+148933X0282Y    R180 S3      
327m4952            C2249 -2          A01X+053822Y+140359X0120Y0150R090 S1      
317m4953            VIA   -    MD0080PA01X+072185Y+123228X0160Y    R270 S0      
317m4953            VIA   -    MD0100PA01X+051384Y+139658X0180Y         S0      
327m4953            C2255 -1          A01X+051374Y+140149X0120Y0150R090 S1      
327m4953            PEX1  -G33        A01X+072185Y+123228X0180Y         S1      
317m4954            VIA   -    MD0080PA01X+122008Y+110138X0160Y    R270 S0      
327m4954            PEX2  -BB44       A01X+122008Y+110138X0180Y         S1      
327m4954            C430  -1          A01X+123026Y+058972X0120Y0150R180 S1      
317m4954            VIA   -    MD0100PA01X+123517Y+058982X0200Y    R090 S0      
327m4955            C605  -1          A01X+109133Y+135309X0120Y0150R090 S1      
317m4955            VIA   -    MD0100PA01X+109143Y+134819X0180Y         S0      
317m4955            VIA   -    MD0080PA01X+108169Y+120236X0160Y         S0      
327m4955            PEX2  -R7         A01X+108169Y+120236X0180Y         S1      
317m4956            VIA   -    MD0080PA01X+166968Y+113130X0160Y    R270 S0      
327m4956            PEX3  -AP42       A01X+166968Y+113130X0180Y         S1      
317m4956            VIA   -    MD0100PA01X+170266Y+047442X0200Y    R090 S0      
327m4956            C663  -1          A01X+169775Y+047432X0120Y0150R180 S1      
317m4957            VIA   -    MD0080PA01X+069567Y+122854X0160Y    R270 S0      
317m4957            VIA   -    MD0100PA01X+052948Y+134819X0180Y         S0      
327m4957            PEX1  -H26        A01X+069567Y+122854X0180Y         S1      
327m4957            C2270 -1          A01X+052958Y+135309X0120Y0150R090 S1      
317m4958            VIA   -    MD0080PA01X+119016Y+110138X0160Y    R270 S0      
327m4958            PEX2  -BB36       A01X+119016Y+110138X0180Y         S1      
327m4958            C464  -1          A01X+106777Y+049417X0120Y0150     S1      
317m4958            VIA   -    MD0100PA01X+106286Y+049407X0200Y    R270 S0      
327m4959            C614  -1          A01X+105821Y+137729X0120Y0150R090 S1      
317m4959            VIA   -    MD0100PA01X+105811Y+137238X0180Y         S0      
317m4959            VIA   -    MD0080PA01X+107795Y+118740X0160Y         S0      
327m4959            PEX2  -W6         A01X+107795Y+118740X0180Y         S1      
317m4960            VIA   -    MD0080PA01X+165472Y+110512X0160Y    R270 S0      
327m4960            C670  -1          A01X+152486Y+052053X0120Y0150     S1      
317m4960            VIA   -    MD0100PA01X+151995Y+052063X0200Y    R270 S0      
327m4960            PEX3  -BA38       A01X+165472Y+110512X0180Y         S1      
317m4961            J13   -X1   D0122PA01X+130508Y+146374X0282Y    R180 S3      
317m4961            VIA   -    MD0080PA01X+117520Y+124724X0160Y         S0      
327m4961            PEX2  -C32        A01X+117520Y+124724X0180Y         S1      
317m4962            VIA   -    MD0100PA01X+070313Y+138430X0180Y         S0      
317m4962            J5    -U1   D0122PA01X+062957Y+147910X0282Y    R180 S3      
327m4962            C387  -2          A01X+070323Y+137939X0120Y0150R090 S1      
317m4963            VIA   -    MD0080PA01X+069193Y+123228X0160Y    R270 S0      
317m4963            VIA   -    MD0100PA01X+051384Y+137238X0180Y         S0      
327m4963            PEX1  -G25        A01X+069193Y+123228X0180Y         S1      
327m4963            C2271 -1          A01X+051374Y+137729X0120Y0150R090 S1      
317m4964            VIA   -    MD0080PA01X+116398Y+109390X0160Y         S0      
317m4964            VIA   -    MD0100PA01X+106286Y+042275X0200Y    R270 S0      
327m4964            C478  -1          A01X+106777Y+042285X0120Y0150     S1      
327m4964            PEX2  -BD29       A01X+116398Y+109390X0180Y         S1      
327m4965            C565  -1          A01X+129143Y+137729X0120Y0150R090 S1      
317m4965            VIA   -    MD0100PA01X+129153Y+137238X0180Y         S0      
317m4965            VIA   -    MD0080PA01X+111161Y+123228X0160Y    R270 S0      
327m4965            PEX2  -G15        A01X+111161Y+123228X0180Y         S1      
317m4966            VIA   -    MD0080PA01X+167716Y+110138X0160Y    R270 S0      
327m4966            PEX3  -BB44       A01X+167716Y+110138X0180Y         S1      
327m4966            C641  -1          A01X+168735Y+058972X0120Y0150R180 S1      
317m4966            VIA   -    MD0100PA01X+169225Y+058982X0200Y    R090 S0      
317m4967            VIA   -    MD0100PA01X+054172Y+140850X0180Y         S0      
317m4967            J12   -R5   D0122PA01X+049098Y+149445X0282Y    R180 S3      
327m4967            C2250 -2          A01X+054182Y+140359X0120Y0150R090 S1      
317m4968            VIA   -    MD0080PA01X+063209Y+109390X0160Y    R270 S0      
327m4968            PEX1  -BD9        A01X+063209Y+109390X0180Y         S1      
327m4968            C277  -1          A01X+053859Y+013241X0120Y0150R180 S1      
317m4968            VIA   -    MD0100PA01X+054349Y+013251X0200Y    R090 S0      
317m4969            VIA   -    MD0080PA01X+120886Y+113130X0160Y    R270 S0      
327m4969            PEX2  -AP41       A01X+120886Y+113130X0180Y         S1      
317m4969            VIA   -    MD0100PA01X+124557Y+047782X0200Y    R090 S0      
327m4969            C451  -1          A01X+124066Y+047792X0120Y0150R180 S1      
327m4970            C602  -1          A01X+110717Y+137729X0120Y0150R090 S1      
317m4970            VIA   -    MD0100PA01X+110707Y+137238X0180Y         S0      
317m4970            VIA   -    MD0080PA01X+107795Y+120984X0160Y         S0      
327m4970            PEX2  -N6         A01X+107795Y+120984X0180Y         S1      
317m4971            VIA   -    MD0080PA01X+167716Y+113504X0160Y    R270 S0      
327m4971            PEX3  -AN44       A01X+167716Y+113504X0180Y         S1      
317m4971            VIA   -    MD0100PA01X+169225Y+046731X0200Y    R090 S0      
327m4971            C665  -1          A01X+168735Y+046721X0120Y0150R180 S1      
317m4972            J7    -O7   D0122PA01X+118382Y+150980X0282Y    R180 S3      
317m4972            VIA   -    MD0080PA01X+107795Y+124724X0160Y         S0      
327m4972            PEX2  -C6         A01X+107795Y+124724X0180Y         S1      
317m4973            VIA   -    MD0080PA01X+063583Y+110512X0160Y    R270 S0      
327m4973            PEX1  -BA10       A01X+063583Y+110512X0180Y         S1      
327m4973            C278  -1          A01X+052819Y+012890X0120Y0150R180 S1      
317m4973            VIA   -    MD0100PA01X+053309Y+012880X0200Y    R090 S0      
317m4974            VIA   -    MD0080PA01X+065453Y+123228X0160Y    R270 S0      
317m4974            VIA   -    MD0100PA01X+050160Y+137238X0180Y         S0      
327m4974            C354  -1          A01X+050150Y+137729X0120Y0150R090 S1      
327m4974            PEX1  -G15        A01X+065453Y+123228X0180Y         S1      
317m4975            VIA   -    MD0080PA01X+121260Y+113130X0160Y    R270 S0      
327m4975            PEX2  -AP42       A01X+121260Y+113130X0180Y         S1      
317m4975            VIA   -    MD0100PA01X+124557Y+047442X0200Y    R090 S0      
327m4975            C452  -1          A01X+124066Y+047432X0120Y0150R180 S1      
327m4976            C559  -1          A01X+126695Y+137729X0120Y0150R090 S1      
317m4976            VIA   -    MD0100PA01X+126705Y+137238X0180Y         S0      
317m4976            VIA   -    MD0080PA01X+110039Y+122480X0160Y         S0      
327m4976            PEX2  -J12        A01X+110039Y+122480X0180Y         S1      
317m4977            VIA   -    MD0080PA01X+160984Y+110138X0160Y    R270 S0      
327m4977            C695  -1          A01X+151686Y+040161X0120Y0150     S1      
317m4977            VIA   -    MD0100PA01X+151195Y+040151X0200Y    R270 S0      
327m4977            PEX3  -BB26       A01X+160984Y+110138X0180Y         S1      
317m4978            J7    -N2   D0122PA01X+114051Y+151413X0282Y    R180 S3      
317m4978            VIA   -    MD0080PA01X+106299Y+122106X0160Y         S0      
327m4978            PEX2  -K2         A01X+106299Y+122106X0180Y         S1      
317m4979            VIA   -    MD0080PA01X+069941Y+123602X0160Y    R270 S0      
317m4979            VIA   -    MD0100PA01X+052948Y+139658X0180Y         S0      
327m4979            PEX1  -F27        A01X+069941Y+123602X0180Y         S1      
327m4979            C2268 -1          A01X+052958Y+140149X0120Y0150R090 S1      
317m4980            VIA   -    MD0080PA01X+061339Y+122480X0160Y         S0      
317m4980            VIA   -    MD0100PA01X+073645Y+134819X0180Y         S0      
327m4980            PEX1  -J4         A01X+061339Y+122480X0180Y         S1      
327m4980            C378  -1          A01X+073635Y+135309X0120Y0150R090 S1      
317m4981            VIA   -    MD0080PA01X+120886Y+112382X0160Y    R270 S0      
327m4981            PEX2  -AT41       A01X+120886Y+112382X0180Y         S1      
317m4981            VIA   -    MD0100PA01X+124557Y+049199X0200Y    R090 S0      
327m4981            C447  -1          A01X+124066Y+049209X0120Y0150R180 S1      
327m4982            C607  -1          A01X+107909Y+137729X0120Y0150R090 S1      
317m4982            VIA   -    MD0100PA01X+107919Y+137238X0180Y         S0      
317m4982            VIA   -    MD0080PA01X+108917Y+119862X0160Y         S0      
327m4982            PEX2  -T9         A01X+108917Y+119862X0180Y         S1      
317m4983            VIA   -    MD0080PA01X+163228Y+110138X0160Y    R270 S0      
327m4983            PEX3  -BB32       A01X+163228Y+110138X0180Y         S1      
327m4983            C683  -1          A01X+151446Y+044413X0120Y0150     S1      
317m4983            VIA   -    MD0100PA01X+150955Y+044403X0200Y    R270 S0      
317m4984            VIA   -    MD0080PA01X+073307Y+122480X0160Y    R270 S0      
317m4984            VIA   -    MD0100PA01X+053832Y+139658X0180Y         S0      
327m4984            C2249 -1          A01X+053822Y+140149X0120Y0150R090 S1      
327m4984            PEX1  -J36        A01X+073307Y+122480X0180Y         S1      
317m4985            VIA   -    MD0080PA01X+060965Y+123602X0160Y    R270 S0      
317m4985            VIA   -    MD0100PA01X+072761Y+137238X0180Y         S0      
327m4985            PEX1  -F3         A01X+060965Y+123602X0180Y         S1      
327m4985            C381  -1          A01X+072771Y+137729X0120Y0150R090 S1      
317m4986            VIA   -    MD0080PA01X+121634Y+113504X0160Y    R270 S0      
327m4986            PEX2  -AN43       A01X+121634Y+113504X0180Y         S1      
317m4986            VIA   -    MD0100PA01X+123517Y+047071X0200Y    R090 S0      
327m4986            C453  -1          A01X+123026Y+047081X0120Y0150R180 S1      
327m4987            C611  -1          A01X+106685Y+135309X0120Y0150R090 S1      
317m4987            VIA   -    MD0100PA01X+106695Y+134819X0180Y         S0      
317m4987            VIA   -    MD0080PA01X+108917Y+119114X0160Y         S0      
327m4987            PEX2  -V9         A01X+108917Y+119114X0180Y         S1      
317m4988            VIA   -    MD0080PA01X+165846Y+109390X0160Y    R270 S0      
327m4988            PEX3  -BD39       A01X+165846Y+109390X0180Y         S1      
327m4988            C669  -1          A01X+151446Y+053119X0120Y0150     S1      
317m4988            VIA   -    MD0100PA01X+150955Y+053109X0200Y    R270 S0      
317m4989            VIA   -    MD0100PA01X+073985Y+136010X0180Y         S0      
317m4989            J5    -U5   D0122PA01X+066421Y+147910X0282Y    R180 S3      
327m4989            C379  -2          A01X+073995Y+135519X0120Y0150R090 S1      
317m4990            VIA   -    MD0080PA01X+063957Y+109764X0160Y    R270 S0      
327m4990            PEX1  -BC11       A01X+063957Y+109764X0180Y         S1      
327m4990            C280  -1          A01X+053859Y+012184X0120Y0150R180 S1      
317m4990            VIA   -    MD0100PA01X+054349Y+012174X0200Y    R090 S0      
317m4991            VIA   -    MD0080PA01X+063209Y+119862X0160Y         S0      
317m4991            VIA   -    MD0100PA01X+066301Y+134819X0180Y         S0      
327m4991            PEX1  -T9         A01X+063209Y+119862X0180Y         S1      
327m4991            C396  -1          A01X+066291Y+135309X0120Y0150R090 S1      
317m4992            VIA   -    MD0080PA01X+121634Y+109764X0160Y    R270 S0      
317m4992            VIA   -    MD0100PA01X+124557Y+060034X0200Y    R090 S0      
327m4992            C427  -1          A01X+124066Y+060044X0120Y0150R180 S1      
327m4992            PEX2  -BC43       A01X+121634Y+109764X0180Y         S1      
327m4993            C568  -1          A01X+130727Y+135309X0120Y0150R090 S1      
317m4993            VIA   -    MD0100PA01X+130717Y+134819X0180Y         S0      
317m4993            VIA   -    MD0080PA01X+111535Y+122854X0160Y         S0      
327m4993            PEX2  -H16        A01X+111535Y+122854X0180Y         S1      
317m4994            VIA   -    MD0080PA01X+161732Y+110138X0160Y    R270 S0      
327m4994            PEX3  -BB28       A01X+161732Y+110138X0180Y         S1      
327m4994            C691  -1          A01X+151446Y+041579X0120Y0150     S1      
317m4994            VIA   -    MD0100PA01X+150955Y+041569X0200Y    R270 S0      
317m4995            J7    -O8   D0122PA01X+119248Y+150902X0282Y    R180 S3      
317m4995            VIA   -    MD0080PA01X+108169Y+125098X0160Y         S0      
327m4995            PEX2  -B7         A01X+108169Y+125098X0180Y         S1      
317m4996            VIA   -    MD0100PA01X+075209Y+138430X0180Y         S0      
317m4996            J5    -U7   D0122PA01X+068154Y+147910X0282Y    R180 S3      
327m4996            C375  -2          A01X+075219Y+137939X0120Y0150R090 S1      
317m4997            VIA   -    MD0080PA01X+072185Y+123602X0160Y    R270 S0      
317m4997            VIA   -    MD0100PA01X+051724Y+139658X0180Y         S0      
327m4997            C2256 -1          A01X+051734Y+140149X0120Y0150R090 S1      
327m4997            PEX1  -F33        A01X+072185Y+123602X0180Y         S1      
317m4998            VIA   -    MD0080PA01X+068071Y+122854X0160Y         S0      
317m4998            VIA   -    MD0100PA01X+049276Y+137238X0180Y         S0      
327m4998            PEX1  -H22        A01X+068071Y+122854X0180Y         S1      
327m4998            C369  -1          A01X+049286Y+137729X0120Y0150R090 S1      
317m4999            VIA   -    MD0080PA01X+121634Y+111260X0160Y    R270 S0      
327m4999            PEX2  -AW43       A01X+121634Y+111260X0180Y         S1      
317m4999            VIA   -    MD0100PA01X+123517Y+052901X0200Y    R090 S0      
327m4999            C441  -1          A01X+123026Y+052911X0120Y0150R180 S1      
327m5000            C558  -1          A01X+125831Y+140149X0120Y0150R090 S1      
317m5000            VIA   -    MD0100PA01X+125821Y+139658X0180Y    R180 S0      
317m5000            VIA   -    MD0080PA01X+109665Y+123602X0160Y    R270 S0      
327m5000            PEX2  -F11        A01X+109665Y+123602X0180Y         S1      
317m5001            VIA   -    MD0080PA01X+163228Y+110512X0160Y    R270 S0      
327m5001            C682  -1          A01X+151446Y+044053X0120Y0150     S1      
317m5001            VIA   -    MD0100PA01X+150955Y+044063X0200Y    R270 S0      
327m5001            PEX3  -BA32       A01X+163228Y+110512X0180Y         S1      
317m5002            VIA   -    MD0080PA01X+065453Y+109764X0160Y    R270 S0      
327m5002            PEX1  -BC15       A01X+065453Y+109764X0180Y         S1      
327m5002            C288  -1          A01X+064095Y+012184X0120Y0150R180 S1      
317m5002            VIA   -    MD0100PA01X+064586Y+012174X0200Y    R090 S0      
317m5003            VIA   -    MD0080PA01X+066949Y+123602X0160Y    R270 S0      
317m5003            VIA   -    MD0100PA01X+046828Y+137238X0180Y         S0      
327m5003            PEX1  -F19        A01X+066949Y+123602X0180Y         S1      
327m5003            C363  -1          A01X+046838Y+137729X0120Y0150R090 S1      
317m5004            VIA   -    MD0080PA01X+114901Y+109390X0160Y    R270 S0      
327m5004            PEX2  -BD25       A01X+114902Y+109390X0180Y         S1      
317m5004            VIA   -    MD0100PA01X+106286Y+039440X0200Y    R270 S0      
327m5004            C486  -1          A01X+106777Y+039450X0120Y0150     S1      
327m5005            C554  -1          A01X+124607Y+137729X0120Y0150R090 S1      
317m5005            VIA   -    MD0100PA01X+124597Y+137238X0180Y         S0      
317m5005            VIA   -    MD0080PA01X+108917Y+123602X0160Y    R270 S0      
327m5005            PEX2  -F9         A01X+108917Y+123602X0180Y         S1      
317m5006            VIA   -    MD0080PA01X+163976Y+110512X0160Y    R270 S0      
327m5006            PEX3  -BA34       A01X+163976Y+110512X0180Y         S1      
327m5006            C678  -1          A01X+152486Y+047640X0120Y0150     S1      
317m5006            VIA   -    MD0100PA01X+151995Y+047650X0200Y    R270 S0      
317m5007            VIA   -    MD0100PA01X+054172Y+136010X0180Y         S0      
317m5007            J12   -Q4   D0122PA01X+048232Y+149878X0282Y    R180 S3      
327m5007            C2252 -2          A01X+054182Y+135519X0120Y0150R090 S1      
317m5008            VIA   -    MD0080PA01X+064705Y+109390X0160Y         S0      
327m5008            PEX1  -BD13       A01X+064705Y+109390X0180Y         S1      
327m5008            C285  -1          A01X+064095Y+013241X0120Y0150R180 S1      
317m5008            VIA   -    MD0100PA01X+064586Y+013251X0200Y    R090 S0      
317m5009            VIA   -    MD0080PA01X+062461Y+120236X0160Y         S0      
317m5009            VIA   -    MD0100PA01X+066301Y+139658X0180Y         S0      
327m5009            PEX1  -R7         A01X+062461Y+120236X0180Y         S1      
327m5009            C394  -1          A01X+066291Y+140149X0120Y0150R090 S1      
317m5010            VIA   -    MD0080PA01X+120512Y+110138X0160Y    R270 S0      
327m5010            C456  -1          A01X+106777Y+053831X0120Y0150     S1      
317m5010            VIA   -    MD0100PA01X+106286Y+053821X0200Y    R270 S0      
327m5010            PEX2  -BB40       A01X+120512Y+110138X0180Y         S1      
327m5011            C563  -1          A01X+127919Y+140149X0120Y0150R090 S1      
317m5011            VIA   -    MD0100PA01X+127929Y+139658X0180Y         S0      
317m5011            VIA   -    MD0080PA01X+110787Y+122480X0160Y         S0      
327m5011            PEX2  -J14        A01X+110787Y+122480X0180Y         S1      
317m5012            VIA   -    MD0080PA01X+168090Y+109764X0160Y    R270 S0      
317m5012            VIA   -    MD0100PA01X+170266Y+058616X0200Y    R090 S0      
327m5012            C642  -1          A01X+169775Y+058626X0120Y0150R180 S1      
327m5012            PEX3  -BC45       A01X+168090Y+109764X0180Y         S1      
317m5013            VIA   -    MD0080PA01X+066575Y+110512X0160Y    R270 S0      
327m5013            C294  -1          A01X+073291Y+012890X0120Y0150R180 S1      
317m5013            VIA   -    MD0100PA01X+073782Y+012880X0200Y    R090 S0      
327m5013            PEX1  -BA18       A01X+066575Y+110512X0180Y         S1      
317m5014            VIA   -    MD0080PA01X+063583Y+122480X0160Y         S0      
317m5014            VIA   -    MD0100PA01X+046488Y+134819X0180Y         S0      
327m5014            C344  -1          A01X+046478Y+135309X0120Y0150R090 S1      
327m5014            PEX1  -J10        A01X+063583Y+122480X0180Y         S1      
317m5015            VIA   -    MD0080PA01X+121634Y+112008X0160Y    R270 S0      
327m5015            PEX2  -AU43       A01X+121634Y+112008X0180Y         S1      
317m5015            VIA   -    MD0100PA01X+123517Y+051484X0200Y    R090 S0      
327m5015            C445  -1          A01X+123026Y+051494X0120Y0150R180 S1      
327m5016            C593  -1          A01X+114389Y+135309X0120Y0150R090 S1      
317m5016            VIA   -    MD0100PA01X+114379Y+134819X0180Y         S0      
317m5016            VIA   -    MD0080PA01X+106299Y+123976X0160Y         S0      
327m5016            PEX2  -E2         A01X+106299Y+123976X0180Y         S1      
317m5017            VIA   -    MD0080PA01X+167342Y+109390X0160Y    R270 S0      
317m5017            VIA   -    MD0100PA01X+170266Y+059694X0200Y    R090 S0      
327m5017            C639  -1          A01X+169775Y+059684X0120Y0150R180 S1      
327m5017            PEX3  -BD43       A01X+167342Y+109390X0180Y         S1      
317m5018            VIA   -    MD0100PA01X+056280Y+136010X0180Y         S0      
317m5018            J12   -S7   D0122PA01X+050831Y+148933X0282Y    R180 S3      
327m5018            C2245 -2          A01X+056270Y+135519X0120Y0150R090 S1      
317m5019            VIA   -    MD0080PA01X+068819Y+122480X0160Y         S0      
317m5019            VIA   -    MD0100PA01X+050160Y+139658X0180Y         S0      
327m5019            PEX1  -J24        A01X+068819Y+122480X0180Y         S1      
327m5019            C2273 -1          A01X+050150Y+140149X0120Y0150R090 S1      
317m5020            VIA   -    MD0080PA01X+062461Y+123602X0160Y    R270 S0      
317m5020            VIA   -    MD0100PA01X+076433Y+134819X0180Y         S0      
327m5020            PEX1  -F7         A01X+062461Y+123602X0180Y         S1      
327m5020            C373  -1          A01X+076443Y+135309X0120Y0150R090 S1      
317m5021            VIA   -    MD0080PA01X+115649Y+109764X0160Y    R270 S0      
327m5021            PEX2  -BC27       A01X+115650Y+109764X0180Y         S1      
317m5021            VIA   -    MD0100PA01X+106286Y+040517X0200Y    R270 S0      
327m5021            C481  -1          A01X+106777Y+040507X0120Y0150     S1      
327m5022            C591  -1          A01X+114029Y+140149X0120Y0150R090 S1      
317m5022            VIA   -    MD0100PA01X+114039Y+139658X0180Y         S0      
317m5022            VIA   -    MD0080PA01X+106673Y+123228X0160Y    R270 S0      
327m5022            PEX2  -G3         A01X+106673Y+123228X0180Y         S1      
327m5023            VIA   -    M      A01X+161792Y+037070X0300Y         S1      
327m5023            R402  -2   M      A01X+169268Y+034232X0198Y0197R270 S1      
327m5023            U45   -4          A01X+168321Y+034232X0160Y0360R270 S1      
327m5023            R403  -2   M      A01X+168868Y+034232X0198Y0197R270 S1      
327m5023            R404  -2   M      A01X+160195Y+038072X0198Y0197R180 S1      
327m5023            R405  -2          A01X+160195Y+038472X0198Y0197R180 S1      
317m5024            VIA   -    MD0100PA01X+072761Y+138430X0180Y         S0      
317m5024            J5    -T4   D0122PA01X+065555Y+148343X0282Y    R180 S3      
327m5024            C381  -2          A01X+072771Y+137939X0120Y0150R090 S1      
317m5025            VIA   -    MD0080PA01X+062461Y+120984X0160Y         S0      
317m5025            VIA   -    MD0100PA01X+068749Y+134819X0180Y         S0      
327m5025            PEX1  -N7         A01X+062461Y+120984X0180Y         S1      
327m5025            C390  -1          A01X+068739Y+135309X0120Y0150R090 S1      
317m5026            VIA   -    MD0080PA01X+123878Y+110138X0160Y    R270 S0      
327m5026            PEX2  -BB49       A01X+123878Y+110138X0180Y         S1      
317m5026            VIA   -    MD0100PA01X+124557Y+053272X0200Y    R090 S0      
327m5026            C440  -1          A01X+124066Y+053262X0120Y0150R180 S1      
327m5027            C594  -1          A01X+114029Y+135309X0120Y0150R090 S1      
317m5027            VIA   -    MD0100PA01X+114039Y+134819X0180Y         S0      
317m5027            VIA   -    MD0080PA01X+105925Y+123976X0160Y         S0      
327m5027            PEX2  -E1         A01X+105925Y+123976X0180Y         S1      
317PRSNT_NIC7_N     VIA   -    M      A01X+162038Y+046587X0200Y         S2      
017PRSNT_NIC7_N     VIA   -    M      A18X+162038Y+046587X0260Y         S2      
017PRSNT_NIC7_N           -    MD0100PA00X+162038Y+046587                       
327PRSNT_NIC7_N     R398  -1          A01X+162038Y+046286X0198Y0197     S1      
317PRSNT_NIC7_N     VIA   -    MD0100PA00X+161662Y+054671X0200Y    R180 S0      
327PRSNT_NIC7_N     R399  -1          A01X+168992Y+062691X0198Y0197R180 S1      
317PRSNT_NIC7_N     VIA   -    MD0100PA00X+169300Y+062691X0200Y    R180 S0      
327PRSNT_NIC7_N     R397  -1   M      A01X+161957Y+054671X0198Y0197     S1      
327PRSNT_NIC7_N     R396  -1   M      A01X+168992Y+054591X0198Y0197R180 S1      
327PRSNT_NIC7_N     R400  -2          A01X+171354Y+055514X0198Y0197R270 S1      
317PRSNT_NIC7_N     VIA   -    MD0100PA00X+171017Y+055310X0200Y         S0      
317m5028            VIA   -    MD0100PA01X+056620Y+136010X0180Y         S0      
317m5028            J12   -R7   D0122PA01X+050831Y+149445X0282Y    R180 S3      
327m5028            C2246 -2          A01X+056630Y+135519X0120Y0150R090 S1      
317m5029            VIA   -    MD0080PA01X+062461Y+123228X0160Y    R270 S0      
317m5029            VIA   -    MD0100PA01X+076093Y+134819X0180Y         S0      
327m5029            PEX1  -G7         A01X+062461Y+123228X0180Y         S1      
327m5029            C372  -1          A01X+076083Y+135309X0120Y0150R090 S1      
317m5030            VIA   -    MD0080PA01X+118268Y+110138X0160Y    R270 S0      
327m5030            C468  -1          A01X+106777Y+048000X0120Y0150     S1      
317m5030            VIA   -    MD0100PA01X+106286Y+047990X0200Y    R270 S0      
327m5030            PEX2  -BB34       A01X+118268Y+110138X0180Y         S1      
327m5031            C573  -1          A01X+132815Y+135309X0120Y0150R090 S1      
317m5031            VIA   -    MD0100PA01X+132825Y+134819X0180Y         S0      
317m5031            VIA   -    MD0080PA01X+112657Y+123228X0160Y    R270 S0      
327m5031            PEX2  -G19        A01X+112657Y+123228X0180Y         S1      
317m5032            J7    -P5   D0122PA01X+116650Y+150468X0282Y    R180 S3      
317m5032            VIA   -    MD0080PA01X+107047Y+124350X0160Y         S0      
327m5032            PEX2  -D4         A01X+107047Y+124350X0180Y         S1      
317HP_NIC7_PWRGD    VIA   -    M      A01X+168634Y+031489X0200Y         S2      
017HP_NIC7_PWRGD    VIA   -    M      A18X+168634Y+031489X0260Y         S2      
017HP_NIC7_PWRGD          -    MD0100PA00X+168634Y+031489                       
327HP_NIC7_PWRGD    U47   -1          A01X+169069Y+031285X0400Y0500     S1      
327HP_NIC7_PWRGD    R408  -2          A01X+168352Y+031874X0198Y0197R270 S1      
327HP_NIC7_PWRGD    R406  -2   M      A01X+168352Y+031489X0198Y0197R090 S1      
317m5033            VIA   -    MD0100PA01X+010399Y+138430X0180Y         S0      
317m5033            J3    -H4   D0122PA01X+013587Y+158579X0282Y    R180 S3      
327m5033            C186  -2          A01X+010409Y+137939X0120Y0150R090 S1      
317m5034            VIA   -    MD0080PA01X+067323Y+122480X0160Y         S0      
317m5034            VIA   -    MD0100PA01X+047712Y+134819X0180Y         S0      
327m5034            PEX1  -J20        A01X+067323Y+122480X0180Y         S1      
327m5034            C364  -1          A01X+047702Y+135309X0120Y0150R090 S1      
317m5035            VIA   -    MD0080PA01X+117894Y+109390X0160Y    R270 S0      
317m5035            VIA   -    MD0100PA01X+105246Y+047279X0200Y    R270 S0      
327m5035            C470  -1          A01X+105737Y+047289X0120Y0150     S1      
327m5035            PEX2  -BD33       A01X+117894Y+109390X0180Y         S1      
327m5036            C561  -1          A01X+127919Y+135309X0120Y0150R090 S1      
317m5036            VIA   -    MD0100PA01X+127929Y+134819X0180Y         S0      
317m5036            VIA   -    MD0080PA01X+110413Y+123228X0160Y    R270 S0      
327m5036            PEX2  -G13        A01X+110413Y+123228X0180Y         S1      
317m5037            J7    -O3   D0122PA01X+114917Y+150980X0282Y    R180 S3      
317m5037            VIA   -    MD0080PA01X+106299Y+124724X0160Y         S0      
327m5037            PEX2  -C2         A01X+106299Y+124724X0180Y         S1      
317m5038            VIA   -    MD0100PA01X+051724Y+136010X0180Y         S0      
317m5038            J12   -R1   D0122PA01X+045634Y+149445X0282Y    R180 S3      
327m5038            C2258 -2          A01X+051734Y+135519X0120Y0150R090 S1      
317m5039            VIA   -    MD0080PA01X+062087Y+119488X0160Y         S0      
317m5039            VIA   -    MD0100PA01X+065417Y+137238X0180Y         S0      
327m5039            PEX1  -U6         A01X+062087Y+119488X0180Y         S1      
327m5039            C399  -1          A01X+065427Y+137729X0120Y0150R090 S1      
317m5040            VIA   -    MD0080PA01X+121260Y+111634X0160Y    R270 S0      
327m5040            PEX2  -AV42       A01X+121260Y+111634X0180Y         S1      
317m5040            VIA   -    MD0100PA01X+124557Y+051855X0200Y    R090 S0      
327m5040            C444  -1          A01X+124066Y+051845X0120Y0150R180 S1      
327m5041            C582  -1          A01X+135623Y+140149X0120Y0150R090 S1      
317m5041            VIA   -    MD0100PA01X+135613Y+139658X0180Y         S0      
317m5041            VIA   -    MD0080PA01X+114154Y+123602X0160Y    R270 S0      
327m5041            PEX2  -F23        A01X+114154Y+123602X0180Y         S1      
327m5042            VIA   -    M      A01X+166610Y+031791X0300Y         S1      
327m5042            Q8    -3          A01X+167109Y+031673X0170Y0240R270 S1      
327m5042            Q8    -2          A01X+167109Y+031929X0170Y0240R270 S1      
327m5042            R407  -2          A01X+166135Y+031787X0198Y0197     S1      
317m5043            VIA   -    MD0100PA01X+008835Y+140850X0180Y         S0      
317m5043            J3    -J3   D0122PA01X+012720Y+157634X0282Y    R180 S3      
327m5043            C187  -2          A01X+008825Y+140359X0120Y0150R090 S1      
317m5044            VIA   -    MD0080PA01X+062835Y+119862X0160Y         S0      
317m5044            VIA   -    MD0100PA01X+066641Y+134819X0180Y         S0      
327m5044            PEX1  -T8         A01X+062835Y+119862X0180Y         S1      
327m5044            C397  -1          A01X+066651Y+135309X0120Y0150R090 S1      
317m5045            VIA   -    MD0080PA01X+117520Y+110512X0160Y    R270 S0      
327m5045            C471  -1          A01X+105737Y+044053X0120Y0150     S1      
317m5045            VIA   -    MD0100PA01X+105246Y+044063X0200Y    R270 S0      
327m5045            PEX2  -BA32       A01X+117520Y+110512X0180Y         S1      
327m5046            C555  -1          A01X+125471Y+135309X0120Y0150R090 S1      
317m5046            VIA   -    MD0100PA01X+125481Y+134819X0180Y         S0      
317m5046            VIA   -    MD0080PA01X+109291Y+122480X0160Y         S0      
327m5046            PEX2  -J10        A01X+109291Y+122480X0180Y         S1      
317m5047            VIA   -    MD0080PA01X+075177Y+109390X0160Y    R270 S0      
327m5047            C213  -1          A01X+078358Y+061101X0120Y0150R180 S1      
317m5047            VIA   -    MD0100PA01X+078848Y+061111X0200Y    R090 S0      
327m5047            PEX1  -BD41       A01X+075177Y+109390X0180Y         S1      
317m5048            VIA   -    MD0080PA01X+063209Y+121358X0160Y         S0      
317m5048            VIA   -    MD0100PA01X+068749Y+139658X0180Y         S0      
327m5048            PEX1  -M9         A01X+063209Y+121358X0180Y         S1      
327m5048            C388  -1          A01X+068739Y+140149X0120Y0150R090 S1      
317m5049            VIA   -    MD0080PA01X+119764Y+110138X0160Y    R270 S0      
327m5049            C460  -1          A01X+106777Y+052413X0120Y0150     S1      
317m5049            VIA   -    MD0100PA01X+106286Y+052403X0200Y    R270 S0      
327m5049            PEX2  -BB38       A01X+119764Y+110138X0180Y         S1      
327m5050            C603  -1          A01X+109133Y+140149X0120Y0150R090 S1      
317m5050            VIA   -    MD0100PA01X+109143Y+139658X0180Y         S0      
317m5050            VIA   -    MD0080PA01X+108917Y+120610X0160Y         S0      
327m5050            PEX2  -P9         A01X+108917Y+120610X0180Y         S1      
317m5051            J13   -W4   D0122PA01X+133106Y+146807X0282Y    R180 S3      
317m5051            VIA   -    MD0080PA01X+118642Y+125472X0160Y    R090 S0      
327m5051            PEX2  -A35        A01X+118642Y+125472X0180Y         S1      
317m5052            VIA   -    MD0100PA01X+009175Y+140850X0180Y         S0      
317m5052            J3    -I3   D0122PA01X+012720Y+158146X0282Y    R180 S3      
327m5052            C188  -2          A01X+009185Y+140359X0120Y0150R090 S1      
317m5053            VIA   -    MD0100PA01X+052948Y+138430X0180Y         S0      
317m5053            J12   -R3   D0122PA01X+047366Y+149445X0282Y    R180 S3      
327m5053            C2254 -2          A01X+052958Y+137939X0120Y0150R090 S1      
317m5054            VIA   -    MD0080PA01X+071063Y+110138X0160Y    R270 S0      
327m5054            C265  -1          A01X+060028Y+042996X0120Y0150     S1      
317m5054            VIA   -    MD0100PA01X+059538Y+042986X0200Y    R270 S0      
327m5054            PEX1  -BB30       A01X+071063Y+110138X0180Y         S1      
317m5055            VIA   -    MD0080PA01X+065079Y+122480X0160Y         S0      
317m5055            VIA   -    MD0100PA01X+048936Y+139658X0180Y         S0      
327m5055            C352  -1          A01X+048926Y+140149X0120Y0150R090 S1      
327m5055            PEX1  -J14        A01X+065079Y+122480X0180Y         S1      
317m5056            VIA   -    MD0080PA01X+120886Y+111634X0160Y    R270 S0      
327m5056            PEX2  -AV41       A01X+120886Y+111634X0180Y         S1      
317m5056            VIA   -    MD0100PA01X+124557Y+052195X0200Y    R090 S0      
327m5056            C443  -1          A01X+124066Y+052205X0120Y0150R180 S1      
327m5057            C606  -1          A01X+109493Y+135309X0120Y0150R090 S1      
317m5057            VIA   -    MD0100PA01X+109483Y+134819X0180Y         S0      
317m5057            VIA   -    MD0080PA01X+107795Y+120236X0160Y         S0      
327m5057            PEX2  -R6         A01X+107795Y+120236X0180Y         S1      
327m5058            VIA   -    M      A18X+071573Y+044706X0260Y         S2      
327m5058            U23   -2          A18X+072972Y+045163X0160Y0240R180 S2      
327m5058            R189  -2          A18X+071880Y+043832X0198Y0197R180 S2      
317m5059            VIA   -    MD0080PA01X+069941Y+109390X0160Y    R270 S0      
327m5059            C271  -1          A01X+061068Y+040867X0120Y0150     S1      
317m5059            VIA   -    MD0100PA01X+060578Y+040857X0200Y    R270 S0      
327m5059            PEX1  -BD27       A01X+069941Y+109390X0180Y         S1      
317m5060            VIA   -    MD0080PA01X+060216Y+123976X0160Y         S0      
317m5060            VIA   -    MD0100PA01X+071197Y+139658X0180Y         S0      
327m5060            C383  -1          A01X+071187Y+140149X0120Y0150R090 S1      
327m5060            PEX1  -E1         A01X+060216Y+123976X0180Y         S1      
317m5061            VIA   -    MD0080PA01X+115276Y+110138X0160Y    R270 S0      
327m5061            C484  -1          A01X+105977Y+040161X0120Y0150     S1      
317m5061            VIA   -    MD0100PA01X+105486Y+040151X0200Y    R270 S0      
327m5061            PEX2  -BB26       A01X+115276Y+110138X0180Y         S1      
327m5062            C562  -1          A01X+128279Y+135309X0120Y0150R090 S1      
317m5062            VIA   -    MD0100PA01X+128269Y+134819X0180Y         S0      
317m5062            VIA   -    MD0080PA01X+110413Y+123602X0160Y    R270 S0      
327m5062            PEX2  -F13        A01X+110413Y+123602X0180Y         S1      
317m5063            J13   -X5   D0122PA01X+133972Y+146374X0282Y    R180 S3      
317m5063            VIA   -    MD0080PA01X+119016Y+124724X0160Y         S0      
327m5063            PEX2  -C36        A01X+119016Y+124724X0180Y         S1      
317m5064            VIA   -    M      A01X+070978Y+044296X0200Y         S2      
017m5064            VIA   -    M      A18X+070978Y+044296X0260Y         S2      
017m5064                  -    MD0100PA00X+070978Y+044296                       
327m5064            U23   -4          A18X+072677Y+045871X0240Y0240R270 S2      
327m5064            R188  -1   M      A01X+070621Y+044587X0198Y0197     S1      
327m5064            R190  -2          A01X+070621Y+045387X0198Y0197R180 S1      
327m5064            R191  -1   M      A01X+070621Y+044987X0198Y0197     S1      
317m5065            VIA   -    MD0100PA01X+008835Y+136010X0180Y         S0      
317m5065            J3    -I2   D0122PA01X+011854Y+158067X0282Y    R180 S3      
327m5065            C189  -2          A01X+008825Y+135519X0120Y0150R090 S1      
317m5066            VIA   -    MD0100PA01X+056280Y+140850X0180Y         S0      
317m5066            J12   -R8   D0122PA01X+051697Y+149366X0282Y    R180 S3      
327m5066            C2243 -2          A01X+056270Y+140359X0120Y0150R090 S1      
317m5067            VIA   -    MD0080PA01X+077795Y+109016X0160Y    R270 S0      
327m5067            C226  -1          A01X+077317Y+056498X0120Y0150R180 S1      
317m5067            VIA   -    MD0100PA01X+077808Y+056488X0200Y    R090 S0      
327m5067            PEX1  -BE48       A01X+077795Y+109016X0180Y         S1      
317m5068            VIA   -    MD0080PA01X+063209Y+123602X0160Y    R270 S0      
317m5068            VIA   -    MD0100PA01X+045604Y+137238X0180Y         S0      
327m5068            C343  -1          A01X+045614Y+137729X0120Y0150R090 S1      
327m5068            PEX1  -F9         A01X+063209Y+123602X0180Y         S1      
317m5069            VIA   -    MD0080PA01X+117146Y+109764X0160Y         S0      
317m5069            VIA   -    MD0100PA01X+106286Y+043352X0200Y    R270 S0      
327m5069            C473  -1          A01X+106777Y+043342X0120Y0150     S1      
327m5069            PEX2  -BC31       A01X+117146Y+109764X0180Y         S1      
327m5070            C592  -1          A01X+114389Y+140149X0120Y0150R090 S1      
317m5070            VIA   -    MD0100PA01X+114379Y+139658X0180Y         S0      
317m5070            VIA   -    MD0080PA01X+106673Y+123602X0160Y    R270 S0      
327m5070            PEX2  -F3         A01X+106673Y+123602X0180Y         S1      
317m5071            J13   -W6   D0122PA01X+134839Y+146807X0282Y    R180 S3      
317m5071            VIA   -    MD0080PA01X+119390Y+125472X0160Y    R090 S0      
327m5071            PEX2  -A37        A01X+119390Y+125472X0180Y         S1      
327m5072            VIA   -    M      A18X+021550Y+054400X0260Y         S2      
327m5072            U8    -2          A18X+021246Y+055485X0160Y0240R090 S2      
327m5072            R36   -2          A18X+022050Y+053958X0198Y0197R270 S2      
317m5073            VIA   -    MD0080PA01X+074803Y+110138X0160Y    R270 S0      
327m5073            C245  -1          A01X+061068Y+053831X0120Y0150     S1      
317m5073            VIA   -    MD0100PA01X+060578Y+053821X0200Y    R270 S0      
327m5073            PEX1  -BB40       A01X+074803Y+110138X0180Y         S1      
317m5074            VIA   -    MD0080PA01X+063209Y+123228X0160Y    R270 S0      
317m5074            VIA   -    MD0100PA01X+045264Y+137238X0180Y         S0      
327m5074            C342  -1          A01X+045254Y+137729X0120Y0150R090 S1      
327m5074            PEX1  -G9         A01X+063209Y+123228X0180Y         S1      
317m5075            VIA   -    MD0080PA01X+116772Y+110512X0160Y    R270 S0      
327m5075            PEX2  -BA30       A01X+116772Y+110512X0180Y         S1      
327m5075            C475  -1          A01X+105737Y+042636X0120Y0150     S1      
317m5075            VIA   -    MD0100PA01X+105246Y+042646X0200Y    R270 S0      
327m5076            C584  -1          A01X+118061Y+137729X0120Y0150R090 S1      
317m5076            VIA   -    MD0100PA01X+118051Y+137238X0180Y         S0      
317m5076            VIA   -    MD0080PA01X+108169Y+123602X0160Y    R270 S0      
327m5076            PEX2  -F7         A01X+108169Y+123602X0180Y         S1      
317m5077            J13   -Y7   D0122PA01X+135705Y+145862X0282Y    R180 S3      
317m5077            VIA   -    MD0080PA01X+119764Y+124350X0160Y         S0      
327m5077            PEX2  -D38        A01X+119764Y+124350X0180Y         S1      
327m5078            U8    -4          A18X+021955Y+055780X0240Y0240R180 S2      
317m5078            VIA   -    M      A01X+022350Y+056800X0200Y         S2      
017m5078            VIA   -    M      A18X+022350Y+056800X0260Y         S2      
017m5078                  -    MD0100PA00X+022350Y+056800                       
327m5078            R35   -1   M      A01X+023018Y+055770X0198Y0197R180 S1      
327m5078            R37   -2          A01X+023018Y+054970X0198Y0197     S1      
327m5078            R38   -1   M      A01X+023018Y+055370X0198Y0197R180 S1      
317m5079            VIA   -    MD0100PA01X+009175Y+136010X0180Y         S0      
317m5079            J3    -H2   D0122PA01X+011854Y+158579X0282Y    R180 S3      
327m5079            C190  -2          A01X+009185Y+135519X0120Y0150R090 S1      
317m5080            VIA   -    MD0100PA01X+071537Y+136010X0180Y         S0      
317m5080            J5    -T2   D0122PA01X+063823Y+148343X0282Y    R180 S3      
327m5080            C384  -2          A01X+071547Y+135519X0120Y0150R090 S1      
317m5081            VIA   -    MD0080PA01X+076673Y+109390X0160Y    R270 S0      
327m5081            C221  -1          A01X+078358Y+058266X0120Y0150R180 S1      
317m5081            VIA   -    MD0100PA01X+078848Y+058276X0200Y    R090 S0      
327m5081            PEX1  -BD45       A01X+076673Y+109390X0180Y         S1      
317m5082            VIA   -    MD0080PA01X+062835Y+121358X0160Y         S0      
317m5082            VIA   -    MD0100PA01X+069089Y+139658X0180Y         S0      
327m5082            PEX1  -M8         A01X+062835Y+121358X0180Y         S1      
327m5082            C389  -1          A01X+069099Y+140149X0120Y0150R090 S1      
317m5083            VIA   -    MD0080PA01X+118268Y+110512X0160Y    R270 S0      
327m5083            PEX2  -BA34       A01X+118268Y+110512X0180Y         S1      
327m5083            C467  -1          A01X+106777Y+047640X0120Y0150     S1      
317m5083            VIA   -    MD0100PA01X+106286Y+047650X0200Y    R270 S0      
327m5084            C583  -1          A01X+117701Y+137729X0120Y0150R090 S1      
317m5084            VIA   -    MD0100PA01X+117711Y+137238X0180Y         S0      
317m5084            VIA   -    MD0080PA01X+108169Y+123228X0160Y    R270 S0      
327m5084            PEX2  -G7         A01X+108169Y+123228X0180Y         S1      
327m5085            VIA   -    M      A18X+158676Y+054400X0260Y         S2      
327m5085            U38   -2          A18X+158372Y+055485X0160Y0240R090 S2      
327m5085            R342  -2          A18X+159176Y+053958X0198Y0197R270 S2      
327PRSNT_NIC1_N     R92   -1          A01X+024912Y+046286X0198Y0197     S1      
317PRSNT_NIC1_N     VIA   -    MD0100PA00X+024912Y+046587X0200Y    R180 S0      
317PRSNT_NIC1_N     VIA   -    M      A01X+024536Y+054671X0200Y    R180 S2      
017PRSNT_NIC1_N     VIA   -    M      A18X+024536Y+054671X0260Y    R180 S2      
017PRSNT_NIC1_N           -    MD0100PA00X+024536Y+054671                       
327PRSNT_NIC1_N     R91   -1   M      A01X+024831Y+054671X0198Y0197     S1      
327PRSNT_NIC1_N     R93   -1          A01X+031866Y+062691X0198Y0197R180 S1      
327PRSNT_NIC1_N     R90   -1   M      A01X+031866Y+054591X0198Y0197R180 S1      
327PRSNT_NIC1_N     R94   -2   M      A01X+034228Y+055514X0198Y0197R270 S1      
317m5086            VIA   -    MD0080PA01X+078169Y+109016X0160Y    R270 S0      
327m5086            C227  -1          A01X+077317Y+056138X0120Y0150R180 S1      
317m5086            VIA   -    MD0100PA01X+077808Y+056148X0200Y    R090 S0      
327m5086            PEX1  -BE49       A01X+078169Y+109016X0180Y         S1      
317m5087            VIA   -    MD0080PA01X+065827Y+122854X0160Y         S0      
327m5087            C357  -1          A01X+044390Y+137729X0120Y0150R090 S1      
317m5087            VIA   -    MD0100PA01X+044380Y+137238X0180Y         S0      
327m5087            PEX1  -H16        A01X+065827Y+122854X0180Y         S1      
317m5088            VIA   -    MD0080PA01X+121260Y+112382X0160Y    R270 S0      
327m5088            PEX2  -AT42       A01X+121260Y+112382X0180Y         S1      
317m5088            VIA   -    MD0100PA01X+124557Y+048859X0200Y    R090 S0      
327m5088            C448  -1          A01X+124066Y+048849X0120Y0150R180 S1      
327m5089            C577  -1          A01X+134039Y+137729X0120Y0150R090 S1      
317m5089            VIA   -    MD0100PA01X+134049Y+137238X0180Y         S0      
317m5089            VIA   -    MD0080PA01X+113405Y+123228X0160Y    R270 S0      
327m5089            PEX2  -G21        A01X+113405Y+123228X0180Y         S1      
327m5090            R341  -1   M      A01X+160144Y+055770X0198Y0197R180 S1      
327m5090            R343  -2          A01X+160144Y+054970X0198Y0197     S1      
327m5090            R344  -1   M      A01X+160144Y+055370X0198Y0197R180 S1      
317m5090            VIA   -    M      A01X+159476Y+056800X0200Y         S2      
017m5090            VIA   -    M      A18X+159476Y+056800X0260Y         S2      
017m5090                  -    MD0100PA00X+159476Y+056800                       
327m5090            U38   -4          A18X+159081Y+055780X0240Y0240R180 S2      
327m5091            VIA   -    M      A01X+029484Y+031791X0300Y         S1      
327m5091            Q2    -2          A01X+029983Y+031929X0170Y0240R270 S1      
327m5091            R101  -2          A01X+029009Y+031787X0198Y0197     S1      
327m5091            Q2    -3          A01X+029983Y+031673X0170Y0240R270 S1      
317m5092            VIA   -    MD0080PA01X+075551Y+110138X0160Y    R270 S0      
327m5092            C215  -1          A01X+077317Y+060390X0120Y0150R180 S1      
317m5092            VIA   -    MD0100PA01X+077808Y+060400X0200Y    R090 S0      
327m5092            PEX1  -BB42       A01X+075551Y+110138X0180Y         S1      
317m5093            VIA   -    MD0080PA01X+063209Y+119114X0160Y         S0      
317m5093            VIA   -    MD0100PA01X+063853Y+139658X0180Y         S0      
327m5093            PEX1  -V9         A01X+063209Y+119114X0180Y         S1      
327m5093            C400  -1          A01X+063843Y+140149X0120Y0150R090 S1      
317m5094            VIA   -    MD0080PA01X+120886Y+109390X0160Y    R270 S0      
327m5094            PEX2  -BD41       A01X+120886Y+109390X0180Y         S1      
317m5094            VIA   -    MD0100PA01X+124557Y+061111X0200Y    R090 S0      
327m5094            C424  -1          A01X+124066Y+061101X0120Y0150R180 S1      
327m5095            C610  -1          A01X+107045Y+140149X0120Y0150R090 S1      
317m5095            VIA   -    MD0100PA01X+107035Y+139658X0180Y         S0      
317m5095            VIA   -    MD0080PA01X+107795Y+119488X0160Y         S0      
327m5095            PEX2  -U6         A01X+107795Y+119488X0180Y         S1      
327m5096            VIA   -    M      A01X+110911Y+070690X0300Y         S1      
327m5096            Q5    -3          A01X+111374Y+070228X0170Y0240R180 S1      
327m5096            Q5    -2          A01X+111630Y+070228X0170Y0240R180 S1      
327m5096            R254  -2   M      A01X+111496Y+071013X0198Y0197R180 S1      
317m5097            VIA   -    M      A01X+029140Y+035022X0200Y         S2      
017m5097            VIA   -    M      A18X+029140Y+035022X0260Y         S2      
017m5097                  -    MD0100PA00X+029140Y+035022                       
327m5097            R96   -2          A01X+032142Y+034232X0198Y0197R270 S1      
327m5097            R97   -2   M      A01X+031742Y+034232X0198Y0197R270 S1      
327m5097            U15   -4   M      A01X+031195Y+034232X0160Y0360R270 S1      
327m5097            R99   -2          A01X+023069Y+038472X0198Y0197R180 S1      
327m5097            R98   -2   M      A01X+023069Y+038072X0198Y0197R180 S1      
317m5098            VIA   -    MD0100PA01X+076093Y+136010X0180Y         S0      
317m5098            J5    -U8   D0122PA01X+069020Y+147831X0282Y    R180 S3      
327m5098            C372  -2          A01X+076083Y+135519X0120Y0150R090 S1      
317m5099            VIA   -    MD0080PA01X+070315Y+110138X0160Y    R270 S0      
327m5099            C269  -1          A01X+060028Y+041579X0120Y0150     S1      
317m5099            VIA   -    MD0100PA01X+059538Y+041569X0200Y    R270 S0      
327m5099            PEX1  -BB28       A01X+070315Y+110138X0180Y         S1      
317m5100            VIA   -    MD0080PA01X+062461Y+121732X0160Y         S0      
317m5100            VIA   -    MD0100PA01X+069973Y+137238X0180Y    R180 S0      
327m5100            PEX1  -L7         A01X+062461Y+121732X0180Y         S1      
327m5100            C386  -1          A01X+069963Y+137729X0120Y0150R090 S1      
317m5101            VIA   -    MD0080PA01X+118642Y+109390X0160Y    R270 S0      
327m5101            PEX2  -BD35       A01X+118642Y+109390X0180Y         S1      
317m5101            VIA   -    MD0100PA01X+105246Y+048696X0200Y    R270 S0      
327m5101            C466  -1          A01X+105737Y+048706X0120Y0150     S1      
327m5102            C580  -1          A01X+135623Y+135309X0120Y0150R090 S1      
317m5102            VIA   -    MD0100PA01X+135613Y+134819X0180Y         S0      
317m5102            VIA   -    MD0080PA01X+113780Y+122854X0160Y         S0      
327m5102            PEX2  -H22        A01X+113780Y+122854X0180Y         S1      
317m5103            J13   -W8   D0122PA01X+136571Y+146807X0282Y    R180 S3      
317m5103            VIA   -    MD0080PA01X+120138Y+125472X0160Y    R090 S0      
327m5103            PEX2  -A39        A01X+120138Y+125472X0180Y         S1      
327m5104            VIA   -    M      A01X+113387Y+064842X0300Y         S1      
327m5104            U30   -4          A01X+110968Y+065316X0160Y0360R270 S1      
327m5104            R249  -2   M      A01X+111515Y+065631X0198Y0197R090 S1      
327m5104            R250  -2   M      A01X+111915Y+065631X0198Y0197R090 S1      
327m5104            R252  -2          A01X+113615Y+062140X0198Y0197     S1      
327m5104            R251  -2   M      A01X+113615Y+062540X0198Y0197     S1      
317HP_NIC1_PWRGD    VIA   -    M      A01X+031508Y+031489X0200Y         S2      
017HP_NIC1_PWRGD    VIA   -    M      A18X+031508Y+031489X0260Y         S2      
017HP_NIC1_PWRGD          -    MD0100PA00X+031508Y+031489                       
327HP_NIC1_PWRGD    U17   -1          A01X+031943Y+031285X0400Y0500     S1      
327HP_NIC1_PWRGD    R102  -2          A01X+031226Y+031874X0198Y0197R270 S1      
327HP_NIC1_PWRGD    R100  -2   M      A01X+031226Y+031489X0198Y0197R090 S1      
317m5105            VIA   -    MD0080PA01X+076673Y+109764X0160Y    R270 S0      
327m5105            C220  -1          A01X+078358Y+058626X0120Y0150R180 S1      
317m5105            VIA   -    MD0100PA01X+078848Y+058616X0200Y    R090 S0      
327m5105            PEX1  -BC45       A01X+076673Y+109764X0180Y         S1      
317m5106            VIA   -    MD0080PA01X+067697Y+123228X0160Y    R270 S0      
317m5106            VIA   -    MD0100PA01X+047712Y+139658X0180Y         S0      
327m5106            PEX1  -G21        A01X+067697Y+123228X0180Y         S1      
327m5106            C366  -1          A01X+047702Y+140149X0120Y0150R090 S1      
317m5107            VIA   -    MD0080PA01X+115649Y+109390X0160Y    R270 S0      
317m5107            VIA   -    MD0100PA01X+106286Y+040857X0200Y    R270 S0      
327m5107            C482  -1          A01X+106777Y+040867X0120Y0150     S1      
327m5107            PEX2  -BD27       A01X+115650Y+109390X0180Y         S1      
327m5108            C578  -1          A01X+134399Y+137729X0120Y0150R090 S1      
317m5108            VIA   -    MD0100PA01X+134389Y+137238X0180Y         S0      
317m5108            VIA   -    MD0080PA01X+113405Y+123602X0160Y    R270 S0      
327m5108            PEX2  -F21        A01X+113405Y+123602X0180Y         S1      
327HP_NIC4_PWRGD    U32   -1          A01X+116476Y+066991X0400Y0500R180 S1      
327HP_NIC4_PWRGD    VIA   -    M      A01X+113097Y+068969X0300Y         S1      
327HP_NIC4_PWRGD    R255  -2          A01X+112222Y+068969X0198Y0197     S1      
327HP_NIC4_PWRGD    R253  -2   M      A01X+116601Y+067589X0198Y0197     S1      
317m5109            VIA   -    MD0100PA01X+076433Y+136010X0180Y         S0      
317m5109            J5    -T8   D0122PA01X+069020Y+148343X0282Y    R180 S3      
327m5109            C373  -2          A01X+076443Y+135519X0120Y0150R090 S1      
317m5110            VIA   -    MD0080PA01X+074055Y+110138X0160Y    R270 S0      
327m5110            C249  -1          A01X+061068Y+052413X0120Y0150     S1      
317m5110            VIA   -    MD0100PA01X+060578Y+052403X0200Y    R270 S0      
327m5110            PEX1  -BB38       A01X+074055Y+110138X0180Y         S1      
317m5111            VIA   -    MD0080PA01X+063583Y+122854X0160Y         S0      
317m5111            VIA   -    MD0100PA01X+046828Y+134819X0180Y         S0      
327m5111            C345  -1          A01X+046838Y+135309X0120Y0150R090 S1      
327m5111            PEX1  -H10        A01X+063583Y+122854X0180Y         S1      
317m5112            VIA   -    MD0080PA01X+122756Y+110512X0160Y    R090 S0      
327m5112            PEX2  -BA46       A01X+122756Y+110512X0180Y         S1      
317m5112            VIA   -    MD0100PA01X+123517Y+057905X0200Y    R090 S0      
327m5112            C433  -1          A01X+123026Y+057915X0120Y0150R180 S1      
327m5113            C553  -1          A01X+124247Y+137729X0120Y0150R090 S1      
317m5113            VIA   -    MD0100PA01X+124257Y+137238X0180Y         S0      
317m5113            VIA   -    MD0080PA01X+108917Y+123228X0160Y    R270 S0      
327m5113            PEX2  -G9         A01X+108917Y+123228X0180Y         S1      
317m5114            J13   -X6   D0122PA01X+134839Y+146295X0282Y    R180 S3      
317m5114            VIA   -    MD0080PA01X+119390Y+125098X0160Y    R090 S0      
327m5114            PEX2  -B37        A01X+119390Y+125098X0180Y         S1      
327PRSNT_NIC4_N     R245  -1          A01X+113575Y+054580X0198Y0197R180 S1      
317PRSNT_NIC4_N     VIA   -    MD0100PA00X+113917Y+054050X0200Y         S0      
327PRSNT_NIC4_N     R246  -1          A01X+106520Y+037860X0198Y0197     S1      
317PRSNT_NIC4_N     VIA   -    MD0100PA00X+106223Y+037860X0200Y         S0      
317PRSNT_NIC4_N     VIA   -    MD0100PA00X+106235Y+045871X0200Y         S0      
317PRSNT_NIC4_N     VIA   -    M      A01X+113555Y+045580X0200Y         S2      
017PRSNT_NIC4_N     VIA   -    M      A18X+113555Y+045580X0260Y         S2      
017PRSNT_NIC4_N           -    MD0100PA00X+113555Y+045580                       
327PRSNT_NIC4_N     R247  -2          A01X+104141Y+045566X0198Y0197R090 S1      
327PRSNT_NIC4_N     R243  -1   M      A01X+106520Y+045960X0198Y0197     S1      
327PRSNT_NIC4_N     R244  -1          A01X+113555Y+045880X0198Y0197R180 S1      
317m5115            VIA   -    MD0080PA01X+077421Y+109390X0160Y    R270 S0      
327m5115            C225  -1          A01X+078358Y+056849X0120Y0150R180 S1      
317m5115            VIA   -    MD0100PA01X+078848Y+056859X0200Y    R090 S0      
327m5115            PEX1  -BD47       A01X+077421Y+109390X0180Y         S1      
317m5116            VIA   -    MD0080PA01X+062087Y+120236X0160Y         S0      
317m5116            VIA   -    MD0100PA01X+066641Y+139658X0180Y         S0      
327m5116            PEX1  -R6         A01X+062087Y+120236X0180Y         S1      
327m5116            C395  -1          A01X+066651Y+140149X0120Y0150R090 S1      
317m5117            VIA   -    MD0080PA01X+117146Y+109390X0160Y         S0      
317m5117            VIA   -    MD0100PA01X+106286Y+043692X0200Y    R270 S0      
327m5117            C474  -1          A01X+106777Y+043702X0120Y0150     S1      
327m5117            PEX2  -BD31       A01X+117146Y+109390X0180Y         S1      
327m5118            C560  -1          A01X+127055Y+137729X0120Y0150R090 S1      
317m5118            VIA   -    MD0100PA01X+127045Y+137238X0180Y         S0      
317m5118            VIA   -    MD0080PA01X+110039Y+122854X0160Y         S0      
327m5118            PEX2  -H12        A01X+110039Y+122854X0180Y         S1      
317m5119            J7    -P7   D0122PA01X+118382Y+150468X0282Y    R180 S3      
317m5119            VIA   -    MD0080PA01X+107795Y+124350X0160Y         S0      
327m5119            PEX2  -D6         A01X+107795Y+124350X0180Y         S1      
317m5120            VIA   -    MD0080PA01X+073681Y+109390X0160Y    R270 S0      
327m5120            C251  -1          A01X+060028Y+051702X0120Y0150     S1      
317m5120            VIA   -    MD0100PA01X+059538Y+051692X0200Y    R270 S0      
327m5120            PEX1  -BD37       A01X+073681Y+109390X0180Y         S1      
317m5121            VIA   -    MD0080PA01X+068445Y+123602X0160Y    R270 S0      
317m5121            VIA   -    MD0100PA01X+050500Y+134819X0180Y         S0      
327m5121            PEX1  -F23        A01X+068445Y+123602X0180Y         S1      
327m5121            C371  -1          A01X+050510Y+135309X0120Y0150R090 S1      
317m5122            VIA   -    MD0080PA01X+121260Y+110512X0160Y    R270 S0      
327m5122            PEX2  -BA42       A01X+121260Y+110512X0180Y         S1      
327m5122            C425  -1          A01X+123026Y+060750X0120Y0150R180 S1      
317m5122            VIA   -    MD0100PA01X+123517Y+060740X0200Y    R090 S0      
327m5123            C596  -1          A01X+112805Y+137729X0120Y0150R090 S1      
317m5123            VIA   -    MD0100PA01X+112815Y+137238X0180Y         S0      
317m5123            VIA   -    MD0080PA01X+105925Y+122854X0160Y    R270 S0      
327m5123            PEX2  -H1         A01X+105925Y+122854X0180Y         S1      
317m5124            J13   -Y3   D0122PA01X+132240Y+145862X0282Y    R180 S3      
317m5124            VIA   -    MD0080PA01X+118268Y+124350X0160Y         S0      
327m5124            PEX2  -D34        A01X+118268Y+124350X0180Y         S1      
317m5125            VIA   -    MD0080PA01X+075925Y+112756X0160Y    R270 S0      
327m5125            C238  -1          A01X+077317Y+048498X0120Y0150R180 S1      
317m5125            VIA   -    MD0100PA01X+077808Y+048488X0200Y    R090 S0      
327m5125            PEX1  -AR43       A01X+075925Y+112756X0180Y         S1      
317m5126            VIA   -    MD0080PA01X+066575Y+122854X0160Y         S0      
317m5126            VIA   -    MD0100PA01X+045604Y+139658X0180Y         S0      
327m5126            PEX1  -H18        A01X+066575Y+122854X0180Y         S1      
327m5126            C361  -1          A01X+045614Y+140149X0120Y0150R090 S1      
317m5127            VIA   -    MD0080PA01X+123504Y+110138X0160Y    R270 S0      
327m5127            PEX2  -BB48       A01X+123504Y+110138X0180Y         S1      
317m5127            VIA   -    MD0100PA01X+124557Y+053612X0200Y    R090 S0      
327m5127            C439  -1          A01X+124066Y+053622X0120Y0150R180 S1      
327m5128            C569  -1          A01X+130367Y+140149X0120Y0150R090 S1      
317m5128            VIA   -    MD0100PA01X+130377Y+139658X0180Y         S0      
317m5128            VIA   -    MD0080PA01X+111909Y+123228X0160Y    R270 S0      
327m5128            PEX2  -G17        A01X+111909Y+123228X0180Y         S1      
317m5129            J13   -X4   D0122PA01X+133106Y+146295X0282Y    R180 S3      
317m5129            VIA   -    MD0080PA01X+118642Y+125098X0160Y    R090 S0      
327m5129            PEX2  -B35        A01X+118642Y+125098X0180Y         S1      
317m5130            VIA   -    MD0100PA01X+055056Y+138430X0180Y         S0      
317m5130            J12   -R6   D0122PA01X+049965Y+149366X0282Y    R180 S3      
327m5130            C2247 -2          A01X+055046Y+137939X0120Y0150R090 S1      
317m5131            VIA   -    MD0080PA01X+077047Y+110512X0160Y    R090 S0      
327m5131            C222  -1          A01X+077317Y+057915X0120Y0150R180 S1      
317m5131            VIA   -    MD0100PA01X+077808Y+057905X0200Y    R090 S0      
327m5131            PEX1  -BA46       A01X+077047Y+110512X0180Y         S1      
317m5132            VIA   -    MD0080PA01X+065079Y+122854X0160Y         S0      
317m5132            VIA   -    MD0100PA01X+049276Y+139658X0180Y         S0      
327m5132            C353  -1          A01X+049286Y+140149X0120Y0150R090 S1      
327m5132            PEX1  -H14        A01X+065079Y+122854X0180Y         S1      
317m5133            VIA   -    MD0080PA01X+121260Y+110138X0160Y    R270 S0      
327m5133            PEX2  -BB42       A01X+121260Y+110138X0180Y         S1      
327m5133            C426  -1          A01X+123026Y+060390X0120Y0150R180 S1      
317m5133            VIA   -    MD0100PA01X+123517Y+060400X0200Y    R090 S0      
327m5134            C590  -1          A01X+115613Y+137729X0120Y0150R090 S1      
317m5134            VIA   -    MD0100PA01X+115603Y+137238X0180Y         S0      
317m5134            VIA   -    MD0080PA01X+107047Y+122854X0160Y         S0      
327m5134            PEX2  -H4         A01X+107047Y+122854X0180Y         S1      
317m5135            J13   -X2   D0122PA01X+131374Y+146295X0282Y    R180 S3      
317m5135            VIA   -    MD0080PA01X+117894Y+125098X0160Y    R090 S0      
327m5135            PEX2  -B33        A01X+117894Y+125098X0180Y         S1      
317m5136            VIA   -    MD0080PA01X+075925Y+113504X0160Y    R270 S0      
327m5136            C242  -1          A01X+077317Y+047081X0120Y0150R180 S1      
317m5136            VIA   -    MD0100PA01X+077808Y+047071X0200Y    R090 S0      
327m5136            PEX1  -AN43       A01X+075925Y+113504X0180Y         S1      
317m5137            VIA   -    MD0080PA01X+068071Y+122480X0160Y         S0      
317m5137            VIA   -    MD0100PA01X+048936Y+137238X0180Y         S0      
327m5137            PEX1  -J22        A01X+068071Y+122480X0180Y         S1      
327m5137            C368  -1          A01X+048926Y+137729X0120Y0150R090 S1      
317m5138            VIA   -    MD0080PA01X+120512Y+110512X0160Y    R270 S0      
327m5138            C455  -1          A01X+106777Y+053471X0120Y0150     S1      
317m5138            VIA   -    MD0100PA01X+106286Y+053481X0200Y    R270 S0      
327m5138            PEX2  -BA40       A01X+120512Y+110512X0180Y         S1      
317m5139            VIA   -    MD0080PA01X+072933Y+109390X0160Y    R270 S0      
327m5139            C255  -1          A01X+060028Y+048706X0120Y0150     S1      
317m5139            VIA   -    MD0100PA01X+059538Y+048696X0200Y    R270 S0      
327m5139            PEX1  -BD35       A01X+072933Y+109390X0180Y         S1      
317m5140            VIA   -    MD0080PA01X+060590Y+123976X0160Y         S0      
317m5140            VIA   -    MD0100PA01X+071537Y+139658X0180Y         S0      
327m5140            C382  -1          A01X+071547Y+140149X0120Y0150R090 S1      
327m5140            PEX1  -E2         A01X+060590Y+123976X0180Y         S1      
317m5141            VIA   -    MD0080PA01X+123130Y+109390X0160Y    R270 S0      
327m5141            PEX2  -BD47       A01X+123130Y+109390X0180Y         S1      
317m5141            VIA   -    MD0100PA01X+124557Y+056859X0200Y    R090 S0      
327m5141            C436  -1          A01X+124066Y+056849X0120Y0150R180 S1      
317m5142            VIA   -    MD0100PA01X+073985Y+140840X0180Y         S0      
317m5142            J5    -T6   D0122PA01X+067287Y+148343X0282Y    R180 S3      
327m5142            C377  -2          A01X+073995Y+140350X0120Y0150R090 S1      
317m5143            VIA   -    MD0080PA01X+076299Y+112008X0160Y    R270 S0      
327m5143            C235  -1          A01X+077317Y+051134X0120Y0150R180 S1      
317m5143            VIA   -    MD0100PA01X+077808Y+051144X0200Y    R090 S0      
327m5143            PEX1  -AU44       A01X+076299Y+112008X0180Y         S1      
317m5144            VIA   -    MD0080PA01X+064331Y+122854X0160Y         S0      
317m5144            VIA   -    MD0100PA01X+048052Y+137238X0180Y         S0      
327m5144            C349  -1          A01X+048062Y+137729X0120Y0150R090 S1      
327m5144            PEX1  -H12        A01X+064331Y+122854X0180Y         S1      
317m5145            VIA   -    MD0080PA01X+121634Y+112756X0160Y    R270 S0      
327m5145            PEX2  -AR43       A01X+121634Y+112756X0180Y         S1      
317m5145            VIA   -    MD0100PA01X+123517Y+048488X0200Y    R090 S0      
327m5145            C449  -1          A01X+123026Y+048498X0120Y0150R180 S1      
317P12V_AUX         VIA   -    MD0080PA00X+042222Y+044463X0160Y    R180 S0      
317P12V_AUX         VIA   -    MD0080PA00X+042502Y+044463X0160Y    R180 S0      
317P12V_AUX         VIA   -    MD0080PA00X+042222Y+043754X0160Y    R180 S0      
317P12V_AUX         VIA   -    MD0080PA00X+042222Y+043400X0160Y    R180 S0      
317P12V_AUX         VIA   -    MD0080PA00X+042222Y+044109X0160Y    R180 S0      
317P12V_AUX         VIA   -    MD0080PA00X+042502Y+043754X0160Y    R180 S0      
317P12V_AUX         VIA   -    MD0080PA00X+042502Y+043400X0160Y    R180 S0      
317P12V_AUX         VIA   -    MD0080PA00X+042502Y+044109X0160Y    R180 S0      
317P12V_AUX         VIA   -    MD0080PA00X+091755Y+046097X0160Y    R180 S0      
317P12V_AUX         VIA   -    MD0080PA00X+092035Y+046097X0160Y    R180 S0      
317P12V_AUX         VIA   -    MD0080PA00X+091755Y+045743X0160Y    R180 S0      
317P12V_AUX         VIA   -    MD0080PA00X+091755Y+045388X0160Y    R180 S0      
317P12V_AUX         VIA   -    MD0080PA00X+092035Y+045743X0160Y    R180 S0      
317P12V_AUX         VIA   -    MD0080PA00X+092035Y+045388X0160Y    R180 S0      
317P12V_AUX         VIA   -    MD0080PA00X+091755Y+045034X0160Y    R180 S0      
317P12V_AUX         VIA   -    MD0080PA00X+092035Y+045034X0160Y    R180 S0      
317P12V_AUX         VIA   -    MD0080PA00X+133640Y+044463X0160Y    R180 S0      
317P12V_AUX         VIA   -    MD0080PA00X+133920Y+044463X0160Y    R180 S0      
317P12V_AUX         VIA   -    MD0080PA00X+133640Y+043754X0160Y    R180 S0      
317P12V_AUX         VIA   -    MD0080PA00X+133640Y+043400X0160Y    R180 S0      
317P12V_AUX         VIA   -    MD0080PA00X+133640Y+044109X0160Y    R180 S0      
317P12V_AUX         VIA   -    MD0080PA00X+133920Y+043754X0160Y    R180 S0      
317P12V_AUX         VIA   -    MD0080PA00X+133920Y+043400X0160Y    R180 S0      
317P12V_AUX         VIA   -    MD0080PA00X+133920Y+044109X0160Y    R180 S0      
317P12V_AUX         VIA   -    MD0080PA00X+179348Y+044463X0160Y    R180 S0      
317P12V_AUX         VIA   -    MD0080PA00X+179628Y+044463X0160Y    R180 S0      
317P12V_AUX         VIA   -    MD0080PA00X+179348Y+043754X0160Y    R180 S0      
317P12V_AUX         VIA   -    MD0080PA00X+179348Y+043400X0160Y    R180 S0      
317P12V_AUX         VIA   -    MD0080PA00X+179348Y+044109X0160Y    R180 S0      
317P12V_AUX         VIA   -    MD0080PA00X+179628Y+043754X0160Y    R180 S0      
317P12V_AUX         VIA   -    MD0080PA00X+179628Y+043400X0160Y    R180 S0      
317P12V_AUX         VIA   -    MD0080PA00X+179628Y+044109X0160Y    R180 S0      
317P12V_AUX         VIA   -    MD0080PA00X+004466Y+062066X0160Y    R270 S0      
317P12V_AUX         VIA   -    MD0080PA00X+004821Y+062066X0160Y    R270 S0      
317P12V_AUX         VIA   -    MD0080PA00X+005175Y+062066X0160Y    R270 S0      
317P12V_AUX         VIA   -    MD0080PA00X+004466Y+061786X0160Y    R270 S0      
317P12V_AUX         VIA   -    MD0080PA00X+004821Y+061786X0160Y    R270 S0      
317P12V_AUX         VIA   -    MD0080PA00X+005175Y+061786X0160Y    R270 S0      
317P12V_AUX         VIA   -    MD0080PA00X+005529Y+062066X0160Y    R270 S0      
317P12V_AUX         VIA   -    MD0080PA00X+005529Y+061786X0160Y    R270 S0      
317P12V_AUX         VIA   -    MD0080PA00X+050529Y+061786X0160Y    R270 S0      
317P12V_AUX         VIA   -    MD0080PA00X+050175Y+061786X0160Y    R270 S0      
317P12V_AUX         VIA   -    MD0080PA00X+050529Y+062066X0160Y    R270 S0      
317P12V_AUX         VIA   -    MD0080PA00X+050175Y+062066X0160Y    R270 S0      
317P12V_AUX         VIA   -    MD0080PA00X+051238Y+062066X0160Y    R270 S0      
317P12V_AUX         VIA   -    MD0080PA00X+050884Y+061786X0160Y    R270 S0      
317P12V_AUX         VIA   -    MD0080PA00X+050884Y+062066X0160Y    R270 S0      
317P12V_AUX         VIA   -    MD0080PA00X+051238Y+061786X0160Y    R270 S0      
317P12V_AUX         VIA   -    MD0080PA00X+095884Y+062066X0160Y    R270 S0      
317P12V_AUX         VIA   -    MD0080PA00X+096238Y+062066X0160Y    R270 S0      
317P12V_AUX         VIA   -    MD0080PA00X+095884Y+061786X0160Y    R270 S0      
317P12V_AUX         VIA   -    MD0080PA00X+096238Y+061786X0160Y    R270 S0      
317P12V_AUX         VIA   -    MD0080PA00X+096947Y+061786X0160Y    R270 S0      
317P12V_AUX         VIA   -    MD0080PA00X+096592Y+062066X0160Y    R270 S0      
317P12V_AUX         VIA   -    MD0080PA00X+096592Y+061786X0160Y    R270 S0      
317P12V_AUX         VIA   -    MD0080PA00X+096947Y+062066X0160Y    R270 S0      
317P12V_AUX         VIA   -    MD0080PA00X+141592Y+061786X0160Y    R270 S0      
317P12V_AUX         VIA   -    MD0080PA00X+141592Y+062066X0160Y    R270 S0      
317P12V_AUX         VIA   -    MD0080PA00X+141947Y+062066X0160Y    R270 S0      
317P12V_AUX         VIA   -    MD0080PA00X+142655Y+061786X0160Y    R270 S0      
317P12V_AUX         VIA   -    MD0080PA00X+142655Y+062066X0160Y    R270 S0      
317P12V_AUX         VIA   -    MD0080PA00X+142301Y+061786X0160Y    R270 S0      
317P12V_AUX         VIA   -    MD0080PA00X+141947Y+061786X0160Y    R270 S0      
317P12V_AUX         VIA   -    MD0080PA00X+142301Y+062066X0160Y    R270 S0      
317P12V_AUX         VIA   -    MD0100PA00X+075519Y+158082X0200Y         S0      
327P12V_AUX         R6825 -1          A01X+075519Y+158375X0198Y0197R090 S1      
327P12V_AUX         PC984 -1          A01X+133186Y+105779X0198Y0197R270 S1      
327P12V_AUX         PC985 -1          A01X+142013Y+105808X0198Y0197R270 S1      
327P12V_AUX         PL11  -2          A01X+132514Y+106430X0420Y0990R270 S1      
327P12V_AUX         PL14  -2          A01X+141327Y+106430X0420Y0990R270 S1      
327P12V_AUX         PC982 -1          A01X+041768Y+105779X0198Y0197R270 S1      
327P12V_AUX         PR97  -1          A18X+045059Y+100719X0198Y0197R270 S2      
327P12V_AUX         PR146 -1          A18X+136476Y+100719X0198Y0197R270 S2      
327P12V_AUX         PC983 -1          A01X+050596Y+105808X0198Y0197R270 S1      
327P12V_AUX         PL8   -2          A01X+049910Y+106430X0420Y0990R270 S1      
327P12V_AUX         PL5   -2          A01X+041097Y+106430X0420Y0990R270 S1      
317P12V_AUX         VIA   -    MD0100PA00X+050068Y+106070X0200Y    R180 S0      
317P12V_AUX         VIA   -    MD0100PA00X+049818Y+106070X0200Y    R180 S0      
317P12V_AUX         VIA   -    MD0100PA00X+049318Y+106070X0200Y    R180 S0      
317P12V_AUX         VIA   -    MD0100PA00X+049568Y+106070X0200Y    R180 S0      
317P12V_AUX         VIA   -    MD0100PA00X+050318Y+106070X0200Y    R180 S0      
317P12V_AUX         VIA   -    MD0100PA00X+050068Y+105810X0200Y    R180 S0      
317P12V_AUX         VIA   -    MD0100PA00X+049818Y+105810X0200Y    R180 S0      
317P12V_AUX         VIA   -    MD0100PA00X+049318Y+105810X0200Y    R180 S0      
317P12V_AUX         VIA   -    MD0100PA00X+049568Y+105810X0200Y    R180 S0      
317P12V_AUX         VIA   -    MD0100PA00X+050318Y+105810X0200Y    R180 S0      
317P12V_AUX         VIA   -    MD0100PA00X+041255Y+106070X0200Y    R180 S0      
317P12V_AUX         VIA   -    MD0100PA00X+041505Y+106070X0200Y    R180 S0      
317P12V_AUX         VIA   -    MD0100PA00X+041255Y+105810X0200Y    R180 S0      
317P12V_AUX         VIA   -    MD0100PA00X+041505Y+105810X0200Y    R180 S0      
317P12V_AUX         VIA   -    MD0100PA00X+040505Y+106070X0200Y    R180 S0      
317P12V_AUX         VIA   -    MD0100PA00X+041005Y+106070X0200Y    R180 S0      
317P12V_AUX         VIA   -    MD0100PA00X+040755Y+106070X0200Y    R180 S0      
317P12V_AUX         VIA   -    MD0100PA00X+040505Y+105810X0200Y    R180 S0      
317P12V_AUX         VIA   -    MD0100PA00X+041005Y+105810X0200Y    R180 S0      
317P12V_AUX         VIA   -    MD0100PA00X+040755Y+105810X0200Y    R180 S0      
317P12V_AUX         VIA   -    MD0100PA00X+132422Y+106070X0200Y    R180 S0      
317P12V_AUX         VIA   -    MD0100PA00X+132172Y+106070X0200Y    R180 S0      
317P12V_AUX         VIA   -    MD0100PA00X+132922Y+106070X0200Y    R180 S0      
317P12V_AUX         VIA   -    MD0100PA00X+132672Y+106070X0200Y    R180 S0      
317P12V_AUX         VIA   -    MD0100PA00X+132672Y+105810X0200Y    R180 S0      
317P12V_AUX         VIA   -    MD0100PA00X+132422Y+105810X0200Y    R180 S0      
317P12V_AUX         VIA   -    MD0100PA00X+132172Y+105810X0200Y    R180 S0      
317P12V_AUX         VIA   -    MD0100PA00X+132922Y+105810X0200Y    R180 S0      
317P12V_AUX         VIA   -    MD0100PA00X+131922Y+106070X0200Y    R180 S0      
317P12V_AUX         VIA   -    MD0100PA00X+131922Y+105810X0200Y    R180 S0      
317P12V_AUX         VIA   -    MD0100PA00X+141735Y+106070X0200Y    R180 S0      
317P12V_AUX         VIA   -    MD0100PA00X+140985Y+106070X0200Y    R180 S0      
317P12V_AUX         VIA   -    MD0100PA00X+140735Y+106070X0200Y    R180 S0      
317P12V_AUX         VIA   -    MD0100PA00X+141235Y+106070X0200Y    R180 S0      
317P12V_AUX         VIA   -    MD0100PA00X+141485Y+106070X0200Y    R180 S0      
317P12V_AUX         VIA   -    MD0100PA00X+141735Y+105810X0200Y    R180 S0      
317P12V_AUX         VIA   -    MD0100PA00X+140985Y+105810X0200Y    R180 S0      
317P12V_AUX         VIA   -    MD0100PA00X+140735Y+105810X0200Y    R180 S0      
317P12V_AUX         VIA   -    MD0100PA00X+141235Y+105810X0200Y    R180 S0      
317P12V_AUX         VIA   -    MD0100PA00X+141485Y+105810X0200Y    R180 S0      
317P12V_AUX         VIA   -    MD0100PA00X+104920Y+133738X0200Y         S0      
327P12V_AUX         U448  -5          A01X+104292Y+132309X0240Y0420R270 S1      
327P12V_AUX         C4484 -1   M      A01X+104836Y+132361X0198Y0197     S1      
317P12V_AUX         VIA   -    MD0100PA00X+077804Y+161940X0200Y         S0      
327P12V_AUX         U443  -5          A01X+076652Y+162246X0240Y0420R180 S1      
327P12V_AUX         C4479 -1   M      A01X+077484Y+161940X0198Y0197R090 S1      
317P12V_AUX         VIA   -    MD0100PA00X+074333Y+162787X0200Y         S0      
327P12V_AUX         PU22  -13         A01X+004423Y+053944X0780Y1070R180 S1      
327P12V_AUX         PU22  -12         A01X+003832Y+053452X0110Y0240R090 S1      
327P12V_AUX         PU24  -13         A01X+038438Y+038964X0780Y1070R270 S1      
327P12V_AUX         PU24  -12         A01X+038930Y+038373X0110Y0240R180 S1      
327P12V_AUX         PU26  -13         A01X+050132Y+053944X0780Y1070R180 S1      
327P12V_AUX         PU26  -12         A01X+049541Y+053452X0110Y0240R090 S1      
327P12V_AUX         PU28  -13         A01X+087971Y+040298X0780Y1070R270 S1      
327P12V_AUX         PU28  -12         A01X+088463Y+039707X0110Y0240R180 S1      
327P12V_AUX         PU23  -13         A01X+095840Y+053944X0780Y1070R180 S1      
327P12V_AUX         PU23  -12         A01X+095250Y+053452X0110Y0240R090 S1      
327P12V_AUX         PU25  -13         A01X+129856Y+038964X0780Y1070R270 S1      
327P12V_AUX         PU25  -12         A01X+130348Y+038373X0110Y0240R180 S1      
327P12V_AUX         PU27  -13         A01X+141549Y+053944X0780Y1070R180 S1      
327P12V_AUX         PU27  -12         A01X+140958Y+053452X0110Y0240R090 S1      
327P12V_AUX         PU29  -13         A01X+175564Y+038964X0780Y1070R270 S1      
327P12V_AUX         PU29  -12         A01X+176056Y+038373X0110Y0240R180 S1      
327P12V_AUX         PU30  -13         A01X+008916Y+021415X0780Y1070     S1      
327P12V_AUX         PU30  -12         A01X+009507Y+021907X0110Y0240R270 S1      
327P12V_AUX         PU32  -13         A01X+019152Y+021415X0780Y1070     S1      
327P12V_AUX         PU32  -12         A01X+019743Y+021907X0110Y0240R270 S1      
327P12V_AUX         PU34  -13         A01X+029389Y+021415X0780Y1070     S1      
327P12V_AUX         PU34  -12         A01X+029979Y+021907X0110Y0240R270 S1      
327P12V_AUX         PU36  -13         A01X+039625Y+021415X0780Y1070     S1      
327P12V_AUX         PU36  -12         A01X+040215Y+021907X0110Y0240R270 S1      
327P12V_AUX         PU31  -13         A01X+054625Y+021415X0780Y1070     S1      
327P12V_AUX         PU31  -12         A01X+055216Y+021907X0110Y0240R270 S1      
327P12V_AUX         PU33  -13         A01X+064861Y+021415X0780Y1070     S1      
327P12V_AUX         PU33  -12         A01X+065452Y+021907X0110Y0240R270 S1      
327P12V_AUX         PU35  -13         A01X+075097Y+021415X0780Y1070     S1      
327P12V_AUX         PU35  -12         A01X+075688Y+021907X0110Y0240R270 S1      
327P12V_AUX         PU37  -13         A01X+085334Y+021415X0780Y1070     S1      
327P12V_AUX         PU37  -12         A01X+085924Y+021907X0110Y0240R270 S1      
327P12V_AUX         PU38  -13         A01X+100334Y+021415X0780Y1070     S1      
327P12V_AUX         PU39  -13         A01X+146042Y+021415X0780Y1070     S1      
327P12V_AUX         PU38  -12         A01X+100924Y+021907X0110Y0240R270 S1      
327P12V_AUX         PU39  -12         A01X+146633Y+021907X0110Y0240R270 S1      
327P12V_AUX         PU40  -13         A01X+110570Y+021415X0780Y1070     S1      
327P12V_AUX         PU41  -13         A01X+156278Y+021415X0780Y1070     S1      
327P12V_AUX         PU40  -12         A01X+111160Y+021907X0110Y0240R270 S1      
327P12V_AUX         PU41  -12         A01X+156869Y+021907X0110Y0240R270 S1      
327P12V_AUX         PU42  -13         A01X+120806Y+021415X0780Y1070     S1      
327P12V_AUX         PU43  -13         A01X+166515Y+021415X0780Y1070     S1      
327P12V_AUX         PU42  -12         A01X+121396Y+021907X0110Y0240R270 S1      
327P12V_AUX         PU43  -12         A01X+167105Y+021907X0110Y0240R270 S1      
327P12V_AUX         PU44  -13         A01X+131042Y+021415X0780Y1070     S1      
327P12V_AUX         PU45  -13         A01X+176751Y+021415X0780Y1070     S1      
327P12V_AUX         PU44  -12         A01X+131633Y+021907X0110Y0240R270 S1      
327P12V_AUX         PU45  -12         A01X+177341Y+021907X0110Y0240R270 S1      
317P12V_AUX         VIA   -    MD0100PA00X+104187Y+144021X0200Y    R090 S0      
317P12V_AUX         VIA   -    MD0100PA00X+104487Y+144021X0200Y    R090 S0      
317P12V_AUX         VIA   -    MD0100PA00X+104187Y+143721X0200Y    R090 S0      
317P12V_AUX         VIA   -    MD0100PA00X+104487Y+143721X0200Y    R090 S0      
317P12V_AUX         VIA   -    MD0100PA00X+104187Y+143421X0200Y    R090 S0      
317P12V_AUX         VIA   -    MD0100PA00X+104187Y+142821X0200Y    R090 S0      
317P12V_AUX         VIA   -    MD0100PA00X+104187Y+143121X0200Y    R090 S0      
317P12V_AUX         VIA   -    MD0100PA00X+104487Y+143121X0200Y    R090 S0      
317P12V_AUX         VIA   -    MD0100PA00X+104487Y+142821X0200Y    R090 S0      
317P12V_AUX         VIA   -    MD0100PA00X+104487Y+143421X0200Y    R090 S0      
317P12V_AUX         VIA   -    MD0100PA00X+103887Y+144021X0200Y    R090 S0      
317P12V_AUX         VIA   -    MD0100PA00X+103887Y+143721X0200Y    R090 S0      
317P12V_AUX         VIA   -    MD0100PA00X+103587Y+144021X0200Y    R090 S0      
317P12V_AUX         VIA   -    MD0100PA00X+103587Y+143721X0200Y    R090 S0      
317P12V_AUX         VIA   -    MD0100PA00X+102987Y+144021X0200Y    R090 S0      
317P12V_AUX         VIA   -    MD0100PA00X+103287Y+144021X0200Y    R090 S0      
317P12V_AUX         VIA   -    MD0100PA00X+102987Y+143721X0200Y    R090 S0      
317P12V_AUX         VIA   -    MD0100PA00X+103287Y+143721X0200Y    R090 S0      
317P12V_AUX         VIA   -    MD0100PA00X+103887Y+143421X0200Y    R090 S0      
317P12V_AUX         VIA   -    MD0100PA00X+103887Y+143121X0200Y    R090 S0      
317P12V_AUX         VIA   -    MD0100PA00X+103887Y+142821X0200Y    R090 S0      
317P12V_AUX         VIA   -    MD0100PA00X+103587Y+143421X0200Y    R090 S0      
317P12V_AUX         VIA   -    MD0100PA00X+102987Y+143421X0200Y    R090 S0      
317P12V_AUX         VIA   -    MD0100PA00X+103287Y+143421X0200Y    R090 S0      
317P12V_AUX         VIA   -    MD0100PA00X+102987Y+143121X0200Y    R090 S0      
317P12V_AUX         VIA   -    MD0100PA00X+103587Y+142821X0200Y    R090 S0      
317P12V_AUX         VIA   -    MD0100PA00X+103587Y+143121X0200Y    R090 S0      
317P12V_AUX         VIA   -    MD0100PA00X+102987Y+142821X0200Y    R090 S0      
317P12V_AUX         VIA   -    MD0100PA00X+103287Y+142821X0200Y    R090 S0      
317P12V_AUX         VIA   -    MD0100PA00X+103287Y+143121X0200Y    R090 S0      
317P12V_AUX         VIA   -    MD0100PA00X+101898Y+144010X0200Y    R090 S0      
317P12V_AUX         VIA   -    MD0100PA00X+102198Y+144010X0200Y    R090 S0      
317P12V_AUX         VIA   -    MD0100PA00X+101898Y+143710X0200Y    R090 S0      
317P12V_AUX         VIA   -    MD0100PA00X+102198Y+143710X0200Y    R090 S0      
317P12V_AUX         VIA   -    MD0100PA00X+101898Y+143410X0200Y    R090 S0      
317P12V_AUX         VIA   -    MD0100PA00X+101898Y+142810X0200Y    R090 S0      
317P12V_AUX         VIA   -    MD0100PA00X+101898Y+143110X0200Y    R090 S0      
317P12V_AUX         VIA   -    MD0100PA00X+102198Y+143110X0200Y    R090 S0      
317P12V_AUX         VIA   -    MD0100PA00X+102198Y+142810X0200Y    R090 S0      
317P12V_AUX         VIA   -    MD0100PA00X+102198Y+143410X0200Y    R090 S0      
317P12V_AUX         VIA   -    MD0100PA00X+101598Y+144010X0200Y    R090 S0      
317P12V_AUX         VIA   -    MD0100PA00X+101598Y+143710X0200Y    R090 S0      
317P12V_AUX         VIA   -    MD0100PA00X+101298Y+144010X0200Y    R090 S0      
317P12V_AUX         VIA   -    MD0100PA00X+101298Y+143710X0200Y    R090 S0      
317P12V_AUX         VIA   -    MD0100PA00X+100698Y+144010X0200Y    R090 S0      
317P12V_AUX         VIA   -    MD0100PA00X+100998Y+144010X0200Y    R090 S0      
317P12V_AUX         VIA   -    MD0100PA00X+100698Y+143710X0200Y    R090 S0      
317P12V_AUX         VIA   -    MD0100PA00X+100998Y+143710X0200Y    R090 S0      
317P12V_AUX         VIA   -    MD0100PA00X+101598Y+143410X0200Y    R090 S0      
317P12V_AUX         VIA   -    MD0100PA00X+101598Y+143110X0200Y    R090 S0      
317P12V_AUX         VIA   -    MD0100PA00X+101598Y+142810X0200Y    R090 S0      
317P12V_AUX         VIA   -    MD0100PA00X+101298Y+143410X0200Y    R090 S0      
317P12V_AUX         VIA   -    MD0100PA00X+100698Y+143410X0200Y    R090 S0      
317P12V_AUX         VIA   -    MD0100PA00X+100998Y+143410X0200Y    R090 S0      
317P12V_AUX         VIA   -    MD0100PA00X+100698Y+143110X0200Y    R090 S0      
317P12V_AUX         VIA   -    MD0100PA00X+101298Y+142810X0200Y    R090 S0      
317P12V_AUX         VIA   -    MD0100PA00X+101298Y+143110X0200Y    R090 S0      
317P12V_AUX         VIA   -    MD0100PA00X+100698Y+142810X0200Y    R090 S0      
317P12V_AUX         VIA   -    MD0100PA00X+100998Y+142810X0200Y    R090 S0      
317P12V_AUX         VIA   -    MD0100PA00X+100998Y+143110X0200Y    R090 S0      
317P12V_AUX         VIA   -    MD0100PA00X+099595Y+144000X0200Y    R090 S0      
317P12V_AUX         VIA   -    MD0100PA00X+099895Y+144000X0200Y    R090 S0      
317P12V_AUX         VIA   -    MD0100PA00X+099595Y+143700X0200Y    R090 S0      
317P12V_AUX         VIA   -    MD0100PA00X+099895Y+143700X0200Y    R090 S0      
317P12V_AUX         VIA   -    MD0100PA00X+099595Y+143400X0200Y    R090 S0      
317P12V_AUX         VIA   -    MD0100PA00X+099595Y+142800X0200Y    R090 S0      
317P12V_AUX         VIA   -    MD0100PA00X+099595Y+143100X0200Y    R090 S0      
317P12V_AUX         VIA   -    MD0100PA00X+099895Y+143100X0200Y    R090 S0      
317P12V_AUX         VIA   -    MD0100PA00X+099895Y+142800X0200Y    R090 S0      
317P12V_AUX         VIA   -    MD0100PA00X+099895Y+143400X0200Y    R090 S0      
317P12V_AUX         VIA   -    MD0100PA00X+099295Y+144000X0200Y    R090 S0      
317P12V_AUX         VIA   -    MD0100PA00X+099295Y+143700X0200Y    R090 S0      
317P12V_AUX         VIA   -    MD0100PA00X+098995Y+144000X0200Y    R090 S0      
317P12V_AUX         VIA   -    MD0100PA00X+098995Y+143700X0200Y    R090 S0      
317P12V_AUX         VIA   -    MD0100PA00X+098395Y+144000X0200Y    R090 S0      
317P12V_AUX         VIA   -    MD0100PA00X+098695Y+144000X0200Y    R090 S0      
317P12V_AUX         VIA   -    MD0100PA00X+098395Y+143700X0200Y    R090 S0      
317P12V_AUX         VIA   -    MD0100PA00X+098695Y+143700X0200Y    R090 S0      
317P12V_AUX         VIA   -    MD0100PA00X+099295Y+143400X0200Y    R090 S0      
317P12V_AUX         VIA   -    MD0100PA00X+099295Y+143100X0200Y    R090 S0      
317P12V_AUX         VIA   -    MD0100PA00X+099295Y+142800X0200Y    R090 S0      
317P12V_AUX         VIA   -    MD0100PA00X+098995Y+143400X0200Y    R090 S0      
317P12V_AUX         VIA   -    MD0100PA00X+098395Y+143400X0200Y    R090 S0      
317P12V_AUX         VIA   -    MD0100PA00X+098695Y+143400X0200Y    R090 S0      
317P12V_AUX         VIA   -    MD0100PA00X+098395Y+143100X0200Y    R090 S0      
317P12V_AUX         VIA   -    MD0100PA00X+098995Y+142800X0200Y    R090 S0      
317P12V_AUX         VIA   -    MD0100PA00X+098995Y+143100X0200Y    R090 S0      
317P12V_AUX         VIA   -    MD0100PA00X+098395Y+142800X0200Y    R090 S0      
317P12V_AUX         VIA   -    MD0100PA00X+098695Y+142800X0200Y    R090 S0      
317P12V_AUX         VIA   -    MD0100PA00X+098695Y+143100X0200Y    R090 S0      
317P12V_AUX         VIA   -    MD0100PA00X+097288Y+144000X0200Y    R090 S0      
317P12V_AUX         VIA   -    MD0100PA00X+097588Y+144000X0200Y    R090 S0      
317P12V_AUX         VIA   -    MD0100PA00X+097288Y+143700X0200Y    R090 S0      
317P12V_AUX         VIA   -    MD0100PA00X+097588Y+143700X0200Y    R090 S0      
317P12V_AUX         VIA   -    MD0100PA00X+097288Y+143400X0200Y    R090 S0      
317P12V_AUX         VIA   -    MD0100PA00X+097288Y+142800X0200Y    R090 S0      
317P12V_AUX         VIA   -    MD0100PA00X+097288Y+143100X0200Y    R090 S0      
317P12V_AUX         VIA   -    MD0100PA00X+097588Y+143100X0200Y    R090 S0      
317P12V_AUX         VIA   -    MD0100PA00X+097588Y+142800X0200Y    R090 S0      
317P12V_AUX         VIA   -    MD0100PA00X+097588Y+143400X0200Y    R090 S0      
317P12V_AUX         VIA   -    MD0100PA00X+096988Y+144000X0200Y    R090 S0      
317P12V_AUX         VIA   -    MD0100PA00X+096988Y+143700X0200Y    R090 S0      
317P12V_AUX         VIA   -    MD0100PA00X+096688Y+144000X0200Y    R090 S0      
317P12V_AUX         VIA   -    MD0100PA00X+096688Y+143700X0200Y    R090 S0      
317P12V_AUX         VIA   -    MD0100PA00X+096088Y+144000X0200Y    R090 S0      
317P12V_AUX         VIA   -    MD0100PA00X+096388Y+144000X0200Y    R090 S0      
317P12V_AUX         VIA   -    MD0100PA00X+096088Y+143700X0200Y    R090 S0      
317P12V_AUX         VIA   -    MD0100PA00X+096388Y+143700X0200Y    R090 S0      
317P12V_AUX         VIA   -    MD0100PA00X+096988Y+143400X0200Y    R090 S0      
317P12V_AUX         VIA   -    MD0100PA00X+096988Y+143100X0200Y    R090 S0      
317P12V_AUX         VIA   -    MD0100PA00X+096988Y+142800X0200Y    R090 S0      
317P12V_AUX         VIA   -    MD0100PA00X+096688Y+143400X0200Y    R090 S0      
317P12V_AUX         VIA   -    MD0100PA00X+096088Y+143400X0200Y    R090 S0      
317P12V_AUX         VIA   -    MD0100PA00X+096388Y+143400X0200Y    R090 S0      
317P12V_AUX         VIA   -    MD0100PA00X+096088Y+143100X0200Y    R090 S0      
317P12V_AUX         VIA   -    MD0100PA00X+096688Y+142800X0200Y    R090 S0      
317P12V_AUX         VIA   -    MD0100PA00X+096688Y+143100X0200Y    R090 S0      
317P12V_AUX         VIA   -    MD0100PA00X+096088Y+142800X0200Y    R090 S0      
317P12V_AUX         VIA   -    MD0100PA00X+096388Y+142800X0200Y    R090 S0      
317P12V_AUX         VIA   -    MD0100PA00X+096388Y+143100X0200Y    R090 S0      
317P12V_AUX         VIA   -    MD0100PA00X+093772Y+143074X0200Y    R090 S0      
317P12V_AUX         VIA   -    MD0100PA00X+093772Y+142774X0200Y    R090 S0      
317P12V_AUX         VIA   -    MD0100PA00X+093472Y+142774X0200Y    R090 S0      
317P12V_AUX         VIA   -    MD0100PA00X+094072Y+143074X0200Y    R090 S0      
317P12V_AUX         VIA   -    MD0100PA00X+094072Y+142774X0200Y    R090 S0      
317P12V_AUX         VIA   -    MD0100PA00X+093772Y+143674X0200Y    R090 S0      
317P12V_AUX         VIA   -    MD0100PA00X+093472Y+143674X0200Y    R090 S0      
317P12V_AUX         VIA   -    MD0100PA00X+093772Y+143974X0200Y    R090 S0      
317P12V_AUX         VIA   -    MD0100PA00X+093472Y+143974X0200Y    R090 S0      
317P12V_AUX         VIA   -    MD0100PA00X+093472Y+143074X0200Y    R090 S0      
317P12V_AUX         VIA   -    MD0100PA00X+093772Y+143374X0200Y    R090 S0      
317P12V_AUX         VIA   -    MD0100PA00X+093472Y+143374X0200Y    R090 S0      
317P12V_AUX         VIA   -    MD0100PA00X+094072Y+143674X0200Y    R090 S0      
317P12V_AUX         VIA   -    MD0100PA00X+094072Y+143974X0200Y    R090 S0      
317P12V_AUX         VIA   -    MD0100PA00X+094072Y+143374X0200Y    R090 S0      
317P12V_AUX         VIA   -    MD0100PA00X+094372Y+142774X0200Y    R090 S0      
317P12V_AUX         VIA   -    MD0100PA00X+094972Y+143674X0200Y    R090 S0      
317P12V_AUX         VIA   -    MD0100PA00X+094672Y+143674X0200Y    R090 S0      
317P12V_AUX         VIA   -    MD0100PA00X+094372Y+143674X0200Y    R090 S0      
317P12V_AUX         VIA   -    MD0100PA00X+094972Y+143974X0200Y    R090 S0      
317P12V_AUX         VIA   -    MD0100PA00X+094672Y+143974X0200Y    R090 S0      
317P12V_AUX         VIA   -    MD0100PA00X+094372Y+143974X0200Y    R090 S0      
317P12V_AUX         VIA   -    MD0100PA00X+094972Y+143374X0200Y    R090 S0      
317P12V_AUX         VIA   -    MD0100PA00X+094972Y+142774X0200Y    R090 S0      
317P12V_AUX         VIA   -    MD0100PA00X+094972Y+143074X0200Y    R090 S0      
317P12V_AUX         VIA   -    MD0100PA00X+094672Y+143074X0200Y    R090 S0      
317P12V_AUX         VIA   -    MD0100PA00X+094672Y+142774X0200Y    R090 S0      
317P12V_AUX         VIA   -    MD0100PA00X+094372Y+143074X0200Y    R090 S0      
317P12V_AUX         VIA   -    MD0100PA00X+094672Y+143374X0200Y    R090 S0      
317P12V_AUX         VIA   -    MD0100PA00X+094372Y+143374X0200Y    R090 S0      
327P12V_AUX         PR2   -2          A18X+080642Y+143624X0198Y0197R180 S2      
327P12V_AUX         PQ6603-3          A01X+099333Y+144439X0280Y0460     S1      
327P12V_AUX         PQ6603-2          A01X+098833Y+144439X0280Y0460     S1      
327P12V_AUX         PQ6603-1          A01X+098333Y+144439X0280Y0460     S1      
327P12V_AUX         PQ6604-3          A01X+101637Y+144449X0280Y0460     S1      
327P12V_AUX         PQ6604-2          A01X+101137Y+144449X0280Y0460     S1      
327P12V_AUX         PQ6604-1          A01X+100637Y+144449X0280Y0460     S1      
327P12V_AUX         PQ6601-2          A01X+093911Y+144414X0280Y0460     S1      
327P12V_AUX         PQ6601-1          A01X+093411Y+144414X0280Y0460     S1      
327P12V_AUX         PQ6602-3          A01X+097027Y+144439X0280Y0460     S1      
327P12V_AUX         PQ6602-2          A01X+096527Y+144439X0280Y0460     S1      
327P12V_AUX         PQ6602-1          A01X+096027Y+144439X0280Y0460     S1      
327P12V_AUX         PQ6605-3          A01X+103925Y+144461X0280Y0460     S1      
327P12V_AUX         PQ6605-2          A01X+103425Y+144461X0280Y0460     S1      
327P12V_AUX         PQ6605-1          A01X+102925Y+144461X0280Y0460     S1      
327P12V_AUX         PQ6601-3          A01X+094411Y+144414X0280Y0460     S1      
317P12V_AUX         VIA   -    MD0100PA00X+100534Y+141839X0200Y    R090 S0      
317P12V_AUX         VIA   -    MD0100PA00X+100534Y+141279X0200Y    R090 S0      
317P12V_AUX         VIA   -    MD0100PA00X+100534Y+141559X0200Y    R090 S0      
317P12V_AUX         VIA   -    MD0100PA00X+100814Y+141839X0200Y    R090 S0      
317P12V_AUX         VIA   -    MD0100PA00X+100814Y+141279X0200Y    R090 S0      
317P12V_AUX         VIA   -    MD0100PA00X+100814Y+141559X0200Y    R090 S0      
317P12V_AUX         VIA   -    MD0100PA00X+100534Y+140999X0200Y    R090 S0      
317P12V_AUX         VIA   -    MD0100PA00X+100534Y+140719X0200Y    R090 S0      
317P12V_AUX         VIA   -    MD0100PA00X+100814Y+140999X0200Y    R090 S0      
317P12V_AUX         VIA   -    MD0100PA00X+100814Y+140719X0200Y    R090 S0      
327P12V_AUX         PD2   -K          A01X+101977Y+141112X1860Y1890R270 S1      
327P12V_AUX         PL23  -1          A01X+179907Y+125791X0280Y0320R180 S1      
327P12V_AUX         PC264 -1          A01X+179425Y+125794X0198Y0197R180 S1      
317P12V_AUX         VIA   -    MD0100PA00X+135776Y+101977X0200Y         S0      
327P12V_AUX         PR142 -1          A18X+135776Y+101734X0198Y0197R090 S2      
317P12V_AUX         VIA   -    MD0100PA00X+136476Y+100477X0200Y         S0      
317P12V_AUX         VIA   -    MD0100PA00X+179484Y+126354X0200Y         S0      
317P12V_AUX         VIA   -    MD0100PA00X+179734Y+126354X0200Y         S0      
317P12V_AUX         VIA   -    MD0100PA00X+179984Y+126354X0200Y         S0      
317P12V_AUX         VIA   -    MD0100PA00X+179734Y+126104X0200Y         S0      
317P12V_AUX         VIA   -    MD0100PA00X+179484Y+126104X0200Y         S0      
317P12V_AUX         VIA   -    MD0100PA00X+179984Y+126104X0200Y         S0      
327P12V_AUX         PL17  -1          A01X+004742Y+124842X0280Y0320R180 S1      
327P12V_AUX         PC203 -1          A01X+004260Y+124845X0198Y0197R180 S1      
327P12V_AUX         PL19  -1          A01X+089112Y+125742X0280Y0320R180 S1      
327P12V_AUX         PC223 -1          A01X+088629Y+125745X0198Y0197R180 S1      
327P12V_AUX         PL21  -1          A01X+095509Y+125742X0280Y0320R180 S1      
327P12V_AUX         PC243 -1          A01X+095027Y+125745X0198Y0197R180 S1      
317P12V_AUX         VIA   -    MD0100PA00X+004820Y+125156X0200Y         S0      
317P12V_AUX         VIA   -    MD0100PA00X+004320Y+125156X0200Y         S0      
317P12V_AUX         VIA   -    MD0100PA00X+004570Y+125156X0200Y         S0      
317P12V_AUX         VIA   -    MD0100PA00X+004820Y+125406X0200Y         S0      
317P12V_AUX         VIA   -    MD0100PA00X+004570Y+125406X0200Y         S0      
317P12V_AUX         VIA   -    MD0100PA00X+004320Y+125406X0200Y         S0      
317P12V_AUX         VIA   -    MD0100PA00X+044359Y+101977X0200Y         S0      
327P12V_AUX         PR93  -1          A18X+044359Y+101734X0198Y0197R090 S2      
317P12V_AUX         VIA   -    MD0100PA00X+045059Y+100477X0200Y         S0      
317P12V_AUX         VIA   -    MD0100PA00X+089189Y+126056X0200Y         S0      
317P12V_AUX         VIA   -    MD0100PA00X+088689Y+126056X0200Y         S0      
317P12V_AUX         VIA   -    MD0100PA00X+088939Y+126056X0200Y         S0      
317P12V_AUX         VIA   -    MD0100PA00X+089189Y+126306X0200Y         S0      
317P12V_AUX         VIA   -    MD0100PA00X+088939Y+126306X0200Y         S0      
317P12V_AUX         VIA   -    MD0100PA00X+088689Y+126306X0200Y         S0      
317P12V_AUX         VIA   -    MD0100PA00X+095586Y+126056X0200Y         S0      
317P12V_AUX         VIA   -    MD0100PA00X+095086Y+126056X0200Y         S0      
317P12V_AUX         VIA   -    MD0100PA00X+095336Y+126056X0200Y         S0      
317P12V_AUX         VIA   -    MD0100PA00X+095586Y+126306X0200Y         S0      
317P12V_AUX         VIA   -    MD0100PA00X+095336Y+126306X0200Y         S0      
317P12V_AUX         VIA   -    MD0100PA00X+095086Y+126306X0200Y         S0      
317P12V_AUX         VIA   -    MD0100PA00X+074714Y+158134X0200Y    R180 S0      
327P12V_AUX         R4414 -2          A01X+074714Y+158374X0198Y0197R270 S1      
327P12V_AUX         R4415 -2          A01X+074492Y+161494X0198Y0197R090 S1      
317P12V_AUX         VIA   -    MD0100PA00X+074492Y+161771X0200Y    R090 S0      
327P12V_AUX         PU1   -28         A01X+080854Y+144378X0090Y0150     S1      
327P12V_AUX         PU1   -29         A01X+081031Y+144378X0090Y0150     S1      
327P12V_AUX         PU1   -30         A01X+081208Y+144378X0090Y0150     S1      
327P12V_AUX         PU1   -31         A01X+081385Y+144378X0090Y0150     S1      
327P12V_AUX         PU1   -32         A01X+081562Y+144378X0090Y0150     S1      
327P12V_AUX         PU1   -33         A01X+081740Y+144378X0090Y0150     S1      
327P12V_AUX         PU1   -34         A01X+081917Y+144378X0090Y0150     S1      
327P12V_AUX         PU2   -1          A01X+087353Y+144570X0100Y0140R270 S1      
327P12V_AUX         PU2   -32         A01X+087156Y+144373X0100Y0140R180 S1      
327P12V_AUX         PU2   -27         A01X+086172Y+144378X0100Y0150R180 S1      
327P12V_AUX         PU2   -28         A01X+086369Y+144378X0100Y0150R180 S1      
327P12V_AUX         PU2   -29         A01X+086566Y+144378X0100Y0150R180 S1      
327P12V_AUX         PU2   -30         A01X+086762Y+144378X0100Y0150R180 S1      
327P12V_AUX         PU2   -31         A01X+086959Y+144378X0100Y0150R180 S1      
327P12V_AUX         PU3   -1          A01X+091553Y+144570X0100Y0140R270 S1      
327P12V_AUX         PU3   -32         A01X+091356Y+144373X0100Y0140R180 S1      
327P12V_AUX         PU3   -30         A01X+090962Y+144378X0100Y0150R180 S1      
327P12V_AUX         PU3   -31         A01X+091159Y+144378X0100Y0150R180 S1      
317P12V_AUX         VIA   -    MD0100PA00X+077156Y+144682X0200Y         S0      
327P12V_AUX         R6249 -2          A01X+077156Y+144987X0198Y0197R180 S1      
317P12V_AUX         VIA   -    MD0100PA00X+081006Y+143278X0200Y    R270 S0      
317P12V_AUX         VIA   -    MD0100PA00X+081590Y+143280X0200Y    R270 S0      
317P12V_AUX         VIA   -    MD0100PA00X+081290Y+143280X0200Y    R270 S0      
317P12V_AUX         VIA   -    MD0100PA00X+090594Y+143536X0200Y         S0      
317P12V_AUX         VIA   -    MD0100PA00X+090594Y+143236X0200Y         S0      
317P12V_AUX         VIA   -    MD0100PA00X+090594Y+142936X0200Y         S0      
317P12V_AUX         VIA   -    MD0100PA00X+090294Y+143236X0200Y         S0      
317P12V_AUX         VIA   -    MD0100PA00X+089994Y+142936X0200Y         S0      
317P12V_AUX         VIA   -    MD0100PA00X+090294Y+142936X0200Y         S0      
317P12V_AUX         VIA   -    MD0100PA00X+090294Y+142636X0200Y         S0      
317P12V_AUX         VIA   -    MD0100PA00X+089994Y+142636X0200Y         S0      
317P12V_AUX         VIA   -    MD0100PA00X+090594Y+142636X0200Y         S0      
317P12V_AUX         VIA   -    MD0100PA00X+091194Y+143536X0200Y         S0      
317P12V_AUX         VIA   -    MD0100PA00X+091494Y+143536X0200Y         S0      
317P12V_AUX         VIA   -    MD0100PA00X+091194Y+143236X0200Y         S0      
317P12V_AUX         VIA   -    MD0100PA00X+091494Y+143236X0200Y         S0      
317P12V_AUX         VIA   -    MD0100PA00X+091194Y+142936X0200Y         S0      
317P12V_AUX         VIA   -    MD0100PA00X+091494Y+142936X0200Y         S0      
317P12V_AUX         VIA   -    MD0100PA00X+091494Y+142636X0200Y         S0      
317P12V_AUX         VIA   -    MD0100PA00X+091194Y+142636X0200Y         S0      
317P12V_AUX         VIA   -    MD0100PA00X+090894Y+143536X0200Y         S0      
317P12V_AUX         VIA   -    MD0100PA00X+090894Y+143236X0200Y         S0      
317P12V_AUX         VIA   -    MD0100PA00X+090894Y+142936X0200Y         S0      
317P12V_AUX         VIA   -    MD0100PA00X+090894Y+142636X0200Y         S0      
317P12V_AUX         VIA   -    MD0100PA00X+082199Y+143878X0200Y    R270 S0      
317P12V_AUX         VIA   -    MD0100PA00X+081000Y+143550X0200Y    R270 S0      
317P12V_AUX         VIA   -    MD0100PA00X+081590Y+143550X0200Y    R270 S0      
317P12V_AUX         VIA   -    MD0100PA00X+081290Y+143550X0200Y    R270 S0      
317P12V_AUX         VIA   -    MD0100PA00X+090594Y+144136X0200Y         S0      
317P12V_AUX         VIA   -    MD0100PA00X+090594Y+143836X0200Y         S0      
317P12V_AUX         VIA   -    MD0100PA00X+090294Y+144136X0200Y         S0      
317P12V_AUX         VIA   -    MD0100PA00X+091194Y+144136X0200Y         S0      
317P12V_AUX         VIA   -    MD0100PA00X+091494Y+144136X0200Y         S0      
317P12V_AUX         VIA   -    MD0100PA00X+091194Y+143836X0200Y         S0      
317P12V_AUX         VIA   -    MD0100PA00X+091494Y+143836X0200Y         S0      
317P12V_AUX         VIA   -    MD0100PA00X+090894Y+144136X0200Y         S0      
317P12V_AUX         VIA   -    MD0100PA00X+090894Y+143836X0200Y         S0      
317P12V_AUX         VIA   -    MD0100PA00X+081599Y+144148X0200Y    R270 S0      
317P12V_AUX         VIA   -    MD0100PA00X+081299Y+144148X0200Y    R270 S0      
317P12V_AUX         VIA   -    MD0100PA00X+080999Y+144148X0200Y    R270 S0      
317P12V_AUX         VIA   -    MD0100PA00X+081599Y+143878X0200Y    R270 S0      
317P12V_AUX         VIA   -    MD0100PA00X+081899Y+143878X0200Y    R270 S0      
317P12V_AUX         VIA   -    MD0100PA00X+081299Y+143878X0200Y    R270 S0      
317P12V_AUX         VIA   -    MD0100PA00X+081899Y+144148X0200Y    R270 S0      
317P12V_AUX         VIA   -    MD0100PA00X+082199Y+144148X0200Y    R270 S0      
317P12V_AUX         VIA   -    MD0100PA00X+080999Y+143878X0200Y    R270 S0      
317P12V_AUX         VIA   -    MD0100PA00X+089994Y+143536X0200Y         S0      
317P12V_AUX         VIA   -    MD0100PA00X+090294Y+143536X0200Y         S0      
317P12V_AUX         VIA   -    MD0100PA00X+089994Y+143236X0200Y         S0      
317P12V_AUX         VIA   -    MD0100PA00X+089994Y+144136X0200Y         S0      
317P12V_AUX         VIA   -    MD0100PA00X+089994Y+143836X0200Y         S0      
317P12V_AUX         VIA   -    MD0100PA00X+090294Y+143836X0200Y         S0      
317P12V_AUX         VIA   -    MD0100PA00X+081890Y+143280X0200Y    R270 S0      
317P12V_AUX         VIA   -    MD0100PA00X+082190Y+143280X0200Y    R270 S0      
317P12V_AUX         VIA   -    MD0100PA00X+081890Y+143550X0200Y    R270 S0      
317P12V_AUX         VIA   -    MD0100PA00X+082190Y+143550X0200Y    R270 S0      
327P12V_AUX         PU3   -29         A01X+090766Y+144378X0100Y0150R180 S1      
327P12V_AUX         PU3   -28         A01X+090569Y+144378X0100Y0150R180 S1      
327P12V_AUX         PU3   -27         A01X+090372Y+144378X0100Y0150R180 S1      
327P12V_AUX         PU3   -26         A01X+090175Y+144378X0100Y0150R180 S1      
327P12V_AUX         PU3   -25         A01X+089978Y+144373X0100Y0140R180 S1      
327P12V_AUX         PU2   -26         A01X+085975Y+144378X0100Y0150R180 S1      
327P12V_AUX         PU2   -25         A01X+085778Y+144373X0100Y0140R180 S1      
327P12V_AUX         PU1   -35         A01X+082128Y+144639X0090Y0150R270 S1      
327P12V_AUX         PU1   -36         A01X+082128Y+144816X0090Y0150R270 S1      
327P12V_AUX         PU2   -2          A01X+087348Y+144767X0100Y0150R270 S1      
327P12V_AUX         PU3   -2          A01X+091548Y+144767X0100Y0150R270 S1      
327P12V_AUX         PC6606-1          A01X+100205Y+140346X0280Y0320R180 S1      
317P12V_AUX         VIA   -    MD0100PA00X+082790Y+143550X0200Y    R270 S0      
317P12V_AUX         VIA   -    MD0100PA00X+082490Y+143550X0200Y    R270 S0      
317P12V_AUX         VIA   -    MD0100PA00X+083090Y+143280X0200Y    R270 S0      
317P12V_AUX         VIA   -    MD0100PA00X+082790Y+143280X0200Y    R270 S0      
317P12V_AUX         VIA   -    MD0100PA00X+082490Y+143280X0200Y    R270 S0      
317P12V_AUX         VIA   -    MD0100PA00X+082490Y+143010X0200Y    R270 S0      
317P12V_AUX         VIA   -    MD0100PA00X+082790Y+143010X0200Y    R270 S0      
317P12V_AUX         VIA   -    MD0100PA00X+083090Y+143010X0200Y    R270 S0      
317P12V_AUX         VIA   -    MD0100PA00X+082190Y+143010X0200Y    R270 S0      
317P12V_AUX         VIA   -    MD0100PA00X+081890Y+143010X0200Y    R270 S0      
317P12V_AUX         VIA   -    MD0100PA00X+082190Y+142740X0200Y    R270 S0      
317P12V_AUX         VIA   -    MD0100PA00X+082790Y+142740X0200Y    R270 S0      
317P12V_AUX         VIA   -    MD0100PA00X+082490Y+142740X0200Y    R270 S0      
317P12V_AUX         VIA   -    MD0100PA00X+085794Y+143236X0200Y         S0      
317P12V_AUX         VIA   -    MD0100PA00X+086694Y+142636X0200Y         S0      
317P12V_AUX         VIA   -    MD0100PA00X+086694Y+142936X0200Y         S0      
317P12V_AUX         VIA   -    MD0100PA00X+086694Y+143236X0200Y         S0      
317P12V_AUX         VIA   -    MD0100PA00X+086994Y+142636X0200Y         S0      
317P12V_AUX         VIA   -    MD0100PA00X+086994Y+142936X0200Y         S0      
317P12V_AUX         VIA   -    MD0100PA00X+086994Y+143236X0200Y         S0      
317P12V_AUX         VIA   -    MD0100PA00X+086394Y+142636X0200Y         S0      
317P12V_AUX         VIA   -    MD0100PA00X+085794Y+142636X0200Y         S0      
317P12V_AUX         VIA   -    MD0100PA00X+086094Y+142636X0200Y         S0      
317P12V_AUX         VIA   -    MD0100PA00X+086094Y+142936X0200Y         S0      
317P12V_AUX         VIA   -    MD0100PA00X+085794Y+142936X0200Y         S0      
317P12V_AUX         VIA   -    MD0100PA00X+086094Y+143236X0200Y         S0      
317P12V_AUX         VIA   -    MD0100PA00X+086394Y+142936X0200Y         S0      
317P12V_AUX         VIA   -    MD0100PA00X+086394Y+143236X0200Y         S0      
317P12V_AUX         VIA   -    MD0100PA00X+086094Y+143836X0200Y         S0      
317P12V_AUX         VIA   -    MD0100PA00X+085794Y+143836X0200Y         S0      
317P12V_AUX         VIA   -    MD0100PA00X+085794Y+144136X0200Y         S0      
317P12V_AUX         VIA   -    MD0100PA00X+086094Y+143536X0200Y         S0      
317P12V_AUX         VIA   -    MD0100PA00X+085794Y+143536X0200Y         S0      
317P12V_AUX         VIA   -    MD0100PA00X+086694Y+143836X0200Y         S0      
317P12V_AUX         VIA   -    MD0100PA00X+086694Y+144136X0200Y         S0      
317P12V_AUX         VIA   -    MD0100PA00X+086994Y+143836X0200Y         S0      
317P12V_AUX         VIA   -    MD0100PA00X+086994Y+144136X0200Y         S0      
317P12V_AUX         VIA   -    MD0100PA00X+086094Y+144136X0200Y         S0      
317P12V_AUX         VIA   -    MD0100PA00X+086394Y+143836X0200Y         S0      
317P12V_AUX         VIA   -    MD0100PA00X+086394Y+144136X0200Y         S0      
317P12V_AUX         VIA   -    MD0100PA00X+086694Y+143536X0200Y         S0      
317P12V_AUX         VIA   -    MD0100PA00X+086994Y+143536X0200Y         S0      
317P12V_AUX         VIA   -    MD0100PA00X+086394Y+143536X0200Y         S0      
317P12V_AUX         VIA   -    MD0100PA00X+087294Y+142636X0200Y         S0      
317P12V_AUX         VIA   -    MD0100PA00X+087294Y+142936X0200Y         S0      
317P12V_AUX         VIA   -    MD0100PA00X+087294Y+143236X0200Y         S0      
317P12V_AUX         VIA   -    MD0100PA00X+087294Y+143836X0200Y         S0      
317P12V_AUX         VIA   -    MD0100PA00X+087294Y+144136X0200Y         S0      
317P12V_AUX         VIA   -    MD0100PA00X+087294Y+143536X0200Y         S0      
327P12V_AUX         J69   -2          A01X+095897Y+137165X0240Y0950R090 S1      
317P12V_AUX         VIA   -    MD0100PA00X+095183Y+137165X0200Y         S0      
327P12V_AUX         PC6001-1          A18X+105945Y+143535X0198Y0197R270 S2      
327P12V_AUX         PR6612-2          A18X+105552Y+143535X0198Y0197R090 S2      
317P12V_AUX         VIA   -    MD0100PA00X+094883Y+137165X0200Y         S0      
327P12V_AUX         PU1   -27         A01X+080676Y+144378X0090Y0150     S1      
327P12V_AUX         PC283 -1          A01X+041686Y+083480X0198Y0197     S1      
327P12V_AUX         PL25  -1          A01X+041204Y+083483X0280Y0320     S1      
317P12V_AUX         VIA   -    MD0100PA00X+041627Y+082919X0200Y    R180 S0      
317P12V_AUX         VIA   -    MD0100PA00X+041377Y+082919X0200Y    R180 S0      
317P12V_AUX         VIA   -    MD0100PA00X+041377Y+083169X0200Y    R180 S0      
317P12V_AUX         VIA   -    MD0100PA00X+041627Y+083169X0200Y    R180 S0      
317P12V_AUX         VIA   -    MD0100PA00X+041127Y+083169X0200Y    R180 S0      
317P12V_AUX         VIA   -    MD0100PA00X+041127Y+082919X0200Y    R180 S0      
317P12V_AUX         VIA   -    MD0100PA00X+094492Y+080896X0200Y    R090 S0      
327P12V_AUX         R4850 -1          A01X+094392Y+081146X0198Y0197R090 S1      
327P12V_AUX         PC23  -1          A01X+044226Y+071120X0198Y0197     S1      
327P12V_AUX         PL3   -1          A01X+043434Y+070588X0420Y0990R270 S1      
317P12V_AUX         VIA   -    MD0100PA00X+042661Y+070976X0200Y         S0      
317P12V_AUX         VIA   -    MD0100PA00X+042661Y+071236X0200Y         S0      
317P12V_AUX         VIA   -    MD0100PA00X+043179Y+070980X0200Y         S0      
317P12V_AUX         VIA   -    MD0100PA00X+042929Y+071240X0200Y         S0      
317P12V_AUX         VIA   -    MD0100PA00X+043179Y+071240X0200Y         S0      
317P12V_AUX         VIA   -    MD0100PA00X+042929Y+070980X0200Y         S0      
317P12V_AUX         VIA   -    MD0100PA00X+043429Y+070980X0200Y         S0      
317P12V_AUX         VIA   -    MD0100PA00X+043429Y+071240X0200Y         S0      
317P12V_AUX         VIA   -    MD0100PA00X+043679Y+070980X0200Y         S0      
317P12V_AUX         VIA   -    MD0100PA00X+043929Y+070980X0200Y         S0      
317P12V_AUX         VIA   -    MD0100PA00X+043679Y+071240X0200Y         S0      
317P12V_AUX         VIA   -    MD0100PA00X+043929Y+071240X0200Y         S0      
317P12V_AUX         VIA   -    MD0100PA00X+087629Y+069097X0200Y         S0      
327P12V_AUX         R3146 -1          A01X+087869Y+069097X0198Y0197     S1      
327P12V_AUX         PL1   -1          A01X+008852Y+065699X0280Y0320R090 S1      
327P12V_AUX         PC18  -1          A01X+009346Y+065540X0198Y0197R270 S1      
317P12V_AUX         VIA   -    MD0100PA00X+009592Y+065837X0200Y    R090 S0      
317P12V_AUX         VIA   -    MD0100PA00X+009290Y+065836X0200Y    R090 S0      
317P12V_AUX         VIA   -    MD0100PA00X+009597Y+065566X0200Y    R090 S0      
327P12V_AUX         PR7048-2          A01X+140145Y+061374X0198Y0197R270 S1      
327P12V_AUX         PR7047-2          A01X+140555Y+060181X0280Y0320R090 S1      
317P12V_AUX         VIA   -    MD0100PA00X+140138Y+061107X0200Y         S0      
327P12V_AUX         PC798 -1          A01X+143525Y+062509X0198Y0197R090 S1      
327P12V_AUX         PD5   -C          A01X+144695Y+061666X0850Y0890R270 S1      
327P12V_AUX         PU105 -21_2       A01X+142966Y+061734X0364Y0492R180 S1      
327P12V_AUX         PU105 -23         A01X+142478Y+061931X0100Y0500R180 S1      
327P12V_AUX         PU105 -24         A01X+142124Y+061931X0100Y0500R180 S1      
327P12V_AUX         PU105 -25         A01X+141770Y+061931X0100Y0500R180 S1      
327P12V_AUX         PU105 -26         A01X+141415Y+061931X0100Y0500R180 S1      
317P12V_AUX         VIA   -    MD0100PA00X+143311Y+061785X0200Y         S0      
317P12V_AUX         VIA   -    MD0100PA00X+143311Y+062065X0200Y         S0      
317P12V_AUX         VIA   -    MD0100PA00X+143779Y+062501X0200Y         S0      
317P12V_AUX         VIA   -    MD0100PA00X+144093Y+061951X0200Y         S0      
317P12V_AUX         VIA   -    MD0100PA00X+144093Y+061671X0200Y         S0      
317P12V_AUX         VIA   -    MD0100PA00X+144093Y+061391X0200Y         S0      
317P12V_AUX         VIA   -    MD0100PA00X+145300Y+061976X0200Y         S0      
317P12V_AUX         VIA   -    MD0100PA00X+145300Y+061696X0200Y         S0      
317P12V_AUX         VIA   -    MD0100PA00X+145300Y+061416X0200Y         S0      
327P12V_AUX         PC799 -1          A01X+097816Y+062509X0198Y0197R090 S1      
327P12V_AUX         PD93  -C          A01X+098986Y+061666X0850Y0890R270 S1      
327P12V_AUX         PU103 -21_2       A01X+097257Y+061734X0364Y0492R180 S1      
327P12V_AUX         PU103 -23         A01X+096770Y+061931X0100Y0500R180 S1      
327P12V_AUX         PU103 -24         A01X+096415Y+061931X0100Y0500R180 S1      
327P12V_AUX         PU103 -25         A01X+096061Y+061931X0100Y0500R180 S1      
327P12V_AUX         PU103 -26         A01X+095707Y+061931X0100Y0500R180 S1      
317P12V_AUX         VIA   -    MD0100PA00X+097603Y+061785X0200Y         S0      
317P12V_AUX         VIA   -    MD0100PA00X+097603Y+062065X0200Y         S0      
317P12V_AUX         VIA   -    MD0100PA00X+098070Y+062501X0200Y         S0      
317P12V_AUX         VIA   -    MD0100PA00X+098384Y+061391X0200Y         S0      
317P12V_AUX         VIA   -    MD0100PA00X+098384Y+061671X0200Y         S0      
317P12V_AUX         VIA   -    MD0100PA00X+098384Y+061951X0200Y         S0      
317P12V_AUX         VIA   -    MD0100PA00X+099591Y+061416X0200Y         S0      
317P12V_AUX         VIA   -    MD0100PA00X+099591Y+061696X0200Y         S0      
317P12V_AUX         VIA   -    MD0100PA00X+099591Y+061976X0200Y         S0      
327P12V_AUX         PR7024-2          A01X+094436Y+061374X0198Y0197R270 S1      
327P12V_AUX         PR7023-2          A01X+094846Y+060181X0280Y0320R090 S1      
317P12V_AUX         VIA   -    MD0100PA00X+094430Y+061107X0200Y         S0      
327P12V_AUX         PC619 -1          A01X+052107Y+062509X0198Y0197R090 S1      
327P12V_AUX         PD81  -C          A01X+053278Y+061666X0850Y0890R270 S1      
327P12V_AUX         PU73  -21_2       A01X+051548Y+061734X0364Y0492R180 S1      
327P12V_AUX         PU73  -23         A01X+051061Y+061931X0100Y0500R180 S1      
327P12V_AUX         PU73  -24         A01X+050706Y+061931X0100Y0500R180 S1      
327P12V_AUX         PU73  -25         A01X+050352Y+061931X0100Y0500R180 S1      
327P12V_AUX         PU73  -26         A01X+049998Y+061931X0100Y0500R180 S1      
317P12V_AUX         VIA   -    MD0100PA00X+052362Y+062501X0200Y         S0      
317P12V_AUX         VIA   -    MD0100PA00X+051894Y+061785X0200Y         S0      
317P12V_AUX         VIA   -    MD0100PA00X+051894Y+062065X0200Y         S0      
317P12V_AUX         VIA   -    MD0100PA00X+053883Y+061976X0200Y         S0      
317P12V_AUX         VIA   -    MD0100PA00X+053883Y+061696X0200Y         S0      
317P12V_AUX         VIA   -    MD0100PA00X+053883Y+061416X0200Y         S0      
317P12V_AUX         VIA   -    MD0100PA00X+052676Y+061951X0200Y         S0      
317P12V_AUX         VIA   -    MD0100PA00X+052676Y+061671X0200Y         S0      
317P12V_AUX         VIA   -    MD0100PA00X+052676Y+061391X0200Y         S0      
327P12V_AUX         PR6890-2          A01X+048728Y+061374X0198Y0197R270 S1      
327P12V_AUX         PR6889-2          A01X+049138Y+060181X0280Y0320R090 S1      
317P12V_AUX         VIA   -    MD0100PA00X+048721Y+061107X0200Y         S0      
327P12V_AUX         PC598 -1          A01X+006399Y+062509X0198Y0197R090 S1      
327P12V_AUX         PD76  -C          A01X+007569Y+061666X0850Y0890R270 S1      
327P12V_AUX         PU71  -21_2       A01X+005840Y+061734X0364Y0492R180 S1      
327P12V_AUX         PU71  -23         A01X+005352Y+061931X0100Y0500R180 S1      
327P12V_AUX         PU71  -24         A01X+004998Y+061931X0100Y0500R180 S1      
327P12V_AUX         PU71  -25         A01X+004644Y+061931X0100Y0500R180 S1      
327P12V_AUX         PU71  -26         A01X+004289Y+061931X0100Y0500R180 S1      
317P12V_AUX         VIA   -    MD0100PA00X+006653Y+062501X0200Y         S0      
317P12V_AUX         VIA   -    MD0100PA00X+006185Y+062065X0200Y         S0      
317P12V_AUX         VIA   -    MD0100PA00X+006185Y+061785X0200Y         S0      
317P12V_AUX         VIA   -    MD0100PA00X+006967Y+061391X0200Y         S0      
317P12V_AUX         VIA   -    MD0100PA00X+006967Y+061671X0200Y         S0      
317P12V_AUX         VIA   -    MD0100PA00X+006967Y+061951X0200Y         S0      
317P12V_AUX         VIA   -    MD0100PA00X+008174Y+061416X0200Y         S0      
317P12V_AUX         VIA   -    MD0100PA00X+008174Y+061696X0200Y         S0      
317P12V_AUX         VIA   -    MD0100PA00X+008174Y+061976X0200Y         S0      
327P12V_AUX         PR6866-2          A01X+003019Y+061374X0198Y0197R270 S1      
327P12V_AUX         PR6865-2          A01X+003429Y+060181X0280Y0320R090 S1      
317P12V_AUX         VIA   -    MD0100PA00X+003012Y+061107X0200Y         S0      
327P12V_AUX         PC304 -1          A01X+142168Y+052927X0198Y0197     S1      
327P12V_AUX         PC305 -2          A01X+142065Y+052397X0400Y0500     S1      
327P12V_AUX         PD9   -C          A01X+141367Y+051102X0850Y0890R180 S1      
317P12V_AUX         VIA   -    MD0100PA00X+140962Y+053195X0200Y         S0      
317P12V_AUX         VIA   -    MD0100PA00X+141267Y+053188X0200Y         S0      
317P12V_AUX         VIA   -    MD0100PA00X+141517Y+053188X0200Y         S0      
317P12V_AUX         VIA   -    MD0100PA00X+141655Y+052537X0200Y         S0      
317P12V_AUX         VIA   -    MD0100PA00X+141655Y+052257X0200Y         S0      
317P12V_AUX         VIA   -    MD0100PA00X+141100Y+051740X0200Y         S0      
317P12V_AUX         VIA   -    MD0100PA00X+141350Y+051740X0200Y         S0      
317P12V_AUX         VIA   -    MD0100PA00X+141600Y+051740X0200Y         S0      
317P12V_AUX         VIA   -    MD0100PA00X+141106Y+050482X0200Y         S0      
317P12V_AUX         VIA   -    MD0100PA00X+141356Y+050482X0200Y         S0      
317P12V_AUX         VIA   -    MD0100PA00X+141606Y+050482X0200Y         S0      
317P12V_AUX         VIA   -    MD0100PA00X+141767Y+053188X0200Y         S0      
317P12V_AUX         VIA   -    MD0100PA00X+141825Y+052917X0200Y         S0      
327P12V_AUX         PC342 -1          A01X+096459Y+052927X0198Y0197     S1      
327P12V_AUX         PC343 -2          A01X+096357Y+052397X0400Y0500     S1      
327P12V_AUX         PD92  -C          A01X+095658Y+051102X0850Y0890R180 S1      
317P12V_AUX         VIA   -    MD0100PA00X+096058Y+053188X0200Y         S0      
317P12V_AUX         VIA   -    MD0100PA00X+095253Y+053195X0200Y         S0      
317P12V_AUX         VIA   -    MD0100PA00X+096117Y+052917X0200Y         S0      
317P12V_AUX         VIA   -    MD0100PA00X+095558Y+053188X0200Y         S0      
317P12V_AUX         VIA   -    MD0100PA00X+095808Y+053188X0200Y         S0      
317P12V_AUX         VIA   -    MD0100PA00X+095947Y+052537X0200Y         S0      
317P12V_AUX         VIA   -    MD0100PA00X+095947Y+052257X0200Y         S0      
317P12V_AUX         VIA   -    MD0100PA00X+095392Y+051740X0200Y         S0      
317P12V_AUX         VIA   -    MD0100PA00X+095642Y+051740X0200Y         S0      
317P12V_AUX         VIA   -    MD0100PA00X+095892Y+051740X0200Y         S0      
317P12V_AUX         VIA   -    MD0100PA00X+095397Y+050482X0200Y         S0      
317P12V_AUX         VIA   -    MD0100PA00X+095647Y+050482X0200Y         S0      
317P12V_AUX         VIA   -    MD0100PA00X+095897Y+050482X0200Y         S0      
327P12V_AUX         PC328 -1          A01X+050750Y+052927X0198Y0197     S1      
327P12V_AUX         PC329 -2          A01X+050648Y+052397X0400Y0500     S1      
327P12V_AUX         PD4   -C          A01X+049949Y+051102X0850Y0890R180 S1      
317P12V_AUX         VIA   -    MD0100PA00X+050408Y+052917X0200Y         S0      
317P12V_AUX         VIA   -    MD0100PA00X+049849Y+053188X0200Y         S0      
317P12V_AUX         VIA   -    MD0100PA00X+050099Y+053188X0200Y         S0      
317P12V_AUX         VIA   -    MD0100PA00X+050238Y+052537X0200Y         S0      
317P12V_AUX         VIA   -    MD0100PA00X+050349Y+053188X0200Y         S0      
317P12V_AUX         VIA   -    MD0100PA00X+049544Y+053195X0200Y         S0      
317P12V_AUX         VIA   -    MD0100PA00X+050238Y+052257X0200Y         S0      
317P12V_AUX         VIA   -    MD0100PA00X+049683Y+051740X0200Y         S0      
317P12V_AUX         VIA   -    MD0100PA00X+049933Y+051740X0200Y         S0      
317P12V_AUX         VIA   -    MD0100PA00X+050183Y+051740X0200Y         S0      
317P12V_AUX         VIA   -    MD0100PA00X+049689Y+050482X0200Y         S0      
317P12V_AUX         VIA   -    MD0100PA00X+049939Y+050482X0200Y         S0      
317P12V_AUX         VIA   -    MD0100PA00X+050189Y+050482X0200Y         S0      
327P12V_AUX         PC352 -1          A01X+005042Y+052927X0198Y0197     S1      
327P12V_AUX         PC353 -2          A01X+004939Y+052397X0400Y0500     S1      
327P12V_AUX         PD24  -C          A01X+004241Y+051102X0850Y0890R180 S1      
317P12V_AUX         VIA   -    MD0100PA00X+003836Y+053195X0200Y         S0      
317P12V_AUX         VIA   -    MD0100PA00X+004641Y+053188X0200Y         S0      
317P12V_AUX         VIA   -    MD0100PA00X+004529Y+052537X0200Y         S0      
317P12V_AUX         VIA   -    MD0100PA00X+004391Y+053188X0200Y         S0      
317P12V_AUX         VIA   -    MD0100PA00X+004141Y+053188X0200Y         S0      
317P12V_AUX         VIA   -    MD0100PA00X+004699Y+052917X0200Y         S0      
317P12V_AUX         VIA   -    MD0100PA00X+004474Y+051740X0200Y         S0      
317P12V_AUX         VIA   -    MD0100PA00X+004224Y+051740X0200Y         S0      
317P12V_AUX         VIA   -    MD0100PA00X+003974Y+051740X0200Y         S0      
317P12V_AUX         VIA   -    MD0100PA00X+004529Y+052257X0200Y         S0      
317P12V_AUX         VIA   -    MD0100PA00X+004480Y+050482X0200Y         S0      
317P12V_AUX         VIA   -    MD0100PA00X+004230Y+050482X0200Y         S0      
317P12V_AUX         VIA   -    MD0100PA00X+003980Y+050482X0200Y         S0      
317P12V_AUX         VIA   -    MD0100PA00X+091076Y+047551X0200Y    R270 S0      
327P12V_AUX         PR6891-2          A01X+090150Y+047134X0280Y0320     S1      
327P12V_AUX         PR6892-2          A01X+091342Y+047544X0198Y0197R180 S1      
317P12V_AUX         VIA   -    MD0100PA00X+178669Y+045917X0200Y    R270 S0      
327P12V_AUX         PR7054-2          A01X+177743Y+045500X0280Y0320     S1      
327P12V_AUX         PR7055-2          A01X+178936Y+045910X0198Y0197R180 S1      
317P12V_AUX         VIA   -    MD0100PA00X+041543Y+045917X0200Y    R270 S0      
327P12V_AUX         PR6867-2          A01X+040617Y+045500X0280Y0320     S1      
327P12V_AUX         PR6868-2          A01X+041810Y+045910X0198Y0197R180 S1      
317P12V_AUX         VIA   -    MD0100PA00X+091432Y+040105X0200Y    R270 S0      
317P12V_AUX         VIA   -    MD0100PA00X+091432Y+040355X0200Y    R270 S0      
317P12V_AUX         VIA   -    MD0100PA00X+091432Y+039855X0200Y    R270 S0      
317P12V_AUX         VIA   -    MD0100PA00X+092196Y+042444X0200Y    R270 S0      
317P12V_AUX         VIA   -    MD0100PA00X+092476Y+042444X0200Y    R270 S0      
317P12V_AUX         VIA   -    MD0100PA00X+092756Y+042444X0200Y    R270 S0      
317P12V_AUX         VIA   -    MD0100PA00X+091754Y+044128X0200Y    R270 S0      
317P12V_AUX         VIA   -    MD0100PA00X+092448Y+043672X0200Y    R270 S0      
317P12V_AUX         VIA   -    MD0100PA00X+092168Y+043672X0200Y    R270 S0      
317P12V_AUX         VIA   -    MD0100PA00X+092728Y+043672X0200Y    R270 S0      
317P12V_AUX         VIA   -    MD0100PA00X+091754Y+044378X0200Y    R270 S0      
317P12V_AUX         VIA   -    MD0100PA00X+090175Y+040099X0200Y    R270 S0      
317P12V_AUX         VIA   -    MD0100PA00X+090175Y+040349X0200Y    R270 S0      
317P12V_AUX         VIA   -    MD0100PA00X+090175Y+039849X0200Y    R270 S0      
317P12V_AUX         VIA   -    MD0100PA00X+088998Y+040574X0200Y    R270 S0      
317P12V_AUX         VIA   -    MD0100PA00X+089378Y+040404X0200Y    R270 S0      
317P12V_AUX         VIA   -    MD0100PA00X+089658Y+040404X0200Y    R270 S0      
317P12V_AUX         VIA   -    MD0100PA00X+088727Y+040266X0200Y    R270 S0      
317P12V_AUX         VIA   -    MD0100PA00X+088727Y+040516X0200Y    R270 S0      
317P12V_AUX         VIA   -    MD0100PA00X+088727Y+040016X0200Y    R270 S0      
327P12V_AUX         PC341 -2          A01X+089518Y+040814X0400Y0500R090 S1      
327P12V_AUX         PD8   -C          A01X+090813Y+039716X0850Y0890R270 S1      
327P12V_AUX         PC599 -1          A01X+091403Y+044175X0198Y0197R180 S1      
327P12V_AUX         PD80  -C          A01X+092435Y+043072X0850Y0890     S1      
327P12V_AUX         PU74  -24         A01X+091900Y+045566X0100Y0500R090 S1      
327P12V_AUX         PU74  -23         A01X+091900Y+045211X0100Y0500R090 S1      
327P12V_AUX         PU74  -21_2       A01X+091703Y+044724X0364Y0492R090 S1      
327P12V_AUX         PU74  -26         A01X+091900Y+046274X0100Y0500R090 S1      
327P12V_AUX         PU74  -25         A01X+091900Y+045920X0100Y0500R090 S1      
327P12V_AUX         PC340 -1          A01X+088988Y+040917X0198Y0197R090 S1      
317P12V_AUX         VIA   -    MD0100PA00X+180550Y+040810X0200Y    R270 S0      
317P12V_AUX         VIA   -    MD0100PA00X+180270Y+040810X0200Y    R270 S0      
317P12V_AUX         VIA   -    MD0100PA00X+179990Y+040810X0200Y    R270 S0      
317P12V_AUX         VIA   -    MD0100PA00X+180521Y+042038X0200Y    R270 S0      
317P12V_AUX         VIA   -    MD0100PA00X+180241Y+042038X0200Y    R270 S0      
317P12V_AUX         VIA   -    MD0100PA00X+179961Y+042038X0200Y    R270 S0      
317P12V_AUX         VIA   -    MD0100PA00X+179348Y+042494X0200Y    R270 S0      
317P12V_AUX         VIA   -    MD0100PA00X+179348Y+042744X0200Y    R270 S0      
317P12V_AUX         VIA   -    MD0100PA00X+177768Y+038465X0200Y    R270 S0      
317P12V_AUX         VIA   -    MD0100PA00X+177768Y+038215X0200Y    R270 S0      
317P12V_AUX         VIA   -    MD0100PA00X+177768Y+038715X0200Y    R270 S0      
317P12V_AUX         VIA   -    MD0100PA00X+176320Y+038632X0200Y    R270 S0      
317P12V_AUX         VIA   -    MD0100PA00X+176320Y+038382X0200Y    R270 S0      
317P12V_AUX         VIA   -    MD0100PA00X+176320Y+038882X0200Y    R270 S0      
317P12V_AUX         VIA   -    MD0100PA00X+176591Y+038940X0200Y    R270 S0      
317P12V_AUX         VIA   -    MD0100PA00X+176971Y+038770X0200Y    R270 S0      
317P12V_AUX         VIA   -    MD0100PA00X+177251Y+038770X0200Y    R270 S0      
327P12V_AUX         PD13  -C          A01X+178406Y+038082X0850Y0890R270 S1      
327P12V_AUX         PC821 -1          A01X+178997Y+042541X0198Y0197R180 S1      
327P12V_AUX         PD17  -C          A01X+180228Y+041438X0850Y0890     S1      
327P12V_AUX         PU106 -24         A01X+179493Y+043931X0100Y0500R090 S1      
327P12V_AUX         PU106 -23         A01X+179493Y+043577X0100Y0500R090 S1      
327P12V_AUX         PU106 -21_2       A01X+179296Y+043090X0364Y0492R090 S1      
327P12V_AUX         PU106 -26         A01X+179493Y+044640X0100Y0500R090 S1      
327P12V_AUX         PU106 -25         A01X+179493Y+044286X0100Y0500R090 S1      
327P12V_AUX         PC330 -1          A01X+176581Y+039283X0198Y0197R090 S1      
327P12V_AUX         PC331 -2          A01X+177111Y+039180X0400Y0500R090 S1      
317P12V_AUX         VIA   -    MD0100PA00X+132961Y+045917X0200Y    R270 S0      
317P12V_AUX         VIA   -    MD0100PA00X+134841Y+040810X0200Y    R270 S0      
317P12V_AUX         VIA   -    MD0100PA00X+134561Y+040810X0200Y    R270 S0      
317P12V_AUX         VIA   -    MD0100PA00X+134281Y+040810X0200Y    R270 S0      
317P12V_AUX         VIA   -    MD0100PA00X+134813Y+042038X0200Y    R270 S0      
317P12V_AUX         VIA   -    MD0100PA00X+134533Y+042038X0200Y    R270 S0      
317P12V_AUX         VIA   -    MD0100PA00X+134253Y+042038X0200Y    R270 S0      
317P12V_AUX         VIA   -    MD0100PA00X+133639Y+042494X0200Y    R270 S0      
317P12V_AUX         VIA   -    MD0100PA00X+133639Y+042744X0200Y    R270 S0      
317P12V_AUX         VIA   -    MD0100PA00X+132059Y+038465X0200Y    R270 S0      
317P12V_AUX         VIA   -    MD0100PA00X+132059Y+038215X0200Y    R270 S0      
317P12V_AUX         VIA   -    MD0100PA00X+132059Y+038715X0200Y    R270 S0      
317P12V_AUX         VIA   -    MD0100PA00X+132890Y+038657X0200Y    R270 S0      
317P12V_AUX         VIA   -    MD0100PA00X+133161Y+038657X0200Y    R270 S0      
317P12V_AUX         VIA   -    MD0100PA00X+133428Y+038657X0200Y    R270 S0      
317P12V_AUX         VIA   -    MD0100PA00X+130611Y+038882X0200Y    R270 S0      
317P12V_AUX         VIA   -    MD0100PA00X+130611Y+038632X0200Y    R270 S0      
317P12V_AUX         VIA   -    MD0100PA00X+131543Y+038770X0200Y    R270 S0      
317P12V_AUX         VIA   -    MD0100PA00X+131263Y+038770X0200Y    R270 S0      
317P12V_AUX         VIA   -    MD0100PA00X+130611Y+038382X0200Y    R270 S0      
317P12V_AUX         VIA   -    MD0100PA00X+130883Y+038940X0200Y    R270 S0      
327P12V_AUX         PD96  -C          A01X+132697Y+038082X0850Y0890R270 S1      
327P12V_AUX         PC818 -1          A01X+133288Y+042541X0198Y0197R180 S1      
327P12V_AUX         PD97  -C          A01X+134519Y+041438X0850Y0890     S1      
327P12V_AUX         PU104 -24         A01X+133785Y+043931X0100Y0500R090 S1      
327P12V_AUX         PU104 -23         A01X+133785Y+043577X0100Y0500R090 S1      
327P12V_AUX         PU104 -21_2       A01X+133588Y+043090X0364Y0492R090 S1      
327P12V_AUX         PU104 -26         A01X+133785Y+044640X0100Y0500R090 S1      
327P12V_AUX         PU104 -25         A01X+133785Y+044286X0100Y0500R090 S1      
327P12V_AUX         PR7030-2          A01X+132035Y+045500X0280Y0320     S1      
327P12V_AUX         PR7031-2          A01X+133227Y+045910X0198Y0197R180 S1      
327P12V_AUX         PC318 -1          A01X+130873Y+039283X0198Y0197R090 S1      
327P12V_AUX         PC319 -2          A01X+131403Y+039180X0400Y0500R090 S1      
317P12V_AUX         VIA   -    MD0100PA00X+043424Y+040810X0200Y    R270 S0      
317P12V_AUX         VIA   -    MD0100PA00X+043144Y+040810X0200Y    R270 S0      
317P12V_AUX         VIA   -    MD0100PA00X+042864Y+040810X0200Y    R270 S0      
317P12V_AUX         VIA   -    MD0100PA00X+043395Y+042038X0200Y    R270 S0      
317P12V_AUX         VIA   -    MD0100PA00X+043115Y+042038X0200Y    R270 S0      
317P12V_AUX         VIA   -    MD0100PA00X+042835Y+042038X0200Y    R270 S0      
317P12V_AUX         VIA   -    MD0100PA00X+041900Y+038721X0200Y    R270 S0      
317P12V_AUX         VIA   -    MD0100PA00X+041900Y+038471X0200Y    R270 S0      
317P12V_AUX         VIA   -    MD0100PA00X+041900Y+038221X0200Y    R270 S0      
317P12V_AUX         VIA   -    MD0100PA00X+042222Y+042494X0200Y    R270 S0      
317P12V_AUX         VIA   -    MD0100PA00X+042222Y+042744X0200Y    R270 S0      
317P12V_AUX         VIA   -    MD0100PA00X+039465Y+038940X0200Y    R270 S0      
317P12V_AUX         VIA   -    MD0100PA00X+040125Y+038770X0200Y    R270 S0      
317P12V_AUX         VIA   -    MD0100PA00X+039845Y+038770X0200Y    R270 S0      
317P12V_AUX         VIA   -    MD0100PA00X+040642Y+038465X0200Y    R270 S0      
317P12V_AUX         VIA   -    MD0100PA00X+040642Y+038215X0200Y    R270 S0      
317P12V_AUX         VIA   -    MD0100PA00X+040642Y+038715X0200Y    R270 S0      
317P12V_AUX         VIA   -    MD0100PA00X+039194Y+038632X0200Y    R270 S0      
317P12V_AUX         VIA   -    MD0100PA00X+039194Y+038882X0200Y    R270 S0      
317P12V_AUX         VIA   -    MD0100PA00X+039194Y+038382X0200Y    R270 S0      
327P12V_AUX         PD12  -C          A01X+041280Y+038082X0850Y0890R270 S1      
327P12V_AUX         PC618 -1          A01X+041871Y+042541X0198Y0197R180 S1      
327P12V_AUX         PD77  -C          A01X+043102Y+041438X0850Y0890     S1      
327P12V_AUX         PU72  -24         A01X+042367Y+043931X0100Y0500R090 S1      
327P12V_AUX         PU72  -23         A01X+042367Y+043577X0100Y0500R090 S1      
327P12V_AUX         PU72  -21_2       A01X+042170Y+043090X0364Y0492R090 S1      
327P12V_AUX         PU72  -26         A01X+042367Y+044640X0100Y0500R090 S1      
327P12V_AUX         PU72  -25         A01X+042367Y+044286X0100Y0500R090 S1      
327P12V_AUX         PC306 -1          A01X+039455Y+039283X0198Y0197R090 S1      
327P12V_AUX         PC307 -2          A01X+039985Y+039180X0400Y0500R090 S1      
327P12V_AUX         PD84  -C          A01X+010083Y+027168X0850Y0890R270 S1      
327P12V_AUX         PC639 -1          A01X+008984Y+027523X0198Y0197R090 S1      
327P12V_AUX         PU76  -1_2        A01X+008248Y+027354X0295Y0354R270 S1      
327P12V_AUX         PD21  -C          A01X+009098Y+024257X0850Y0890     S1      
327P12V_AUX         PC367 -2          A01X+008400Y+022962X0400Y0500R180 S1      
327P12V_AUX         PC390 -1          A01X+008297Y+022432X0198Y0197R180 S1      
327P12V_AUX         PD88  -C          A01X+020320Y+027168X0850Y0890R270 S1      
327P12V_AUX         PU75  -1_2        A01X+018484Y+027354X0295Y0354R270 S1      
327P12V_AUX         PC649 -1          A01X+019221Y+027523X0198Y0197R090 S1      
327P12V_AUX         PD25  -C          A01X+019334Y+024257X0850Y0890     S1      
327P12V_AUX         PC377 -2          A01X+018636Y+022962X0400Y0500R180 S1      
327P12V_AUX         PC402 -1          A01X+018534Y+022432X0198Y0197R180 S1      
327P12V_AUX         PD85  -C          A01X+030556Y+027168X0850Y0890R270 S1      
327P12V_AUX         PC648 -1          A01X+029457Y+027523X0198Y0197R090 S1      
327P12V_AUX         PU78  -1_2        A01X+028721Y+027354X0295Y0354R270 S1      
327P12V_AUX         PD29  -C          A01X+029571Y+024257X0850Y0890     S1      
327P12V_AUX         PC376 -1          A01X+028770Y+022432X0198Y0197R180 S1      
327P12V_AUX         PC355 -2          A01X+028872Y+022962X0400Y0500R180 S1      
327P12V_AUX         PD89  -C          A01X+040792Y+027168X0850Y0890R270 S1      
327P12V_AUX         PC638 -1          A01X+039693Y+027523X0198Y0197R090 S1      
327P12V_AUX         PU77  -1_2        A01X+038957Y+027354X0295Y0354R270 S1      
327P12V_AUX         PD33  -C          A01X+039807Y+024257X0850Y0890     S1      
327P12V_AUX         PC391 -2          A01X+039108Y+022962X0400Y0500R180 S1      
327P12V_AUX         PC354 -1          A01X+039006Y+022432X0198Y0197R180 S1      
327P12V_AUX         PD105 -C          A01X+055792Y+027168X0850Y0890R270 S1      
327P12V_AUX         PC839 -1          A01X+054693Y+027523X0198Y0197R090 S1      
327P12V_AUX         PU107 -1_2        A01X+053957Y+027354X0295Y0354R270 S1      
327P12V_AUX         PD16  -C          A01X+054807Y+024257X0850Y0890     S1      
327P12V_AUX         PC317 -2          A01X+054108Y+022962X0400Y0500R180 S1      
327P12V_AUX         PC316 -1          A01X+054006Y+022432X0198Y0197R180 S1      
327P12V_AUX         PD101 -C          A01X+066028Y+027168X0850Y0890R270 S1      
327P12V_AUX         PU108 -1_2        A01X+064193Y+027354X0295Y0354R270 S1      
327P12V_AUX         PC848 -1          A01X+064929Y+027523X0198Y0197R090 S1      
327P12V_AUX         PD28  -C          A01X+065043Y+024257X0850Y0890     S1      
327P12V_AUX         PC379 -2          A01X+064345Y+022962X0400Y0500R180 S1      
327P12V_AUX         PC366 -1          A01X+064242Y+022432X0198Y0197R180 S1      
327P12V_AUX         PD100 -C          A01X+076264Y+027168X0850Y0890R270 S1      
327P12V_AUX         PC838 -1          A01X+075166Y+027523X0198Y0197R090 S1      
327P12V_AUX         PU109 -1_2        A01X+074429Y+027354X0295Y0354R270 S1      
327P12V_AUX         PD32  -C          A01X+075279Y+024257X0850Y0890     S1      
327P12V_AUX         PC389 -2          A01X+074581Y+022962X0400Y0500R180 S1      
327P12V_AUX         PC378 -1          A01X+074478Y+022432X0198Y0197R180 S1      
327P12V_AUX         PD104 -C          A01X+086501Y+027168X0850Y0890R270 S1      
327P12V_AUX         PC849 -1          A01X+085402Y+027523X0198Y0197R090 S1      
327P12V_AUX         PU110 -1_2        A01X+084666Y+027354X0295Y0354R270 S1      
327P12V_AUX         PD20  -C          A01X+085516Y+024257X0850Y0890     S1      
327P12V_AUX         PC365 -2          A01X+084817Y+022962X0400Y0500R180 S1      
327P12V_AUX         PC388 -1          A01X+084715Y+022432X0198Y0197R180 S1      
327P12V_AUX         PD36  -C          A01X+101501Y+027168X0850Y0890R270 S1      
327P12V_AUX         PU111 -1_2        A01X+099666Y+027354X0295Y0354R270 S1      
327P12V_AUX         PC859 -1          A01X+100402Y+027523X0198Y0197R090 S1      
327P12V_AUX         PD113 -C          A01X+100516Y+024257X0850Y0890     S1      
327P12V_AUX         PC401 -2          A01X+099817Y+022962X0400Y0500R180 S1      
327P12V_AUX         PC400 -1          A01X+099715Y+022432X0198Y0197R180 S1      
327P12V_AUX         PD112 -C          A01X+111737Y+027168X0850Y0890R270 S1      
327P12V_AUX         PU112 -1_2        A01X+109902Y+027354X0295Y0354R270 S1      
327P12V_AUX         PC869 -1          A01X+110638Y+027523X0198Y0197R090 S1      
327P12V_AUX         PD44  -C          A01X+110752Y+024257X0850Y0890     S1      
327P12V_AUX         PC415 -2          A01X+110053Y+022962X0400Y0500R180 S1      
327P12V_AUX         PC414 -1          A01X+109951Y+022432X0198Y0197R180 S1      
327P12V_AUX         PD109 -C          A01X+121973Y+027168X0850Y0890R270 S1      
327P12V_AUX         PC868 -1          A01X+120874Y+027523X0198Y0197R090 S1      
327P12V_AUX         PU114 -1_2        A01X+120138Y+027354X0295Y0354R270 S1      
327P12V_AUX         PD48  -C          A01X+120988Y+024257X0850Y0890     S1      
327P12V_AUX         PC427 -2          A01X+120290Y+022962X0400Y0500R180 S1      
327P12V_AUX         PC364 -1          A01X+120187Y+022432X0198Y0197R180 S1      
327P12V_AUX         PD108 -C          A01X+132209Y+027168X0850Y0890R270 S1      
327P12V_AUX         PC858 -1          A01X+131110Y+027523X0198Y0197R090 S1      
327P12V_AUX         PU113 -1_2        A01X+130374Y+027354X0295Y0354R270 S1      
327P12V_AUX         PD49  -C          A01X+131224Y+024257X0850Y0890     S1      
327P12V_AUX         PC425 -2          A01X+130526Y+022962X0400Y0500R180 S1      
327P12V_AUX         PC436 -1          A01X+130423Y+022432X0198Y0197R180 S1      
327P12V_AUX         PD116 -C          A01X+147209Y+027168X0850Y0890R270 S1      
327P12V_AUX         PC888 -1          A01X+146110Y+027523X0198Y0197R090 S1      
327P12V_AUX         PU115 -1_2        A01X+145374Y+027354X0295Y0354R270 S1      
327P12V_AUX         PD41  -C          A01X+146224Y+024257X0850Y0890     S1      
327P12V_AUX         PC413 -2          A01X+145526Y+022962X0400Y0500R180 S1      
327P12V_AUX         PC412 -1          A01X+145423Y+022432X0198Y0197R180 S1      
327P12V_AUX         PD117 -C          A01X+157446Y+027168X0850Y0890R270 S1      
327P12V_AUX         PC889 -1          A01X+156347Y+027523X0198Y0197R090 S1      
327P12V_AUX         PU116 -1_2        A01X+155610Y+027354X0295Y0354R270 S1      
327P12V_AUX         PD45  -C          A01X+156460Y+024257X0850Y0890     S1      
327P12V_AUX         PC437 -2          A01X+155762Y+022962X0400Y0500R180 S1      
327P12V_AUX         PC424 -1          A01X+155660Y+022432X0198Y0197R180 S1      
327P12V_AUX         PD37  -C          A01X+167682Y+027168X0850Y0890R270 S1      
327P12V_AUX         PC878 -1          A01X+166583Y+027523X0198Y0197R090 S1      
327P12V_AUX         PU117 -1_2        A01X+165847Y+027354X0295Y0354R270 S1      
327P12V_AUX         PD121 -C          A01X+166697Y+024257X0850Y0890     S1      
327P12V_AUX         PC439 -2          A01X+165998Y+022962X0400Y0500R180 S1      
327P12V_AUX         PC426 -1          A01X+165896Y+022432X0198Y0197R180 S1      
327P12V_AUX         PD120 -C          A01X+177918Y+027168X0850Y0890R270 S1      
327P12V_AUX         PU118 -1_2        A01X+176083Y+027354X0295Y0354R270 S1      
327P12V_AUX         PC879 -1          A01X+176819Y+027523X0198Y0197R090 S1      
327P12V_AUX         PD40  -C          A01X+176933Y+024257X0850Y0890     S1      
327P12V_AUX         PC403 -2          A01X+176234Y+022962X0400Y0500R180 S1      
327P12V_AUX         PC438 -1          A01X+176132Y+022432X0198Y0197R180 S1      
317P12V_AUX         VIA   -    MD0100PA00X+009409Y+026820X0200Y         S0      
317P12V_AUX         VIA   -    MD0100PA00X+009129Y+026820X0200Y         S0      
317P12V_AUX         VIA   -    MD0100PA00X+008879Y+026820X0200Y         S0      
317P12V_AUX         VIA   -    MD0100PA00X+008879Y+027070X0200Y         S0      
317P12V_AUX         VIA   -    MD0100PA00X+009129Y+027070X0200Y         S0      
317P12V_AUX         VIA   -    MD0100PA00X+009409Y+027070X0200Y         S0      
317P12V_AUX         VIA   -    MD0100PA00X+010025Y+026590X0200Y         S0      
317P12V_AUX         VIA   -    MD0100PA00X+009775Y+026590X0200Y         S0      
317P12V_AUX         VIA   -    MD0100PA00X+009359Y+024876X0200Y    R180 S0      
317P12V_AUX         VIA   -    MD0100PA00X+008859Y+024876X0200Y    R180 S0      
317P12V_AUX         VIA   -    MD0100PA00X+009109Y+024876X0200Y    R180 S0      
317P12V_AUX         VIA   -    MD0100PA00X+008865Y+023619X0200Y    R180 S0      
317P12V_AUX         VIA   -    MD0100PA00X+009115Y+023619X0200Y    R180 S0      
317P12V_AUX         VIA   -    MD0100PA00X+009365Y+023619X0200Y    R180 S0      
317P12V_AUX         VIA   -    MD0100PA00X+009198Y+022171X0200Y    R180 S0      
317P12V_AUX         VIA   -    MD0100PA00X+009633Y+022164X0200Y         S0      
317P12V_AUX         VIA   -    MD0100PA00X+008810Y+022822X0200Y         S0      
317P12V_AUX         VIA   -    M      A01X+008810Y+023102X0200Y         S2      
017P12V_AUX         VIA   -    M      A18X+008810Y+023102X0260Y         S2      
017P12V_AUX               -    MD0100PA00X+008810Y+023102                       
317P12V_AUX         VIA   -    MD0100PA00X+008640Y+022442X0200Y         S0      
317P12V_AUX         VIA   -    MD0100PA00X+008698Y+022171X0200Y    R180 S0      
317P12V_AUX         VIA   -    MD0100PA00X+008948Y+022171X0200Y    R180 S0      
317P12V_AUX         VIA   -    MD0100PA00X+009185Y+020677X0200Y    R180 S0      
317P12V_AUX         VIA   -    MD0100PA00X+008685Y+020677X0200Y    R180 S0      
317P12V_AUX         VIA   -    MD0100PA00X+008935Y+020677X0200Y    R180 S0      
317P12V_AUX         VIA   -    MD0100PA00X+019115Y+026820X0200Y         S0      
317P12V_AUX         VIA   -    MD0100PA00X+019115Y+027070X0200Y         S0      
317P12V_AUX         VIA   -    MD0100PA00X+019365Y+027070X0200Y         S0      
317P12V_AUX         VIA   -    MD0100PA00X+019645Y+027070X0200Y         S0      
317P12V_AUX         VIA   -    MD0100PA00X+019365Y+026820X0200Y         S0      
317P12V_AUX         VIA   -    MD0100PA00X+019645Y+026820X0200Y         S0      
317P12V_AUX         VIA   -    MD0100PA00X+019595Y+024876X0200Y    R180 S0      
317P12V_AUX         VIA   -    MD0100PA00X+019345Y+024876X0200Y    R180 S0      
317P12V_AUX         VIA   -    MD0100PA00X+019095Y+024876X0200Y    R180 S0      
317P12V_AUX         VIA   -    MD0100PA00X+019601Y+023619X0200Y    R180 S0      
317P12V_AUX         VIA   -    MD0100PA00X+019351Y+023619X0200Y    R180 S0      
317P12V_AUX         VIA   -    MD0100PA00X+019101Y+023619X0200Y    R180 S0      
317P12V_AUX         VIA   -    MD0100PA00X+018934Y+022171X0200Y    R180 S0      
317P12V_AUX         VIA   -    MD0100PA00X+018876Y+022442X0200Y         S0      
317P12V_AUX         VIA   -    MD0100PA00X+019184Y+022171X0200Y    R180 S0      
317P12V_AUX         VIA   -    MD0100PA00X+019046Y+023102X0200Y         S0      
317P12V_AUX         VIA   -    MD0100PA00X+019046Y+022822X0200Y         S0      
317P12V_AUX         VIA   -    MD0100PA00X+019870Y+022164X0200Y         S0      
317P12V_AUX         VIA   -    MD0100PA00X+019434Y+022171X0200Y    R180 S0      
317P12V_AUX         VIA   -    MD0100PA00X+019422Y+020677X0200Y    R180 S0      
317P12V_AUX         VIA   -    MD0100PA00X+019172Y+020677X0200Y    R180 S0      
317P12V_AUX         VIA   -    MD0100PA00X+018922Y+020677X0200Y    R180 S0      
317P12V_AUX         VIA   -    MD0100PA00X+020261Y+026590X0200Y         S0      
317P12V_AUX         VIA   -    MD0100PA00X+020011Y+026590X0200Y         S0      
317P12V_AUX         VIA   -    MD0100PA00X+029601Y+026820X0200Y         S0      
317P12V_AUX         VIA   -    MD0100PA00X+029351Y+026820X0200Y         S0      
317P12V_AUX         VIA   -    MD0100PA00X+029351Y+027070X0200Y         S0      
317P12V_AUX         VIA   -    MD0100PA00X+029601Y+027070X0200Y         S0      
317P12V_AUX         VIA   -    MD0100PA00X+029581Y+024876X0200Y    R180 S0      
317P12V_AUX         VIA   -    MD0100PA00X+029331Y+024876X0200Y    R180 S0      
317P12V_AUX         VIA   -    MD0100PA00X+029587Y+023619X0200Y    R180 S0      
317P12V_AUX         VIA   -    MD0100PA00X+029337Y+023619X0200Y    R180 S0      
317P12V_AUX         VIA   -    MD0100PA00X+029171Y+022171X0200Y    R180 S0      
317P12V_AUX         VIA   -    MD0100PA00X+029112Y+022442X0200Y         S0      
317P12V_AUX         VIA   -    MD0100PA00X+029421Y+022171X0200Y    R180 S0      
317P12V_AUX         VIA   -    MD0100PA00X+029282Y+023102X0200Y         S0      
317P12V_AUX         VIA   -    MD0100PA00X+029282Y+022822X0200Y         S0      
317P12V_AUX         VIA   -    MD0100PA00X+029671Y+022171X0200Y    R180 S0      
317P12V_AUX         VIA   -    MD0100PA00X+029658Y+020677X0200Y    R180 S0      
317P12V_AUX         VIA   -    MD0100PA00X+029408Y+020677X0200Y    R180 S0      
317P12V_AUX         VIA   -    MD0100PA00X+029158Y+020677X0200Y    R180 S0      
317P12V_AUX         VIA   -    MD0100PA00X+029881Y+026820X0200Y         S0      
317P12V_AUX         VIA   -    MD0100PA00X+029881Y+027070X0200Y         S0      
317P12V_AUX         VIA   -    MD0100PA00X+030497Y+026590X0200Y         S0      
317P12V_AUX         VIA   -    MD0100PA00X+030247Y+026590X0200Y         S0      
317P12V_AUX         VIA   -    MD0100PA00X+029831Y+024876X0200Y    R180 S0      
317P12V_AUX         VIA   -    MD0100PA00X+029837Y+023619X0200Y    R180 S0      
317P12V_AUX         VIA   -    MD0100PA00X+030106Y+022164X0200Y         S0      
317P12V_AUX         VIA   -    MD0100PA00X+039348Y+022442X0200Y         S0      
317P12V_AUX         VIA   -    MD0100PA00X+039407Y+022171X0200Y    R180 S0      
317P12V_AUX         VIA   -    MD0100PA00X+039518Y+023102X0200Y         S0      
317P12V_AUX         VIA   -    MD0100PA00X+039394Y+020677X0200Y    R180 S0      
317P12V_AUX         VIA   -    MD0100PA00X+039837Y+027070X0200Y         S0      
317P12V_AUX         VIA   -    MD0100PA00X+039587Y+027070X0200Y         S0      
317P12V_AUX         VIA   -    MD0100PA00X+039587Y+026820X0200Y         S0      
317P12V_AUX         VIA   -    MD0100PA00X+039837Y+026820X0200Y         S0      
317P12V_AUX         VIA   -    MD0100PA00X+040117Y+027070X0200Y         S0      
317P12V_AUX         VIA   -    MD0100PA00X+040117Y+026820X0200Y         S0      
317P12V_AUX         VIA   -    MD0100PA00X+040483Y+026590X0200Y         S0      
317P12V_AUX         VIA   -    MD0100PA00X+040733Y+026590X0200Y         S0      
317P12V_AUX         VIA   -    MD0100PA00X+039568Y+024876X0200Y    R180 S0      
317P12V_AUX         VIA   -    MD0100PA00X+039818Y+024876X0200Y    R180 S0      
317P12V_AUX         VIA   -    MD0100PA00X+040068Y+024876X0200Y    R180 S0      
317P12V_AUX         VIA   -    MD0100PA00X+039574Y+023619X0200Y    R180 S0      
317P12V_AUX         VIA   -    MD0100PA00X+039824Y+023619X0200Y    R180 S0      
317P12V_AUX         VIA   -    MD0100PA00X+040074Y+023619X0200Y    R180 S0      
317P12V_AUX         VIA   -    MD0100PA00X+040342Y+022164X0200Y         S0      
317P12V_AUX         VIA   -    MD0100PA00X+039657Y+022171X0200Y    R180 S0      
317P12V_AUX         VIA   -    MD0100PA00X+039907Y+022171X0200Y    R180 S0      
317P12V_AUX         VIA   -    MD0100PA00X+039518Y+022822X0200Y         S0      
317P12V_AUX         VIA   -    MD0100PA00X+039644Y+020677X0200Y    R180 S0      
317P12V_AUX         VIA   -    MD0100PA00X+039894Y+020677X0200Y    R180 S0      
317P12V_AUX         VIA   -    MD0100PA00X+054587Y+027070X0200Y         S0      
317P12V_AUX         VIA   -    MD0100PA00X+054837Y+027070X0200Y         S0      
317P12V_AUX         VIA   -    MD0100PA00X+055117Y+026820X0200Y         S0      
317P12V_AUX         VIA   -    MD0100PA00X+055483Y+026590X0200Y         S0      
317P12V_AUX         VIA   -    MD0100PA00X+055117Y+027070X0200Y         S0      
317P12V_AUX         VIA   -    MD0100PA00X+054837Y+026820X0200Y         S0      
317P12V_AUX         VIA   -    MD0100PA00X+054587Y+026820X0200Y         S0      
317P12V_AUX         VIA   -    MD0100PA00X+054568Y+024876X0200Y    R180 S0      
317P12V_AUX         VIA   -    MD0100PA00X+054818Y+024876X0200Y    R180 S0      
317P12V_AUX         VIA   -    MD0100PA00X+055068Y+024876X0200Y    R180 S0      
317P12V_AUX         VIA   -    MD0100PA00X+054574Y+023619X0200Y    R180 S0      
317P12V_AUX         VIA   -    MD0100PA00X+054824Y+023619X0200Y    R180 S0      
317P12V_AUX         VIA   -    MD0100PA00X+055074Y+023619X0200Y    R180 S0      
317P12V_AUX         VIA   -    MD0100PA00X+054348Y+022442X0200Y         S0      
317P12V_AUX         VIA   -    MD0100PA00X+054407Y+022171X0200Y    R180 S0      
317P12V_AUX         VIA   -    MD0100PA00X+054518Y+022822X0200Y         S0      
317P12V_AUX         VIA   -    MD0100PA00X+054518Y+023102X0200Y         S0      
317P12V_AUX         VIA   -    MD0100PA00X+055342Y+022164X0200Y         S0      
317P12V_AUX         VIA   -    MD0100PA00X+054657Y+022171X0200Y    R180 S0      
317P12V_AUX         VIA   -    MD0100PA00X+054907Y+022171X0200Y    R180 S0      
317P12V_AUX         VIA   -    MD0100PA00X+054394Y+020677X0200Y    R180 S0      
317P12V_AUX         VIA   -    MD0100PA00X+054644Y+020677X0200Y    R180 S0      
317P12V_AUX         VIA   -    MD0100PA00X+054894Y+020677X0200Y    R180 S0      
317P12V_AUX         VIA   -    MD0100PA00X+055733Y+026590X0200Y         S0      
317P12V_AUX         VIA   -    MD0100PA00X+065143Y+022171X0200Y    R180 S0      
317P12V_AUX         VIA   -    MD0100PA00X+064643Y+022171X0200Y    R180 S0      
317P12V_AUX         VIA   -    M      A01X+064755Y+023102X0200Y         S2      
017P12V_AUX         VIA   -    M      A18X+064755Y+023102X0260Y         S2      
017P12V_AUX               -    MD0100PA00X+064755Y+023102                       
317P12V_AUX         VIA   -    MD0100PA00X+064585Y+022442X0200Y         S0      
317P12V_AUX         VIA   -    MD0100PA00X+064755Y+022822X0200Y         S0      
317P12V_AUX         VIA   -    MD0100PA00X+064893Y+022171X0200Y    R180 S0      
317P12V_AUX         VIA   -    MD0100PA00X+064880Y+020677X0200Y    R180 S0      
317P12V_AUX         VIA   -    MD0100PA00X+065130Y+020677X0200Y    R180 S0      
317P12V_AUX         VIA   -    MD0100PA00X+064630Y+020677X0200Y    R180 S0      
317P12V_AUX         VIA   -    MD0100PA00X+064824Y+026820X0200Y         S0      
317P12V_AUX         VIA   -    MD0100PA00X+064824Y+027070X0200Y         S0      
317P12V_AUX         VIA   -    MD0100PA00X+065074Y+027070X0200Y         S0      
317P12V_AUX         VIA   -    MD0100PA00X+065354Y+026820X0200Y         S0      
317P12V_AUX         VIA   -    MD0100PA00X+065354Y+027070X0200Y         S0      
317P12V_AUX         VIA   -    MD0100PA00X+065074Y+026820X0200Y         S0      
317P12V_AUX         VIA   -    MD0100PA00X+064804Y+024876X0200Y    R180 S0      
317P12V_AUX         VIA   -    MD0100PA00X+065054Y+024876X0200Y    R180 S0      
317P12V_AUX         VIA   -    MD0100PA00X+065304Y+024876X0200Y    R180 S0      
317P12V_AUX         VIA   -    MD0100PA00X+065310Y+023619X0200Y    R180 S0      
317P12V_AUX         VIA   -    MD0100PA00X+064810Y+023619X0200Y    R180 S0      
317P12V_AUX         VIA   -    MD0100PA00X+065060Y+023619X0200Y    R180 S0      
317P12V_AUX         VIA   -    MD0100PA00X+065970Y+026590X0200Y         S0      
317P12V_AUX         VIA   -    MD0100PA00X+065720Y+026590X0200Y         S0      
317P12V_AUX         VIA   -    MD0100PA00X+065578Y+022164X0200Y         S0      
317P12V_AUX         VIA   -    MD0100PA00X+075060Y+027070X0200Y         S0      
317P12V_AUX         VIA   -    MD0100PA00X+075060Y+026820X0200Y         S0      
317P12V_AUX         VIA   -    MD0100PA00X+075040Y+024876X0200Y         S0      
317P12V_AUX         VIA   -    MD0100PA00X+075046Y+023619X0200Y    R180 S0      
317P12V_AUX         VIA   -    MD0100PA00X+074879Y+022171X0200Y    R180 S0      
317P12V_AUX         VIA   -    MD0100PA00X+074821Y+022442X0200Y         S0      
317P12V_AUX         VIA   -    MD0100PA00X+075129Y+022171X0200Y    R180 S0      
317P12V_AUX         VIA   -    MD0100PA00X+074991Y+023102X0200Y         S0      
317P12V_AUX         VIA   -    MD0100PA00X+074991Y+022822X0200Y         S0      
317P12V_AUX         VIA   -    MD0100PA00X+074866Y+020677X0200Y    R180 S0      
317P12V_AUX         VIA   -    MD0100PA00X+075116Y+020677X0200Y    R180 S0      
317P12V_AUX         VIA   -    MD0100PA00X+076206Y+026590X0200Y         S0      
317P12V_AUX         VIA   -    MD0100PA00X+075956Y+026590X0200Y         S0      
317P12V_AUX         VIA   -    MD0100PA00X+075590Y+027070X0200Y         S0      
317P12V_AUX         VIA   -    MD0100PA00X+075310Y+027070X0200Y         S0      
317P12V_AUX         VIA   -    MD0100PA00X+075590Y+026820X0200Y         S0      
317P12V_AUX         VIA   -    MD0100PA00X+075310Y+026820X0200Y         S0      
317P12V_AUX         VIA   -    MD0100PA00X+075290Y+024876X0200Y         S0      
317P12V_AUX         VIA   -    MD0100PA00X+075540Y+024876X0200Y         S0      
317P12V_AUX         VIA   -    MD0100PA00X+075546Y+023619X0200Y    R180 S0      
317P12V_AUX         VIA   -    MD0100PA00X+075296Y+023619X0200Y    R180 S0      
317P12V_AUX         VIA   -    MD0100PA00X+075814Y+022164X0200Y         S0      
317P12V_AUX         VIA   -    MD0100PA00X+075379Y+022171X0200Y    R180 S0      
317P12V_AUX         VIA   -    MD0100PA00X+075366Y+020677X0200Y    R180 S0      
317P12V_AUX         VIA   -    MD0100PA00X+085546Y+026820X0200Y         S0      
317P12V_AUX         VIA   -    MD0100PA00X+086192Y+026590X0200Y         S0      
317P12V_AUX         VIA   -    MD0100PA00X+085826Y+027070X0200Y         S0      
317P12V_AUX         VIA   -    MD0100PA00X+085826Y+026820X0200Y         S0      
317P12V_AUX         VIA   -    MD0100PA00X+086442Y+026590X0200Y         S0      
317P12V_AUX         VIA   -    MD0100PA00X+085546Y+027070X0200Y         S0      
317P12V_AUX         VIA   -    MD0100PA00X+085296Y+027070X0200Y         S0      
317P12V_AUX         VIA   -    MD0100PA00X+085296Y+026820X0200Y         S0      
317P12V_AUX         VIA   -    MD0100PA00X+085776Y+024876X0200Y    R180 S0      
317P12V_AUX         VIA   -    MD0100PA00X+085526Y+024876X0200Y    R180 S0      
317P12V_AUX         VIA   -    MD0100PA00X+085276Y+024876X0200Y    R180 S0      
317P12V_AUX         VIA   -    MD0100PA00X+085782Y+023619X0200Y    R180 S0      
317P12V_AUX         VIA   -    MD0100PA00X+085532Y+023619X0200Y    R180 S0      
317P12V_AUX         VIA   -    MD0100PA00X+085282Y+023619X0200Y    R180 S0      
317P12V_AUX         VIA   -    MD0100PA00X+085116Y+022171X0200Y    R180 S0      
317P12V_AUX         VIA   -    MD0100PA00X+085057Y+022442X0200Y         S0      
317P12V_AUX         VIA   -    MD0100PA00X+085616Y+022171X0200Y    R180 S0      
317P12V_AUX         VIA   -    MD0100PA00X+085366Y+022171X0200Y    R180 S0      
317P12V_AUX         VIA   -    M      A01X+085227Y+023102X0200Y         S2      
017P12V_AUX         VIA   -    M      A18X+085227Y+023102X0260Y         S2      
017P12V_AUX               -    MD0100PA00X+085227Y+023102                       
317P12V_AUX         VIA   -    MD0100PA00X+085227Y+022822X0200Y         S0      
317P12V_AUX         VIA   -    MD0100PA00X+086051Y+022164X0200Y         S0      
317P12V_AUX         VIA   -    MD0100PA00X+085103Y+020677X0200Y    R180 S0      
317P12V_AUX         VIA   -    MD0100PA00X+085603Y+020677X0200Y    R180 S0      
317P12V_AUX         VIA   -    MD0100PA00X+085353Y+020677X0200Y    R180 S0      
317P12V_AUX         VIA   -    MD0100PA00X+100546Y+027070X0200Y         S0      
317P12V_AUX         VIA   -    MD0100PA00X+100296Y+027070X0200Y         S0      
317P12V_AUX         VIA   -    MD0100PA00X+100826Y+027070X0200Y         S0      
317P12V_AUX         VIA   -    MD0100PA00X+100296Y+026820X0200Y         S0      
317P12V_AUX         VIA   -    MD0100PA00X+100546Y+026820X0200Y         S0      
317P12V_AUX         VIA   -    MD0100PA00X+100826Y+026820X0200Y         S0      
317P12V_AUX         VIA   -    MD0100PA00X+100776Y+024876X0200Y    R180 S0      
317P12V_AUX         VIA   -    MD0100PA00X+100526Y+024876X0200Y    R180 S0      
317P12V_AUX         VIA   -    MD0100PA00X+100276Y+024876X0200Y    R180 S0      
317P12V_AUX         VIA   -    MD0100PA00X+100782Y+023619X0200Y    R180 S0      
317P12V_AUX         VIA   -    MD0100PA00X+100532Y+023619X0200Y    R180 S0      
317P12V_AUX         VIA   -    MD0100PA00X+100282Y+023619X0200Y    R180 S0      
317P12V_AUX         VIA   -    MD0100PA00X+100116Y+022171X0200Y    R180 S0      
317P12V_AUX         VIA   -    MD0100PA00X+100057Y+022442X0200Y         S0      
317P12V_AUX         VIA   -    MD0100PA00X+100616Y+022171X0200Y    R180 S0      
317P12V_AUX         VIA   -    MD0100PA00X+100366Y+022171X0200Y    R180 S0      
317P12V_AUX         VIA   -    MD0100PA00X+101051Y+022164X0200Y         S0      
317P12V_AUX         VIA   -    MD0100PA00X+100227Y+023102X0200Y         S0      
317P12V_AUX         VIA   -    MD0100PA00X+100227Y+022822X0200Y         S0      
317P12V_AUX         VIA   -    MD0100PA00X+100103Y+020677X0200Y    R180 S0      
317P12V_AUX         VIA   -    MD0100PA00X+100603Y+020677X0200Y    R180 S0      
317P12V_AUX         VIA   -    MD0100PA00X+100353Y+020677X0200Y    R180 S0      
317P12V_AUX         VIA   -    MD0100PA00X+101192Y+026590X0200Y         S0      
317P12V_AUX         VIA   -    MD0100PA00X+101442Y+026590X0200Y         S0      
317P12V_AUX         VIA   -    MD0100PA00X+110463Y+023102X0200Y         S0      
317P12V_AUX         VIA   -    MD0100PA00X+110352Y+022171X0200Y    R180 S0      
317P12V_AUX         VIA   -    MD0100PA00X+110293Y+022442X0200Y         S0      
317P12V_AUX         VIA   -    MD0100PA00X+110852Y+022171X0200Y    R180 S0      
317P12V_AUX         VIA   -    MD0100PA00X+110339Y+020677X0200Y    R180 S0      
317P12V_AUX         VIA   -    MD0100PA00X+110839Y+020677X0200Y    R180 S0      
317P12V_AUX         VIA   -    MD0100PA00X+110589Y+020677X0200Y    R180 S0      
317P12V_AUX         VIA   -    MD0100PA00X+110782Y+027070X0200Y         S0      
317P12V_AUX         VIA   -    MD0100PA00X+110532Y+027070X0200Y         S0      
317P12V_AUX         VIA   -    MD0100PA00X+110532Y+026820X0200Y         S0      
317P12V_AUX         VIA   -    MD0100PA00X+110782Y+026820X0200Y         S0      
317P12V_AUX         VIA   -    MD0100PA00X+110762Y+024876X0200Y    R180 S0      
317P12V_AUX         VIA   -    MD0100PA00X+110512Y+024876X0200Y    R180 S0      
317P12V_AUX         VIA   -    MD0100PA00X+110768Y+023619X0200Y    R180 S0      
317P12V_AUX         VIA   -    MD0100PA00X+110518Y+023619X0200Y    R180 S0      
317P12V_AUX         VIA   -    MD0100PA00X+110602Y+022171X0200Y    R180 S0      
317P12V_AUX         VIA   -    MD0100PA00X+110463Y+022822X0200Y         S0      
317P12V_AUX         VIA   -    MD0100PA00X+111062Y+027070X0200Y         S0      
317P12V_AUX         VIA   -    MD0100PA00X+111062Y+026820X0200Y         S0      
317P12V_AUX         VIA   -    MD0100PA00X+111428Y+026590X0200Y         S0      
317P12V_AUX         VIA   -    MD0100PA00X+111678Y+026590X0200Y         S0      
317P12V_AUX         VIA   -    MD0100PA00X+111012Y+024876X0200Y    R180 S0      
317P12V_AUX         VIA   -    MD0100PA00X+111018Y+023619X0200Y    R180 S0      
317P12V_AUX         VIA   -    MD0100PA00X+111287Y+022164X0200Y         S0      
317P12V_AUX         VIA   -    MD0100PA00X+120700Y+023102X0200Y         S0      
317P12V_AUX         VIA   -    MD0100PA00X+120588Y+022171X0200Y    R180 S0      
317P12V_AUX         VIA   -    MD0100PA00X+120530Y+022442X0200Y         S0      
317P12V_AUX         VIA   -    MD0100PA00X+120575Y+020677X0200Y    R180 S0      
317P12V_AUX         VIA   -    MD0100PA00X+121018Y+027070X0200Y         S0      
317P12V_AUX         VIA   -    MD0100PA00X+120768Y+027070X0200Y         S0      
317P12V_AUX         VIA   -    MD0100PA00X+121298Y+027070X0200Y         S0      
317P12V_AUX         VIA   -    MD0100PA00X+120768Y+026820X0200Y         S0      
317P12V_AUX         VIA   -    MD0100PA00X+121018Y+026820X0200Y         S0      
317P12V_AUX         VIA   -    MD0100PA00X+121298Y+026820X0200Y         S0      
317P12V_AUX         VIA   -    MD0100PA00X+121664Y+026590X0200Y         S0      
317P12V_AUX         VIA   -    MD0100PA00X+121914Y+026590X0200Y         S0      
317P12V_AUX         VIA   -    MD0100PA00X+121249Y+024876X0200Y    R180 S0      
317P12V_AUX         VIA   -    MD0100PA00X+120999Y+024876X0200Y    R180 S0      
317P12V_AUX         VIA   -    MD0100PA00X+120749Y+024876X0200Y    R180 S0      
317P12V_AUX         VIA   -    MD0100PA00X+121255Y+023619X0200Y    R180 S0      
317P12V_AUX         VIA   -    MD0100PA00X+121005Y+023619X0200Y    R180 S0      
317P12V_AUX         VIA   -    MD0100PA00X+120755Y+023619X0200Y    R180 S0      
317P12V_AUX         VIA   -    MD0100PA00X+121088Y+022171X0200Y    R180 S0      
317P12V_AUX         VIA   -    MD0100PA00X+120838Y+022171X0200Y    R180 S0      
317P12V_AUX         VIA   -    MD0100PA00X+120700Y+022822X0200Y         S0      
317P12V_AUX         VIA   -    MD0100PA00X+121523Y+022164X0200Y         S0      
317P12V_AUX         VIA   -    MD0100PA00X+121075Y+020677X0200Y    R180 S0      
317P12V_AUX         VIA   -    MD0100PA00X+120825Y+020677X0200Y    R180 S0      
317P12V_AUX         VIA   -    MD0100PA00X+131535Y+027070X0200Y         S0      
317P12V_AUX         VIA   -    MD0100PA00X+131005Y+027070X0200Y         S0      
317P12V_AUX         VIA   -    MD0100PA00X+131255Y+027070X0200Y         S0      
317P12V_AUX         VIA   -    MD0100PA00X+131901Y+026590X0200Y         S0      
317P12V_AUX         VIA   -    MD0100PA00X+131535Y+026820X0200Y         S0      
317P12V_AUX         VIA   -    MD0100PA00X+131255Y+026820X0200Y         S0      
317P12V_AUX         VIA   -    MD0100PA00X+131005Y+026820X0200Y         S0      
317P12V_AUX         VIA   -    MD0100PA00X+131485Y+024876X0200Y    R180 S0      
317P12V_AUX         VIA   -    MD0100PA00X+130985Y+024876X0200Y    R180 S0      
317P12V_AUX         VIA   -    MD0100PA00X+131235Y+024876X0200Y    R180 S0      
317P12V_AUX         VIA   -    MD0100PA00X+131241Y+023619X0200Y    R180 S0      
317P12V_AUX         VIA   -    MD0100PA00X+131491Y+023619X0200Y    R180 S0      
317P12V_AUX         VIA   -    MD0100PA00X+130991Y+023619X0200Y    R180 S0      
317P12V_AUX         VIA   -    MD0100PA00X+130766Y+022442X0200Y         S0      
317P12V_AUX         VIA   -    MD0100PA00X+130824Y+022171X0200Y    R180 S0      
317P12V_AUX         VIA   -    MD0100PA00X+131759Y+022164X0200Y         S0      
317P12V_AUX         VIA   -    MD0100PA00X+130936Y+022822X0200Y         S0      
317P12V_AUX         VIA   -    M      A01X+130936Y+023102X0200Y         S2      
017P12V_AUX         VIA   -    M      A18X+130936Y+023102X0260Y         S2      
017P12V_AUX               -    MD0100PA00X+130936Y+023102                       
317P12V_AUX         VIA   -    MD0100PA00X+131074Y+022171X0200Y    R180 S0      
317P12V_AUX         VIA   -    MD0100PA00X+131324Y+022171X0200Y    R180 S0      
317P12V_AUX         VIA   -    MD0100PA00X+131061Y+020677X0200Y    R180 S0      
317P12V_AUX         VIA   -    MD0100PA00X+131311Y+020677X0200Y    R180 S0      
317P12V_AUX         VIA   -    MD0100PA00X+130811Y+020677X0200Y    R180 S0      
317P12V_AUX         VIA   -    MD0100PA00X+132151Y+026590X0200Y         S0      
317P12V_AUX         VIA   -    MD0100PA00X+146535Y+026820X0200Y         S0      
317P12V_AUX         VIA   -    MD0100PA00X+146535Y+027070X0200Y         S0      
317P12V_AUX         VIA   -    MD0100PA00X+146255Y+026820X0200Y         S0      
317P12V_AUX         VIA   -    MD0100PA00X+146255Y+027070X0200Y         S0      
317P12V_AUX         VIA   -    MD0100PA00X+146005Y+026820X0200Y         S0      
317P12V_AUX         VIA   -    MD0100PA00X+146005Y+027070X0200Y         S0      
317P12V_AUX         VIA   -    MD0100PA00X+146235Y+024876X0200Y    R180 S0      
317P12V_AUX         VIA   -    MD0100PA00X+146485Y+024876X0200Y    R180 S0      
317P12V_AUX         VIA   -    MD0100PA00X+145985Y+024876X0200Y    R180 S0      
317P12V_AUX         VIA   -    MD0100PA00X+146241Y+023619X0200Y    R180 S0      
317P12V_AUX         VIA   -    MD0100PA00X+146491Y+023619X0200Y    R180 S0      
317P12V_AUX         VIA   -    MD0100PA00X+145991Y+023619X0200Y    R180 S0      
317P12V_AUX         VIA   -    MD0100PA00X+145936Y+022822X0200Y         S0      
317P12V_AUX         VIA   -    MD0100PA00X+145936Y+023102X0200Y         S0      
317P12V_AUX         VIA   -    MD0100PA00X+145766Y+022442X0200Y         S0      
317P12V_AUX         VIA   -    MD0100PA00X+145824Y+022171X0200Y    R180 S0      
317P12V_AUX         VIA   -    MD0100PA00X+146074Y+022171X0200Y    R180 S0      
317P12V_AUX         VIA   -    MD0100PA00X+146324Y+022171X0200Y    R180 S0      
317P12V_AUX         VIA   -    MD0100PA00X+146061Y+020677X0200Y    R180 S0      
317P12V_AUX         VIA   -    MD0100PA00X+146311Y+020677X0200Y    R180 S0      
317P12V_AUX         VIA   -    MD0100PA00X+145811Y+020677X0200Y    R180 S0      
317P12V_AUX         VIA   -    MD0100PA00X+146901Y+026590X0200Y         S0      
317P12V_AUX         VIA   -    MD0100PA00X+147151Y+026590X0200Y         S0      
317P12V_AUX         VIA   -    MD0100PA00X+146759Y+022164X0200Y         S0      
317P12V_AUX         VIA   -    MD0100PA00X+156241Y+027070X0200Y         S0      
317P12V_AUX         VIA   -    MD0100PA00X+156241Y+026820X0200Y         S0      
317P12V_AUX         VIA   -    MD0100PA00X+156221Y+024876X0200Y    R180 S0      
317P12V_AUX         VIA   -    MD0100PA00X+156227Y+023619X0200Y    R180 S0      
317P12V_AUX         VIA   -    MD0100PA00X+156172Y+022822X0200Y         S0      
317P12V_AUX         VIA   -    MD0100PA00X+156172Y+023102X0200Y         S0      
317P12V_AUX         VIA   -    MD0100PA00X+156310Y+022171X0200Y    R180 S0      
317P12V_AUX         VIA   -    MD0100PA00X+156002Y+022442X0200Y         S0      
317P12V_AUX         VIA   -    MD0100PA00X+156060Y+022171X0200Y    R180 S0      
317P12V_AUX         VIA   -    MD0100PA00X+156298Y+020677X0200Y    R180 S0      
317P12V_AUX         VIA   -    MD0100PA00X+156048Y+020677X0200Y    R180 S0      
317P12V_AUX         VIA   -    MD0100PA00X+156491Y+026820X0200Y         S0      
317P12V_AUX         VIA   -    MD0100PA00X+156491Y+027070X0200Y         S0      
317P12V_AUX         VIA   -    MD0100PA00X+156771Y+026820X0200Y         S0      
317P12V_AUX         VIA   -    MD0100PA00X+157137Y+026590X0200Y         S0      
317P12V_AUX         VIA   -    MD0100PA00X+157387Y+026590X0200Y         S0      
317P12V_AUX         VIA   -    MD0100PA00X+156771Y+027070X0200Y         S0      
317P12V_AUX         VIA   -    MD0100PA00X+156721Y+024876X0200Y    R180 S0      
317P12V_AUX         VIA   -    MD0100PA00X+156471Y+024876X0200Y    R180 S0      
317P12V_AUX         VIA   -    MD0100PA00X+156727Y+023619X0200Y    R180 S0      
317P12V_AUX         VIA   -    MD0100PA00X+156477Y+023619X0200Y    R180 S0      
317P12V_AUX         VIA   -    MD0100PA00X+156996Y+022164X0200Y         S0      
317P12V_AUX         VIA   -    MD0100PA00X+156560Y+022171X0200Y    R180 S0      
317P12V_AUX         VIA   -    MD0100PA00X+156548Y+020677X0200Y    R180 S0      
317P12V_AUX         VIA   -    MD0100PA00X+166727Y+027070X0200Y         S0      
317P12V_AUX         VIA   -    MD0100PA00X+166957Y+024876X0200Y    R180 S0      
317P12V_AUX         VIA   -    MD0100PA00X+166457Y+024876X0200Y    R180 S0      
317P12V_AUX         VIA   -    MD0100PA00X+166707Y+024876X0200Y    R180 S0      
317P12V_AUX         VIA   -    MD0100PA00X+166463Y+023619X0200Y    R180 S0      
317P12V_AUX         VIA   -    MD0100PA00X+166713Y+023619X0200Y    R180 S0      
317P12V_AUX         VIA   -    MD0100PA00X+166963Y+023619X0200Y    R180 S0      
317P12V_AUX         VIA   -    MD0100PA00X+166238Y+022442X0200Y         S0      
317P12V_AUX         VIA   -    MD0100PA00X+166297Y+022171X0200Y    R180 S0      
317P12V_AUX         VIA   -    MD0100PA00X+167232Y+022164X0200Y         S0      
317P12V_AUX         VIA   -    MD0100PA00X+166408Y+022822X0200Y         S0      
317P12V_AUX         VIA   -    M      A01X+166408Y+023102X0200Y         S2      
017P12V_AUX         VIA   -    M      A18X+166408Y+023102X0260Y         S2      
017P12V_AUX               -    MD0100PA00X+166408Y+023102                       
317P12V_AUX         VIA   -    MD0100PA00X+166547Y+022171X0200Y    R180 S0      
317P12V_AUX         VIA   -    MD0100PA00X+166797Y+022171X0200Y    R180 S0      
317P12V_AUX         VIA   -    MD0100PA00X+166534Y+020677X0200Y    R180 S0      
317P12V_AUX         VIA   -    MD0100PA00X+166784Y+020677X0200Y    R180 S0      
317P12V_AUX         VIA   -    MD0100PA00X+166284Y+020677X0200Y    R180 S0      
317P12V_AUX         VIA   -    MD0100PA00X+166477Y+027070X0200Y         S0      
317P12V_AUX         VIA   -    MD0100PA00X+166477Y+026820X0200Y         S0      
317P12V_AUX         VIA   -    MD0100PA00X+166727Y+026820X0200Y         S0      
317P12V_AUX         VIA   -    MD0100PA00X+167007Y+027070X0200Y         S0      
317P12V_AUX         VIA   -    MD0100PA00X+167007Y+026820X0200Y         S0      
317P12V_AUX         VIA   -    MD0100PA00X+167373Y+026590X0200Y         S0      
317P12V_AUX         VIA   -    MD0100PA00X+167623Y+026590X0200Y         S0      
317P12V_AUX         VIA   -    MD0100PA00X+176713Y+026820X0200Y         S0      
317P12V_AUX         VIA   -    MD0100PA00X+176963Y+026820X0200Y         S0      
317P12V_AUX         VIA   -    MD0100PA00X+177243Y+027070X0200Y         S0      
317P12V_AUX         VIA   -    MD0100PA00X+177243Y+026820X0200Y         S0      
317P12V_AUX         VIA   -    MD0100PA00X+176963Y+027070X0200Y         S0      
317P12V_AUX         VIA   -    MD0100PA00X+176713Y+027070X0200Y         S0      
317P12V_AUX         VIA   -    MD0100PA00X+176694Y+024876X0200Y    R180 S0      
317P12V_AUX         VIA   -    MD0100PA00X+176944Y+024876X0200Y    R180 S0      
317P12V_AUX         VIA   -    MD0100PA00X+177194Y+024876X0200Y    R180 S0      
317P12V_AUX         VIA   -    MD0100PA00X+176700Y+023619X0200Y    R180 S0      
317P12V_AUX         VIA   -    MD0100PA00X+176950Y+023619X0200Y    R180 S0      
317P12V_AUX         VIA   -    MD0100PA00X+177200Y+023619X0200Y    R180 S0      
317P12V_AUX         VIA   -    MD0100PA00X+177468Y+022164X0200Y         S0      
317P12V_AUX         VIA   -    MD0100PA00X+176644Y+022822X0200Y         S0      
317P12V_AUX         VIA   -    MD0100PA00X+176644Y+023102X0200Y         S0      
317P12V_AUX         VIA   -    MD0100PA00X+176474Y+022442X0200Y         S0      
317P12V_AUX         VIA   -    MD0100PA00X+176783Y+022171X0200Y    R180 S0      
317P12V_AUX         VIA   -    MD0100PA00X+177033Y+022171X0200Y    R180 S0      
317P12V_AUX         VIA   -    MD0100PA00X+176533Y+022171X0200Y    R180 S0      
317P12V_AUX         VIA   -    MD0100PA00X+176770Y+020677X0200Y    R180 S0      
317P12V_AUX         VIA   -    MD0100PA00X+177020Y+020677X0200Y    R180 S0      
317P12V_AUX         VIA   -    MD0100PA00X+176520Y+020677X0200Y    R180 S0      
317P12V_AUX         VIA   -    MD0100PA00X+177609Y+026590X0200Y         S0      
317P12V_AUX         VIA   -    MD0100PA00X+177859Y+026590X0200Y         S0      
327P12V_AUX         R6779 -1          A01X+074333Y+163064X0198Y0197R090 S1      
327P12V_AUX         R6823 -2          A18X+098532Y+136188X0198Y0197R270 S2      
317m5146            VIA   -    MD0100PA01X+071537Y+140850X0180Y         S0      
317m5146            J5    -U3   D0122PA01X+064689Y+147910X0282Y    R180 S3      
327m5146            C382  -2          A01X+071547Y+140359X0120Y0150R090 S1      
317m5147            VIA   -    MD0080PA01X+073307Y+110138X0160Y    R270 S0      
327m5147            C253  -1          A01X+061068Y+049417X0120Y0150     S1      
317m5147            VIA   -    MD0100PA01X+060578Y+049407X0200Y    R270 S0      
327m5147            PEX1  -BB36       A01X+073307Y+110138X0180Y         S1      
317m5148            VIA   -    MD0080PA01X+067323Y+122854X0160Y         S0      
317m5148            VIA   -    MD0100PA01X+048052Y+134819X0180Y         S0      
327m5148            PEX1  -H20        A01X+067323Y+122854X0180Y         S1      
327m5148            C365  -1          A01X+048062Y+135309X0120Y0150R090 S1      
317m5149            VIA   -    MD0080PA01X+121634Y+109390X0160Y    R270 S0      
317m5149            VIA   -    MD0100PA01X+124557Y+059694X0200Y    R090 S0      
327m5149            C428  -1          A01X+124066Y+059684X0120Y0150R180 S1      
327m5149            PEX2  -BD43       A01X+121634Y+109390X0180Y         S1      
317m5150            J13   -X7   D0122PA01X+135705Y+146374X0282Y    R180 S3      
317m5150            VIA   -    MD0080PA01X+119764Y+124724X0160Y         S0      
327m5150            PEX2  -C38        A01X+119764Y+124724X0180Y         S1      
317m5151            VIA   -    MD0100PA01X+055396Y+138430X0180Y         S0      
317m5151            J12   -Q6   D0122PA01X+049965Y+149878X0282Y    R180 S3      
327m5151            C2248 -2          A01X+055406Y+137939X0120Y0150R090 S1      
317m5152            VIA   -    MD0080PA01X+075925Y+112008X0160Y    R270 S0      
327m5152            C234  -1          A01X+077317Y+051494X0120Y0150R180 S1      
317m5152            VIA   -    MD0100PA01X+077808Y+051484X0200Y    R090 S0      
327m5152            PEX1  -AU43       A01X+075925Y+112008X0180Y         S1      
317m5153            VIA   -    MD0080PA01X+062461Y+118740X0160Y         S0      
317m5153            VIA   -    MD0100PA01X+062629Y+139658X0180Y         S0      
327m5153            PEX1  -W7         A01X+062461Y+118740X0180Y         S1      
327m5153            C402  -1          A01X+062619Y+140149X0120Y0150R090 S1      
317m5154            VIA   -    MD0080PA01X+117894Y+109764X0160Y    R270 S0      
317m5154            VIA   -    MD0100PA01X+105246Y+046939X0200Y    R270 S0      
327m5154            C469  -1          A01X+105737Y+046929X0120Y0150     S1      
327m5154            PEX2  -BC33       A01X+117894Y+109764X0180Y         S1      
317m5155            J7    -N6   D0122PA01X+117516Y+151413X0282Y    R180 S3      
317m5155            VIA   -    MD0080PA01X+107421Y+125472X0160Y         S0      
327m5155            PEX2  -A5         A01X+107421Y+125472X0180Y         S1      
317m5156            VIA   -    MD0100PA01X+072421Y+138430X0180Y         S0      
317m5156            J5    -U4   D0122PA01X+065555Y+147831X0282Y    R180 S3      
327m5156            C380  -2          A01X+072411Y+137939X0120Y0150R090 S1      
317m5157            VIA   -    MD0100PA01X+059538Y+052769X0200Y    R270 S0      
327m5157            C246  -1          A01X+060028Y+052759X0120Y0150     S1      
317m5157            VIA   -    MD0080PA01X+074429Y+109764X0160Y    R270 S0      
327m5157            PEX1  -BC39       A01X+074429Y+109764X0180Y         S1      
317m5158            VIA   -    MD0080PA01X+062461Y+119488X0160Y         S0      
317m5158            VIA   -    MD0100PA01X+065077Y+137238X0180Y         S0      
327m5158            PEX1  -U7         A01X+062461Y+119488X0180Y         S1      
327m5158            C398  -1          A01X+065067Y+137729X0120Y0150R090 S1      
317m5159            VIA   -    MD0080PA01X+122008Y+110512X0160Y    R270 S0      
327m5159            C429  -1          A01X+123026Y+059332X0120Y0150R180 S1      
317m5159            VIA   -    MD0100PA01X+123517Y+059322X0200Y    R090 S0      
327m5159            PEX2  -BA44       A01X+122008Y+110512X0180Y         S1      
317m5160            J7    -O5   D0122PA01X+116650Y+150980X0282Y    R180 S3      
317m5160            VIA   -    MD0080PA01X+107047Y+124724X0160Y         S0      
327m5160            PEX2  -C4         A01X+107047Y+124724X0180Y         S1      
317m5161            VIA   -    MD0080PA01X+072933Y+109764X0160Y    R270 S0      
327m5161            C254  -1          A01X+060028Y+048346X0120Y0150     S1      
317m5161            VIA   -    MD0100PA01X+059538Y+048356X0200Y    R270 S0      
327m5161            PEX1  -BC35       A01X+072933Y+109764X0180Y         S1      
317m5162            VIA   -    MD0080PA01X+064705Y+123228X0160Y    R270 S0      
317m5162            VIA   -    MD0100PA01X+048936Y+134819X0180Y         S0      
327m5162            C350  -1          A01X+048926Y+135309X0120Y0150R090 S1      
327m5162            PEX1  -G13        A01X+064705Y+123228X0180Y         S1      
317m5163            VIA   -    MD0080PA01X+119764Y+110512X0160Y    R270 S0      
327m5163            C459  -1          A01X+106777Y+052053X0120Y0150     S1      
317m5163            VIA   -    MD0100PA01X+106286Y+052063X0200Y    R270 S0      
327m5163            PEX2  -BA38       A01X+119764Y+110512X0180Y         S1      
317m5164            VIA   -    MD0100PA01X+051384Y+136010X0180Y         S0      
317m5164            J12   -S1   D0122PA01X+045634Y+148933X0282Y    R180 S3      
327m5164            C2257 -2          A01X+051374Y+135519X0120Y0150R090 S1      
317m5165            VIA   -    MD0080PA01X+072185Y+109390X0160Y    R270 S0      
327m5165            C259  -1          A01X+060028Y+047289X0120Y0150     S1      
317m5165            VIA   -    MD0100PA01X+059538Y+047279X0200Y    R270 S0      
327m5165            PEX1  -BD33       A01X+072185Y+109390X0180Y         S1      
317m5166            VIA   -    MD0080PA01X+063209Y+120610X0160Y         S0      
317m5166            VIA   -    MD0100PA01X+067525Y+137238X0180Y         S0      
327m5166            C392  -1          A01X+067515Y+137729X0120Y0150R090 S1      
327m5166            PEX1  -P9         A01X+063209Y+120610X0180Y         S1      
317m5167            VIA   -    MD0080PA01X+123504Y+109016X0160Y    R270 S0      
327m5167            PEX2  -BE48       A01X+123504Y+109016X0180Y         S1      
317m5167            VIA   -    MD0100PA01X+123517Y+056488X0200Y    R090 S0      
327m5167            C437  -1          A01X+123026Y+056498X0120Y0150R180 S1      
317m5168            J7    -P3   D0122PA01X+114917Y+150468X0282Y    R180 S3      
317m5168            VIA   -    MD0080PA01X+105925Y+124724X0160Y         S0      
327m5168            PEX2  -C1         A01X+105925Y+124724X0180Y         S1      
317m5169            VIA   -    MD0080PA01X+075177Y+111634X0160Y    R270 S0      
327m5169            C232  -1          A01X+078358Y+052205X0120Y0150R180 S1      
317m5169            VIA   -    MD0100PA01X+078848Y+052195X0200Y    R090 S0      
327m5169            PEX1  -AV41       A01X+075177Y+111634X0180Y         S1      
317m5170            VIA   -    MD0080PA01X+065827Y+122480X0160Y         S0      
327m5170            C356  -1          A01X+044030Y+137729X0120Y0150R090 S1      
317m5170            VIA   -    MD0100PA01X+044040Y+137238X0180Y         S0      
327m5170            PEX1  -J16        A01X+065827Y+122480X0180Y         S1      
317m5171            VIA   -    MD0080PA01X+119390Y+109764X0160Y    R270 S0      
317m5171            VIA   -    MD0100PA01X+105246Y+051352X0200Y    R270 S0      
327m5171            C461  -1          A01X+105737Y+051342X0120Y0150     S1      
327m5171            PEX2  -BC37       A01X+119390Y+109764X0180Y         S1      
317m5172            J12   -M3   D0122PA01X+047366Y+156098X0282Y    R180 S3      
317m5172            VIA   -    MD0080PA01X+069567Y+124350X0160Y         S0      
327m5172            PEX1  -D26        A01X+069567Y+124350X0180Y         S1      
317m5173            VIA   -    MD0080PA01X+075551Y+111634X0160Y    R270 S0      
327m5173            C233  -1          A01X+078358Y+051845X0120Y0150R180 S1      
317m5173            VIA   -    MD0100PA01X+078848Y+051855X0200Y    R090 S0      
327m5173            PEX1  -AV42       A01X+075551Y+111634X0180Y         S1      
317m5174            VIA   -    MD0080PA01X+064331Y+122480X0160Y         S0      
317m5174            VIA   -    MD0100PA01X+047712Y+137238X0180Y         S0      
327m5174            C348  -1          A01X+047702Y+137729X0120Y0150R090 S1      
327m5174            PEX1  -J12        A01X+064331Y+122480X0180Y         S1      
317m5175            VIA   -    MD0080PA01X+114901Y+109764X0160Y    R270 S0      
327m5175            PEX2  -BC25       A01X+114902Y+109764X0180Y         S1      
317m5175            VIA   -    MD0100PA01X+106286Y+039100X0200Y    R270 S0      
327m5175            C485  -1          A01X+106777Y+039090X0120Y0150     S1      
317m5176            J5    -B8   D0122PA01X+069020Y+161650X0282Y    R180 S3      
317m5176            VIA   -    MD0080PA01X+060216Y+121358X0160Y         S0      
327m5176            PEX1  -M1         A01X+060216Y+121358X0180Y         S1      
317m5177            J7    -N4   D0122PA01X+115783Y+151413X0282Y    R180 S3      
317m5177            VIA   -    MD0080PA01X+106673Y+125472X0160Y         S0      
327m5177            PEX2  -A3         A01X+106673Y+125472X0180Y         S1      
317m5178            VIA   -    MD0080PA01X+069193Y+109764X0160Y    R270 S0      
327m5178            C274  -1          A01X+061068Y+039090X0120Y0150     S1      
317m5178            VIA   -    MD0100PA01X+060578Y+039100X0200Y    R270 S0      
327m5178            PEX1  -BC25       A01X+069193Y+109764X0180Y         S1      
317m5179            VIA   -    MD0080PA01X+062087Y+121732X0160Y         S0      
317m5179            VIA   -    MD0100PA01X+070313Y+137238X0180Y    R180 S0      
327m5179            PEX1  -L6         A01X+062087Y+121732X0180Y         S1      
327m5179            C387  -1          A01X+070323Y+137729X0120Y0150R090 S1      
317m5180            VIA   -    MD0080PA01X+116024Y+110138X0160Y    R270 S0      
327m5180            PEX2  -BB28       A01X+116024Y+110138X0180Y         S1      
327m5180            C480  -1          A01X+105737Y+041579X0120Y0150     S1      
317m5180            VIA   -    MD0100PA01X+105246Y+041569X0200Y    R270 S0      
317m5181            J5    -B6   D0122PA01X+067287Y+161650X0282Y    R180 S3      
317m5181            VIA   -    MD0080PA01X+060216Y+120610X0160Y         S0      
327m5181            PEX1  -P1         A01X+060216Y+120610X0180Y         S1      
317m5182            VIA   -    MD0100PA01X+007951Y+138430X0180Y         S0      
317m5182            J3    -I1   D0122PA01X+010988Y+158146X0282Y    R180 S3      
327m5182            C192  -2          A01X+007961Y+137939X0120Y0150R090 S1      
317m5183            VIA   -    MD0100PA01X+073645Y+136010X0180Y         S0      
317m5183            J5    -V5   D0122PA01X+066421Y+147398X0282Y    R180 S3      
327m5183            C378  -2          A01X+073635Y+135519X0120Y0150R090 S1      
317m5184            VIA   -    MD0080PA01X+072185Y+109764X0160Y    R270 S0      
327m5184            C258  -1          A01X+060028Y+046929X0120Y0150     S1      
317m5184            VIA   -    MD0100PA01X+059538Y+046939X0200Y    R270 S0      
327m5184            PEX1  -BC33       A01X+072185Y+109764X0180Y         S1      
317m5185            VIA   -    MD0080PA01X+061713Y+123228X0160Y    R270 S0      
317m5185            VIA   -    MD0100PA01X+073645Y+139649X0180Y         S0      
327m5185            C376  -1          A01X+073635Y+140140X0120Y0150R090 S1      
327m5185            PEX1  -G5         A01X+061713Y+123228X0180Y         S1      
317m5186            VIA   -    MD0080PA01X+120138Y+109390X0160Y    R270 S0      
327m5186            PEX2  -BD39       A01X+120138Y+109390X0180Y         S1      
327m5186            C458  -1          A01X+105737Y+053119X0120Y0150     S1      
317m5186            VIA   -    MD0100PA01X+105246Y+053109X0200Y    R270 S0      
317m5187            J12   -L4   D0122PA01X+048232Y+156532X0282Y    R180 S3      
317m5187            VIA   -    MD0080PA01X+069941Y+125098X0160Y    R090 S0      
327m5187            PEX1  -B27        A01X+069941Y+125098X0180Y         S1      
317m5188            J13   -X3   D0122PA01X+132240Y+146374X0282Y    R180 S3      
317m5188            VIA   -    MD0080PA01X+118268Y+124724X0160Y         S0      
327m5188            PEX2  -C34        A01X+118268Y+124724X0180Y         S1      
327m5189            C169  -1          A01X+016169Y+140149X0120Y0150R090 S1      
317m5189            VIA   -    MD0100PA01X+016179Y+139658X0180Y         S0      
317m5189            VIA   -    MD0080PA01X+015256Y+123228X0160Y    R270 S0      
327m5189            PEX0  -G3         A01X+015256Y+123228X0180Y         S1      
317m5190            VIA   -    MD0080PA01X+076299Y+112756X0160Y    R270 S0      
327m5190            C239  -1          A01X+077317Y+048138X0120Y0150R180 S1      
317m5190            VIA   -    MD0100PA01X+077808Y+048148X0200Y    R090 S0      
327m5190            PEX1  -AR44       A01X+076299Y+112756X0180Y         S1      
317m5191            VIA   -    MD0080PA01X+062087Y+118740X0160Y         S0      
317m5191            VIA   -    MD0100PA01X+062969Y+139658X0180Y         S0      
327m5191            C403  -1          A01X+062979Y+140149X0120Y0150R090 S1      
327m5191            PEX1  -W6         A01X+062087Y+118740X0180Y         S1      
317m5192            VIA   -    MD0080PA01X+116024Y+110512X0160Y    R270 S0      
327m5192            PEX2  -BA28       A01X+116024Y+110512X0180Y         S1      
327m5192            C479  -1          A01X+105737Y+041219X0120Y0150     S1      
317m5192            VIA   -    MD0100PA01X+105246Y+041229X0200Y    R270 S0      
317m5193            J12   -L3   D0122PA01X+047366Y+156610X0282Y    R180 S3      
317m5193            VIA   -    MD0080PA01X+069567Y+124724X0160Y         S0      
327m5193            PEX1  -C26        A01X+069567Y+124724X0180Y         S1      
317m5194            J13   -Y1   D0122PA01X+130508Y+145862X0282Y    R180 S3      
317m5194            VIA   -    MD0080PA01X+117520Y+124350X0160Y         S0      
327m5194            PEX2  -D32        A01X+117520Y+124350X0180Y         S1      
317m5195            VIA   -    MD0100PA01X+007611Y+138430X0180Y         S0      
317m5195            J3    -J1   D0122PA01X+010988Y+157634X0282Y    R180 S3      
327m5195            C191  -2          A01X+007601Y+137939X0120Y0150R090 S1      
317m5196            VIA   -    MD0080PA01X+076299Y+111260X0160Y    R270 S0      
327m5196            C231  -1          A01X+077317Y+052551X0120Y0150R180 S1      
317m5196            VIA   -    MD0100PA01X+077808Y+052561X0200Y    R090 S0      
327m5196            PEX1  -AW44       A01X+076299Y+111260X0180Y         S1      
317m5197            VIA   -    MD0080PA01X+061339Y+122854X0160Y         S0      
317m5197            VIA   -    MD0100PA01X+073985Y+134819X0180Y         S0      
327m5197            PEX1  -H4         A01X+061339Y+122854X0180Y         S1      
327m5197            C379  -1          A01X+073995Y+135309X0120Y0150R090 S1      
317m5198            VIA   -    MD0080PA01X+122756Y+110138X0160Y    R270 S0      
327m5198            PEX2  -BB46       A01X+122756Y+110138X0180Y         S1      
317m5198            VIA   -    MD0100PA01X+123517Y+057565X0200Y    R090 S0      
327m5198            C434  -1          A01X+123026Y+057555X0120Y0150R180 S1      
317m5199            J5    -D7   D0122PA01X+068154Y+160705X0282Y    R180 S3      
317m5199            VIA   -    MD0080PA01X+061339Y+120984X0160Y         S0      
327m5199            PEX1  -N4         A01X+061339Y+120984X0180Y         S1      
317m5200            VIA   -    MD0100PA01X+074869Y+138430X0180Y         S0      
317m5200            J5    -V7   D0122PA01X+068154Y+147398X0282Y    R180 S3      
327m5200            C374  -2          A01X+074859Y+137939X0120Y0150R090 S1      
317m5201            VIA   -    MD0080PA01X+070689Y+109764X0160Y         S0      
327m5201            C266  -1          A01X+061068Y+041925X0120Y0150     S1      
317m5201            VIA   -    MD0100PA01X+060578Y+041935X0200Y    R270 S0      
327m5201            PEX1  -BC29       A01X+070689Y+109764X0180Y         S1      
317m5202            VIA   -    MD0080PA01X+062835Y+122854X0160Y         S0      
327m5202            C341  -1          A01X+044390Y+135309X0120Y0150R090 S1      
317m5202            VIA   -    MD0100PA01X+044380Y+134819X0180Y         S0      
327m5202            PEX1  -H8         A01X+062835Y+122854X0180Y         S1      
317m5203            J5    -D5   D0122PA01X+066421Y+160705X0282Y    R180 S3      
317m5203            VIA   -    MD0080PA01X+061339Y+120236X0160Y         S0      
327m5203            PEX1  -R4         A01X+061339Y+120236X0180Y         S1      
317m5204            J13   -X8   D0122PA01X+136571Y+146295X0282Y    R180 S3      
317m5204            VIA   -    MD0080PA01X+120138Y+125098X0160Y    R090 S0      
327m5204            PEX2  -B39        A01X+120138Y+125098X0180Y         S1      
317m5205            VIA   -    MD0100PA01X+056620Y+140850X0180Y         S0      
317m5205            J12   -Q8   D0122PA01X+051697Y+149878X0282Y    R180 S3      
327m5205            C2244 -2          A01X+056630Y+140359X0120Y0150R090 S1      
327m5206            C170  -1          A01X+016529Y+140149X0120Y0150R090 S1      
317m5206            VIA   -    MD0100PA01X+016519Y+139658X0180Y         S0      
317m5206            VIA   -    MD0080PA01X+015256Y+123602X0160Y    R270 S0      
327m5206            PEX0  -F3         A01X+015256Y+123602X0180Y         S1      
317m5207            VIA   -    MD0080PA01X+074055Y+110512X0160Y    R270 S0      
327m5207            C248  -1          A01X+061068Y+052053X0120Y0150     S1      
317m5207            VIA   -    MD0100PA01X+060578Y+052063X0200Y    R270 S0      
327m5207            PEX1  -BA38       A01X+074055Y+110512X0180Y         S1      
317m5208            VIA   -    MD0080PA01X+062087Y+120984X0160Y         S0      
317m5208            VIA   -    MD0100PA01X+069089Y+134819X0180Y         S0      
327m5208            PEX1  -N6         A01X+062087Y+120984X0180Y         S1      
327m5208            C391  -1          A01X+069099Y+135309X0120Y0150R090 S1      
317m5209            J5    -C5   D0122PA01X+066421Y+161217X0282Y    R180 S3      
317m5209            VIA   -    MD0080PA01X+060965Y+120236X0160Y         S0      
327m5209            PEX1  -R3         A01X+060965Y+120236X0180Y         S1      
317m5210            J7    -O1   D0122PA01X+113185Y+150980X0282Y    R180 S3      
317m5210            VIA   -    MD0080PA01X+106673Y+121732X0160Y         S0      
327m5210            PEX2  -L3         A01X+106673Y+121732X0180Y         S1      
327m5211            C172  -1          A01X+016169Y+135309X0120Y0150R090 S1      
317m5211            VIA   -    MD0100PA01X+016179Y+134819X0180Y         S0      
317m5211            VIA   -    MD0080PA01X+014508Y+123976X0160Y         S0      
327m5211            PEX0  -E1         A01X+014508Y+123976X0180Y         S1      
317m5212            VIA   -    MD0080PA01X+075925Y+109390X0160Y    R270 S0      
327m5212            C217  -1          A01X+078358Y+059684X0120Y0150R180 S1      
317m5212            VIA   -    MD0100PA01X+078848Y+059694X0200Y    R090 S0      
327m5212            PEX1  -BD43       A01X+075925Y+109390X0180Y         S1      
317m5213            VIA   -    MD0080PA01X+062835Y+122480X0160Y         S0      
327m5213            C340  -1          A01X+044030Y+135309X0120Y0150R090 S1      
317m5213            VIA   -    MD0100PA01X+044040Y+134819X0180Y         S0      
327m5213            PEX1  -J8         A01X+062835Y+122480X0180Y         S1      
317m5214            J5    -B4   D0122PA01X+065555Y+161650X0282Y    R180 S3      
317m5214            VIA   -    MD0080PA01X+060216Y+119862X0160Y         S0      
327m5214            PEX1  -T1         A01X+060216Y+119862X0180Y         S1      
317m5215            J13   -W2   D0122PA01X+131374Y+146807X0282Y    R180 S3      
317m5215            VIA   -    MD0080PA01X+117894Y+125472X0160Y    R090 S0      
327m5215            PEX2  -A33        A01X+117894Y+125472X0180Y         S1      
317m5216            VIA   -    MD0080PA01X+075551Y+113130X0160Y    R270 S0      
327m5216            C241  -1          A01X+078358Y+047432X0120Y0150R180 S1      
317m5216            VIA   -    MD0100PA01X+078848Y+047442X0200Y    R090 S0      
327m5216            PEX1  -AP42       A01X+075551Y+113130X0180Y         S1      
317m5217            VIA   -    MD0080PA01X+061713Y+123602X0160Y    R270 S0      
317m5217            VIA   -    MD0100PA01X+073985Y+139649X0180Y         S0      
327m5217            C377  -1          A01X+073995Y+140140X0120Y0150R090 S1      
327m5217            PEX1  -F5         A01X+061713Y+123602X0180Y         S1      
317m5218            J12   -L5   D0122PA01X+049098Y+156610X0282Y    R180 S3      
317m5218            VIA   -    MD0080PA01X+070315Y+124724X0160Y         S0      
327m5218            PEX1  -C28        A01X+070315Y+124724X0180Y         S1      
317m5219            J7    -O6   D0122PA01X+117516Y+150902X0282Y    R180 S3      
317m5219            VIA   -    MD0080PA01X+107421Y+125098X0160Y         S0      
327m5219            PEX2  -B5         A01X+107421Y+125098X0180Y         S1      
317m5220            VIA   -    MD0080PA01X+069193Y+109390X0160Y    R270 S0      
327m5220            C275  -1          A01X+061068Y+039450X0120Y0150     S1      
317m5220            VIA   -    MD0100PA01X+060578Y+039440X0200Y    R270 S0      
327m5220            PEX1  -BD25       A01X+069193Y+109390X0180Y         S1      
317m5221            VIA   -    MD0100PA01X+045604Y+134819X0180Y         S0      
327m5221            C359  -1          A01X+045614Y+135309X0120Y0150R090 S1      
317m5221            VIA   -    MD0080PA01X+066201Y+123602X0160Y    R270 S0      
327m5221            PEX1  -F17        A01X+066201Y+123602X0180Y         S1      
317m5222            J12   -M7   D0122PA01X+050831Y+156098X0282Y    R180 S3      
317m5222            VIA   -    MD0080PA01X+071063Y+124350X0160Y         S0      
327m5222            PEX1  -D30        A01X+071063Y+124350X0180Y         S1      
317m5223            J7    -O2   D0122PA01X+114051Y+150902X0282Y    R180 S3      
317m5223            VIA   -    MD0080PA01X+105925Y+122106X0160Y         S0      
327m5223            PEX2  -K1         A01X+105925Y+122106X0180Y         S1      
327m5224            C183  -1          A01X+011273Y+135309X0120Y0150R090 S1      
317m5224            VIA   -    MD0100PA01X+011283Y+134819X0180Y         S0      
317m5224            VIA   -    MD0080PA01X+016752Y+120236X0160Y         S0      
327m5224            PEX0  -R7         A01X+016752Y+120236X0180Y         S1      
317m5225            VIA   -    MD0080PA01X+072559Y+110512X0160Y    R270 S0      
327m5225            C256  -1          A01X+061068Y+047640X0120Y0150     S1      
317m5225            VIA   -    MD0100PA01X+060578Y+047650X0200Y    R270 S0      
327m5225            PEX1  -BA34       A01X+072559Y+110512X0180Y         S1      
317m5226            VIA   -    MD0080PA01X+068445Y+123228X0160Y    R270 S0      
317m5226            VIA   -    MD0100PA01X+050160Y+134819X0180Y         S0      
327m5226            PEX1  -G23        A01X+068445Y+123228X0180Y         S1      
327m5226            C370  -1          A01X+050150Y+135309X0120Y0150R090 S1      
317m5227            J12   -K6   D0122PA01X+049965Y+157043X0282Y    R180 S3      
317m5227            VIA   -    MD0080PA01X+070689Y+125472X0160Y    R090 S0      
327m5227            PEX1  -A29        A01X+070689Y+125472X0180Y         S1      
327m5228            C165  -1          A01X+018617Y+135309X0120Y0150R090 S1      
317m5228            VIA   -    MD0100PA01X+018627Y+134819X0180Y         S0      
317m5228            VIA   -    MD0080PA01X+016004Y+123228X0160Y    R270 S0      
327m5228            PEX0  -G5         A01X+016004Y+123228X0180Y         S1      
317m5229            VIA   -    MD0080PA01X+071437Y+109390X0160Y         S0      
327m5229            C263  -1          A01X+061068Y+043702X0120Y0150     S1      
317m5229            VIA   -    MD0100PA01X+060578Y+043692X0200Y    R270 S0      
327m5229            PEX1  -BD31       A01X+071437Y+109390X0180Y         S1      
317m5230            VIA   -    MD0080PA01X+063957Y+123228X0160Y    R270 S0      
317m5230            VIA   -    MD0100PA01X+046488Y+139658X0180Y    R180 S0      
327m5230            C346  -1          A01X+046478Y+140149X0120Y0150R090 S1      
327m5230            PEX1  -G11        A01X+063957Y+123228X0180Y         S1      
317m5231            J12   -K2   D0122PA01X+046500Y+157043X0282Y    R180 S3      
317m5231            VIA   -    MD0080PA01X+069193Y+125472X0160Y    R090 S0      
327m5231            PEX1  -A25        A01X+069193Y+125472X0180Y         S1      
317m5232            VIA   -    MD0080PA01X+075925Y+109764X0160Y    R270 S0      
327m5232            C216  -1          A01X+078358Y+060044X0120Y0150R180 S1      
317m5232            VIA   -    MD0100PA01X+078848Y+060034X0200Y    R090 S0      
327m5232            PEX1  -BC43       A01X+075925Y+109764X0180Y         S1      
317m5233            VIA   -    MD0080PA01X+060216Y+122854X0160Y    R270 S0      
317m5233            VIA   -    MD0100PA01X+071197Y+134819X0180Y         S0      
327m5233            C385  -1          A01X+071187Y+135309X0120Y0150R090 S1      
327m5233            PEX1  -H1         A01X+060216Y+122854X0180Y         S1      
317m5234            J12   -L7   D0122PA01X+050831Y+156610X0282Y    R180 S3      
317m5234            VIA   -    MD0080PA01X+071063Y+124724X0160Y         S0      
327m5234            PEX1  -C30        A01X+071063Y+124724X0180Y         S1      
317m5235            VIA   -    MD0080PA01X+075551Y+110512X0160Y    R270 S0      
327m5235            C214  -1          A01X+077317Y+060750X0120Y0150R180 S1      
317m5235            VIA   -    MD0100PA01X+077808Y+060740X0200Y    R090 S0      
327m5235            PEX1  -BA42       A01X+075551Y+110512X0180Y         S1      
317m5236            VIA   -    MD0080PA01X+060965Y+123228X0160Y    R270 S0      
317m5236            VIA   -    MD0100PA01X+072421Y+137238X0180Y         S0      
327m5236            PEX1  -G3         A01X+060965Y+123228X0180Y         S1      
327m5236            C380  -1          A01X+072411Y+137729X0120Y0150R090 S1      
317m5237            J5    -C8   D0122PA01X+069020Y+161138X0282Y    R180 S3      
317m5237            VIA   -    MD0080PA01X+060590Y+121358X0160Y         S0      
327m5237            PEX1  -M2         A01X+060590Y+121358X0180Y         S1      
317m5238            J13   -Y5   D0122PA01X+133972Y+145862X0282Y    R180 S3      
317m5238            VIA   -    MD0080PA01X+119016Y+124350X0160Y         S0      
327m5238            PEX2  -D36        A01X+119016Y+124350X0180Y         S1      
317m5239            VIA   -    MD0080PA01X+069567Y+110512X0160Y    R270 S0      
327m5239            C272  -1          A01X+060268Y+039801X0120Y0150     S1      
317m5239            VIA   -    MD0100PA01X+059778Y+039811X0200Y    R270 S0      
327m5239            PEX1  -BA26       A01X+069567Y+110512X0180Y         S1      
317m5240            VIA   -    MD0080PA01X+062087Y+122480X0160Y         S0      
317m5240            VIA   -    MD0100PA01X+074869Y+137238X0180Y         S0      
327m5240            PEX1  -J6         A01X+062087Y+122480X0180Y         S1      
327m5240            C374  -1          A01X+074859Y+137729X0120Y0150R090 S1      
317m5241            J12   -L8   D0122PA01X+051697Y+156532X0282Y    R180 S3      
317m5241            VIA   -    MD0080PA01X+071437Y+125098X0160Y    R090 S0      
327m5241            PEX1  -B31        A01X+071437Y+125098X0180Y         S1      
317m5242            VIA   -    MD0080PA01X+077421Y+109764X0160Y    R270 S0      
327m5242            C224  -1          A01X+078358Y+057209X0120Y0150R180 S1      
317m5242            VIA   -    MD0100PA01X+078848Y+057199X0200Y    R090 S0      
327m5242            PEX1  -BC47       A01X+077421Y+109764X0180Y         S1      
317m5243            VIA   -    MD0080PA01X+062835Y+120610X0160Y         S0      
317m5243            VIA   -    MD0100PA01X+067865Y+137238X0180Y         S0      
327m5243            C393  -1          A01X+067875Y+137729X0120Y0150R090 S1      
327m5243            PEX1  -P8         A01X+062835Y+120610X0180Y         S1      
317m5244            J5    -C3   D0122PA01X+064689Y+161217X0282Y    R180 S3      
317m5244            VIA   -    MD0080PA01X+060965Y+119488X0160Y         S0      
327m5244            PEX1  -U3         A01X+060965Y+119488X0180Y         S1      
327m5245            C171  -1          A01X+016529Y+135309X0120Y0150R090 S1      
317m5245            VIA   -    MD0100PA01X+016519Y+134819X0180Y         S0      
317m5245            VIA   -    MD0080PA01X+014882Y+123976X0160Y         S0      
327m5245            PEX0  -E2         A01X+014882Y+123976X0180Y         S1      
317m5246            VIA   -    MD0080PA01X+076299Y+110512X0160Y    R270 S0      
327m5246            C218  -1          A01X+077317Y+059332X0120Y0150R180 S1      
317m5246            VIA   -    MD0100PA01X+077808Y+059322X0200Y    R090 S0      
327m5246            PEX1  -BA44       A01X+076299Y+110512X0180Y         S1      
317m5247            VIA   -    MD0080PA01X+062087Y+122854X0160Y         S0      
317m5247            VIA   -    MD0100PA01X+075209Y+137238X0180Y         S0      
327m5247            C375  -1          A01X+075219Y+137729X0120Y0150R090 S1      
327m5247            PEX1  -H6         A01X+062087Y+122854X0180Y         S1      
317m5248            J5    -B2   D0122PA01X+063823Y+161650X0282Y    R180 S3      
317m5248            VIA   -    MD0080PA01X+060216Y+119114X0160Y         S0      
327m5248            PEX1  -V1         A01X+060216Y+119114X0180Y         S1      
317m5249            J7    -P1   D0122PA01X+113185Y+150468X0282Y    R180 S3      
317m5249            VIA   -    MD0080PA01X+107047Y+121732X0160Y         S0      
327m5249            PEX2  -L4         A01X+107047Y+121732X0180Y         S1      
327m5250            C162  -1          A01X+020201Y+137729X0120Y0150R090 S1      
317m5250            VIA   -    MD0100PA01X+020191Y+137238X0180Y         S0      
317m5250            VIA   -    MD0080PA01X+016752Y+123602X0160Y    R270 S0      
327m5250            PEX0  -F7         A01X+016752Y+123602X0180Y         S1      
317m5251            VIA   -    MD0080PA01X+076299Y+110138X0160Y    R270 S0      
327m5251            C219  -1          A01X+077317Y+058972X0120Y0150R180 S1      
317m5251            VIA   -    MD0100PA01X+077808Y+058982X0200Y    R090 S0      
327m5251            PEX1  -BB44       A01X+076299Y+110138X0180Y         S1      
317m5252            VIA   -    MD0080PA01X+066575Y+122480X0160Y         S0      
317m5252            VIA   -    MD0100PA01X+045264Y+139658X0180Y         S0      
327m5252            PEX1  -J18        A01X+066575Y+122480X0180Y         S1      
327m5252            C360  -1          A01X+045254Y+140149X0120Y0150R090 S1      
317m5253            J12   -K8   D0122PA01X+051697Y+157043X0282Y    R180 S3      
317m5253            VIA   -    MD0080PA01X+071437Y+125472X0160Y    R090 S0      
327m5253            PEX1  -A31        A01X+071437Y+125472X0180Y         S1      
317m5254            VIA   -    MD0100PA01X+059538Y+053109X0200Y    R270 S0      
327m5254            C247  -1          A01X+060028Y+053119X0120Y0150     S1      
317m5254            VIA   -    MD0080PA01X+074429Y+109390X0160Y    R270 S0      
327m5254            PEX1  -BD39       A01X+074429Y+109390X0180Y         S1      
317m5255            VIA   -    MD0100PA01X+045264Y+134819X0180Y         S0      
327m5255            C358  -1          A01X+045254Y+135309X0120Y0150R090 S1      
317m5255            VIA   -    MD0080PA01X+066201Y+123228X0160Y    R270 S0      
327m5255            PEX1  -G17        A01X+066201Y+123228X0180Y         S1      
317m5256            J5    -C1   D0122PA01X+062957Y+161217X0282Y    R180 S3      
317m5256            VIA   -    MD0080PA01X+060965Y+118740X0160Y         S0      
327m5256            PEX1  -W3         A01X+060965Y+118740X0180Y         S1      
317m5257            VIA   -    MD0080PA01X+074803Y+110512X0160Y    R270 S0      
327m5257            C244  -1          A01X+061068Y+053471X0120Y0150     S1      
317m5257            VIA   -    MD0100PA01X+060578Y+053481X0200Y    R270 S0      
327m5257            PEX1  -BA40       A01X+074803Y+110512X0180Y         S1      
317m5258            VIA   -    MD0080PA01X+067697Y+123602X0160Y    R270 S0      
317m5258            VIA   -    MD0100PA01X+048052Y+139658X0180Y         S0      
327m5258            PEX1  -F21        A01X+067697Y+123602X0180Y         S1      
327m5258            C367  -1          A01X+048062Y+140149X0120Y0150R090 S1      
317m5259            J12   -M5   D0122PA01X+049098Y+156098X0282Y    R180 S3      
317m5259            VIA   -    MD0080PA01X+070315Y+124350X0160Y         S0      
327m5259            PEX1  -D28        A01X+070315Y+124350X0180Y         S1      
317m5260            VIA   -    MD0080PA01X+071063Y+110512X0160Y    R270 S0      
327m5260            C264  -1          A01X+060028Y+042636X0120Y0150     S1      
317m5260            VIA   -    MD0100PA01X+059538Y+042646X0200Y    R270 S0      
327m5260            PEX1  -BA30       A01X+071063Y+110512X0180Y         S1      
317m5261            VIA   -    MD0080PA01X+062835Y+119114X0160Y         S0      
317m5261            VIA   -    MD0100PA01X+064193Y+139658X0180Y         S0      
327m5261            PEX1  -V8         A01X+062835Y+119114X0180Y         S1      
327m5261            C401  -1          A01X+064203Y+140149X0120Y0150R090 S1      
317m5262            J12   -M1   D0122PA01X+045634Y+156098X0282Y    R180 S3      
317m5262            VIA   -    MD0080PA01X+068819Y+124350X0160Y         S0      
327m5262            PEX1  -D24        A01X+068819Y+124350X0180Y         S1      
317m5263            VIA   -    MD0100PA01X+066301Y+140850X0180Y         S0      
317m5263            J5    -J5   D0122PA01X+066421Y+157634X0282Y    R180 S3      
327m5263            C394  -2          A01X+066291Y+140359X0120Y0150R090 S1      
327m5264            C177  -1          A01X+013721Y+135309X0120Y0150R090 S1      
317m5264            VIA   -    MD0100PA01X+013731Y+134819X0180Y         S0      
317m5264            VIA   -    MD0080PA01X+017500Y+121358X0160Y         S0      
327m5264            PEX0  -M9         A01X+017500Y+121358X0180Y         S1      
317m5265            VIA   -    MD0080PA01X+075177Y+112382X0160Y    R270 S0      
327m5265            C236  -1          A01X+078358Y+049209X0120Y0150R180 S1      
317m5265            VIA   -    MD0100PA01X+078848Y+049199X0200Y    R090 S0      
327m5265            PEX1  -AT41       A01X+075177Y+112382X0180Y         S1      
317m5266            VIA   -    MD0080PA01X+065453Y+123602X0160Y    R270 S0      
317m5266            VIA   -    MD0100PA01X+050500Y+137238X0180Y         S0      
327m5266            C355  -1          A01X+050510Y+137729X0120Y0150R090 S1      
327m5266            PEX1  -F15        A01X+065453Y+123602X0180Y         S1      
317m5267            J12   -L1   D0122PA01X+045634Y+156610X0282Y    R180 S3      
317m5267            VIA   -    MD0080PA01X+068819Y+124724X0160Y         S0      
327m5267            PEX1  -C24        A01X+068819Y+124724X0180Y         S1      
327m5268            C164  -1          A01X+018977Y+140149X0120Y0150R090 S1      
317m5268            VIA   -    MD0100PA01X+018967Y+139658X0180Y         S0      
317m5268            VIA   -    MD0080PA01X+016378Y+122854X0160Y         S0      
327m5268            PEX0  -H6         A01X+016378Y+122854X0180Y         S1      
317m5269            VIA   -    MD0080PA01X+075177Y+109764X0160Y    R270 S0      
327m5269            C212  -1          A01X+078358Y+061461X0120Y0150R180 S1      
317m5269            VIA   -    MD0100PA01X+078848Y+061451X0200Y    R090 S0      
327m5269            PEX1  -BC41       A01X+075177Y+109764X0180Y         S1      
317m5270            VIA   -    MD0080PA01X+060590Y+122854X0160Y    R270 S0      
317m5270            VIA   -    MD0100PA01X+071537Y+134819X0180Y         S0      
327m5270            C384  -1          A01X+071547Y+135309X0120Y0150R090 S1      
327m5270            PEX1  -H2         A01X+060590Y+122854X0180Y         S1      
317m5271            J12   -L2   D0122PA01X+046500Y+156532X0282Y    R180 S3      
317m5271            VIA   -    MD0080PA01X+069193Y+125098X0160Y    R090 S0      
327m5271            PEX1  -B25        A01X+069193Y+125098X0180Y         S1      
317m5272            VIA   -    MD0100PA01X+024502Y+138430X0180Y         S0      
317m5272            J11   -F1   D0122PA01X+028311Y+159681X0282Y    R180 S3      
327m5272            C128  -2          A01X+024512Y+137939X0120Y0150R090 S1      
317m5273            VIA   -    MD0100PA01X+055056Y+136010X0180Y         S0      
317m5273            J12   -F6   D0122PA01X+049965Y+159602X0282Y    R180 S3      
327m5273            C2263 -2          A01X+055046Y+135519X0120Y0150R090 S1      
327m5274            C175  -1          A01X+013721Y+140149X0120Y0150R090 S1      
317m5274            VIA   -    MD0100PA01X+013731Y+139658X0180Y         S0      
317m5274            VIA   -    MD0080PA01X+016752Y+121732X0160Y         S0      
327m5274            PEX0  -L7         A01X+016752Y+121732X0180Y         S1      
317m5275            VIA   -    MD0080PA01X+075925Y+111260X0160Y    R270 S0      
327m5275            C230  -1          A01X+077317Y+052911X0120Y0150R180 S1      
317m5275            VIA   -    MD0100PA01X+077808Y+052901X0200Y    R090 S0      
327m5275            PEX1  -AW43       A01X+075925Y+111260X0180Y         S1      
317m5276            VIA   -    MD0080PA01X+064705Y+123602X0160Y    R270 S0      
317m5276            VIA   -    MD0100PA01X+049276Y+134819X0180Y         S0      
327m5276            C351  -1          A01X+049286Y+135309X0120Y0150R090 S1      
327m5276            PEX1  -F13        A01X+064705Y+123602X0180Y         S1      
317m5277            J5    -C4   D0122PA01X+065555Y+161138X0282Y    R180 S3      
317m5277            VIA   -    MD0080PA01X+060590Y+119862X0160Y         S0      
327m5277            PEX1  -T2         A01X+060590Y+119862X0180Y         S1      
317m5278            VIA   -    MD0100PA01X+055056Y+140850X0180Y         S0      
327m5278            C2261 -2          A01X+055046Y+140359X0120Y0150R090 S1      
317m5278            J12   -G7   D0122PA01X+050831Y+159169X0282Y    R180 S3      
317m5279            VIA   -    MD0080PA01X+026476Y+109390X0160Y    R270 S0      
327m5279            C48   -1          A01X+014320Y+047289X0120Y0150     S1      
317m5279            VIA   -    MD0100PA01X+013829Y+047279X0200Y    R270 S0      
327m5279            PEX0  -BD33       A01X+026476Y+109390X0180Y         S1      
327m5280            C176  -1          A01X+014081Y+140149X0120Y0150R090 S1      
317m5280            VIA   -    MD0100PA01X+014071Y+139658X0180Y         S0      
317m5280            VIA   -    MD0080PA01X+016378Y+121732X0160Y         S0      
327m5280            PEX0  -L6         A01X+016378Y+121732X0180Y         S1      
317m5281            VIA   -    MD0080PA01X+075551Y+112382X0160Y    R270 S0      
327m5281            C237  -1          A01X+078358Y+048849X0120Y0150R180 S1      
317m5281            VIA   -    MD0100PA01X+078848Y+048859X0200Y    R090 S0      
327m5281            PEX1  -AT42       A01X+075551Y+112382X0180Y         S1      
317m5282            VIA   -    MD0080PA01X+066949Y+123228X0160Y    R270 S0      
317m5282            VIA   -    MD0100PA01X+046488Y+137238X0180Y         S0      
327m5282            PEX1  -G19        A01X+066949Y+123228X0180Y         S1      
327m5282            C362  -1          A01X+046478Y+137729X0120Y0150R090 S1      
317m5283            J12   -L6   D0122PA01X+049965Y+156532X0282Y    R180 S3      
317m5283            VIA   -    MD0080PA01X+070689Y+125098X0160Y    R090 S0      
327m5283            PEX1  -B29        A01X+070689Y+125098X0180Y         S1      
317m5284            VIA   -    MD0100PA01X+035178Y+136010X0180Y         S0      
317m5284            J11   -R6   D0122PA01X+032642Y+149366X0282Y    R180 S3      
327m5284            C101  -2          A01X+035168Y+135519X0120Y0150R090 S1      
317m5285            VIA   -    MD0100PA01X+056280Y+138430X0180Y         S0      
317m5285            J12   -F8   D0122PA01X+051697Y+159602X0282Y    R180 S3      
327m5285            C2259 -2          A01X+056270Y+137939X0120Y0150R090 S1      
317m5286            VIA   -    MD0080PA01X+029842Y+113130X0160Y    R270 S0      
327m5286            PEX0  -AP42       A01X+029842Y+113130X0180Y         S1      
327m5286            C30   -1          A01X+032649Y+047432X0120Y0150R180 S1      
317m5286            VIA   -    MD0100PA01X+033140Y+047442X0200Y    R090 S0      
327m5287            C173  -1          A01X+015305Y+137729X0120Y0150R090 S1      
317m5287            VIA   -    MD0100PA01X+015295Y+137238X0180Y         S0      
317m5287            VIA   -    MD0080PA01X+014882Y+122854X0160Y    R270 S0      
327m5287            PEX0  -H2         A01X+014882Y+122854X0180Y         S1      
317m5288            VIA   -    MD0100PA01X+078848Y+053612X0200Y    R090 S0      
327m5288            C228  -1          A01X+078358Y+053622X0120Y0150R180 S1      
317m5288            VIA   -    MD0080PA01X+077795Y+110138X0160Y    R270 S0      
327m5288            PEX1  -BB48       A01X+077795Y+110138X0180Y         S1      
317m5289            VIA   -    MD0080PA01X+063957Y+123602X0160Y    R270 S0      
317m5289            VIA   -    MD0100PA01X+046828Y+139658X0180Y    R180 S0      
327m5289            C347  -1          A01X+046838Y+140149X0120Y0150R090 S1      
327m5289            PEX1  -F11        A01X+063957Y+123602X0180Y         S1      
317m5290            J5    -D3   D0122PA01X+064689Y+160705X0282Y    R180 S3      
317m5290            VIA   -    MD0080PA01X+061339Y+119488X0160Y         S0      
327m5290            PEX1  -U4         A01X+061339Y+119488X0180Y         S1      
317m5291            VIA   -    MD0100PA01X+055396Y+136010X0180Y         S0      
317m5291            J12   -E6   D0122PA01X+049965Y+160114X0282Y    R180 S3      
327m5291            C2264 -2          A01X+055406Y+135519X0120Y0150R090 S1      
317m5292            VIA   -    MD0080PA01X+027598Y+110138X0160Y    R270 S0      
327m5292            PEX0  -BB36       A01X+027598Y+110138X0180Y         S1      
327m5292            C42   -1          A01X+015360Y+049417X0120Y0150     S1      
317m5292            VIA   -    MD0100PA01X+014869Y+049407X0200Y    R270 S0      
317m5293            VIA   -    MD0080PA01X+071811Y+110138X0160Y    R270 S0      
327m5293            C261  -1          A01X+060028Y+044413X0120Y0150     S1      
317m5293            VIA   -    MD0100PA01X+059538Y+044403X0200Y    R270 S0      
327m5293            PEX1  -BB32       A01X+071811Y+110138X0180Y         S1      
317m5294            J5    -C2   D0122PA01X+063823Y+161138X0282Y    R180 S3      
317m5294            VIA   -    MD0080PA01X+060590Y+119114X0160Y         S0      
327m5294            PEX1  -V2         A01X+060590Y+119114X0180Y         S1      
317m5295            VIA   -    MD0100PA01X+069089Y+136010X0180Y         S0      
317m5295            J5    -I7   D0122PA01X+068154Y+158146X0282Y    R180 S3      
327m5295            C391  -2          A01X+069099Y+135519X0120Y0150R090 S1      
317m5296            VIA   -    MD0080PA01X+031712Y+109764X0160Y    R270 S0      
327m5296            PEX0  -BC47       A01X+031712Y+109764X0180Y         S1      
327m5296            C13   -1          A01X+032649Y+057209X0120Y0150R180 S1      
317m5296            VIA   -    MD0100PA01X+033140Y+057199X0200Y    R090 S0      
317m5297            VIA   -    MD0100PA01X+078848Y+053272X0200Y    R090 S0      
327m5297            C229  -1          A01X+078358Y+053262X0120Y0150R180 S1      
317m5297            VIA   -    MD0080PA01X+078169Y+110138X0160Y    R270 S0      
327m5297            PEX1  -BB49       A01X+078169Y+110138X0180Y         S1      
317m5298            J5    -C6   D0122PA01X+067287Y+161138X0282Y    R180 S3      
317m5298            VIA   -    MD0080PA01X+060590Y+120610X0160Y         S0      
327m5298            PEX1  -P2         A01X+060590Y+120610X0180Y         S1      
317m5299            VIA   -    MD0080PA01X+028720Y+109764X0160Y    R270 S0      
327m5299            C35   -1          A01X+014320Y+052759X0120Y0150     S1      
317m5299            VIA   -    MD0100PA01X+013829Y+052769X0200Y    R270 S0      
327m5299            PEX0  -BC39       A01X+028720Y+109764X0180Y         S1      
327m5300            C168  -1          A01X+017753Y+137729X0120Y0150R090 S1      
317m5300            VIA   -    MD0100PA01X+017743Y+137238X0180Y         S0      
317m5300            VIA   -    MD0080PA01X+015630Y+122854X0160Y         S0      
327m5300            PEX0  -H4         A01X+015630Y+122854X0180Y         S1      
317m5301            VIA   -    MD0080PA01X+076299Y+113504X0160Y    R270 S0      
327m5301            C243  -1          A01X+077317Y+046721X0120Y0150R180 S1      
317m5301            VIA   -    MD0100PA01X+077808Y+046731X0200Y    R090 S0      
327m5301            PEX1  -AN44       A01X+076299Y+113504X0180Y         S1      
317m5302            J5    -C7   D0122PA01X+068154Y+161217X0282Y    R180 S3      
317m5302            VIA   -    MD0080PA01X+060965Y+120984X0160Y         S0      
327m5302            PEX1  -N3         A01X+060965Y+120984X0180Y         S1      
317m5303            VIA   -    MD0100PA01X+033954Y+138430X0180Y         S0      
317m5303            J11   -S5   D0122PA01X+031776Y+148933X0282Y    R180 S3      
327m5303            C103  -2          A01X+033944Y+137939X0120Y0150R090 S1      
317m5304            VIA   -    MD0100PA01X+069089Y+140850X0180Y         S0      
317m5304            J5    -H8   D0122PA01X+069020Y+158579X0282Y    R180 S3      
327m5304            C389  -2          A01X+069099Y+140359X0120Y0150R090 S1      
317m5305            VIA   -    MD0080PA01X+026850Y+110138X0160Y    R270 S0      
327m5305            C46   -1          A01X+015360Y+048000X0120Y0150     S1      
317m5305            VIA   -    MD0100PA01X+014869Y+047990X0200Y    R270 S0      
327m5305            PEX0  -BB34       A01X+026850Y+110138X0180Y         S1      
327m5306            C161  -1          A01X+019841Y+137729X0120Y0150R090 S1      
317m5306            VIA   -    MD0100PA01X+019851Y+137238X0180Y         S0      
317m5306            VIA   -    MD0080PA01X+016752Y+123228X0160Y    R270 S0      
327m5306            PEX0  -G7         A01X+016752Y+123228X0180Y         S1      
317m5307            VIA   -    MD0080PA01X+069941Y+109764X0160Y    R270 S0      
327m5307            C270  -1          A01X+061068Y+040507X0120Y0150     S1      
317m5307            VIA   -    MD0100PA01X+060578Y+040517X0200Y    R270 S0      
327m5307            PEX1  -BC27       A01X+069941Y+109764X0180Y         S1      
317m5308            J5    -D1   D0122PA01X+062957Y+160705X0282Y    R180 S3      
317m5308            VIA   -    MD0080PA01X+061339Y+118740X0160Y         S0      
327m5308            PEX1  -W4         A01X+061339Y+118740X0180Y         S1      
317m5309            VIA   -    MD0080PA01X+029094Y+110512X0160Y    R270 S0      
327m5309            C33   -1          A01X+015360Y+053471X0120Y0150     S1      
317m5309            VIA   -    MD0100PA01X+014869Y+053481X0200Y    R270 S0      
327m5309            PEX0  -BA40       A01X+029094Y+110512X0180Y         S1      
317m5310            VIA   -    MD0080PA01X+071811Y+110512X0160Y    R270 S0      
327m5310            C260  -1          A01X+060028Y+044053X0120Y0150     S1      
317m5310            VIA   -    MD0100PA01X+059538Y+044063X0200Y    R270 S0      
327m5310            PEX1  -BA32       A01X+071811Y+110512X0180Y         S1      
317m5311            J12   -K4   D0122PA01X+048232Y+157043X0282Y    R180 S3      
317m5311            VIA   -    MD0080PA01X+069941Y+125472X0160Y    R090 S0      
327m5311            PEX1  -A27        A01X+069941Y+125472X0180Y         S1      
317m5312            VIA   -    MD0100PA01X+024162Y+138430X0180Y         S0      
317m5312            J11   -G1   D0122PA01X+028311Y+159169X0282Y    R180 S3      
327m5312            C127  -2          A01X+024152Y+137939X0120Y0150R090 S1      
317m5313            VIA   -    MD0080PA01X+030216Y+109390X0160Y    R270 S0      
327m5313            C6    -1          A01X+032649Y+059684X0120Y0150R180 S1      
317m5313            VIA   -    MD0100PA01X+033140Y+059694X0200Y    R090 S0      
327m5313            PEX0  -BD43       A01X+030216Y+109390X0180Y         S1      
317m5314            VIA   -    MD0080PA01X+073681Y+109764X0160Y    R270 S0      
327m5314            C250  -1          A01X+060028Y+051342X0120Y0150     S1      
317m5314            VIA   -    MD0100PA01X+059538Y+051352X0200Y    R270 S0      
327m5314            PEX1  -BC37       A01X+073681Y+109764X0180Y         S1      
317m5315            J12   -X6   D0122PA01X+049965Y+146295X0282Y    R180 S3      
317m5315            VIA   -    MD0080PA01X+073681Y+125098X0160Y    R090 S0      
327m5315            PEX1  -B37        A01X+073681Y+125098X0180Y         S1      
317m5316            VIA   -    MD0080PA01X+027972Y+109764X0160Y    R270 S0      
327m5316            C39   -1          A01X+014320Y+051342X0120Y0150     S1      
317m5316            VIA   -    MD0100PA01X+013829Y+051352X0200Y    R270 S0      
327m5316            PEX0  -BC37       A01X+027972Y+109764X0180Y         S1      
327m5317            C181  -1          A01X+011273Y+140149X0120Y0150R090 S1      
317m5317            VIA   -    MD0100PA01X+011283Y+139658X0180Y         S0      
317m5317            VIA   -    MD0080PA01X+017500Y+120610X0160Y         S0      
327m5317            PEX0  -P9         A01X+017500Y+120610X0180Y         S1      
317m5318            VIA   -    MD0080PA01X+077047Y+110138X0160Y    R270 S0      
327m5318            C223  -1          A01X+077317Y+057555X0120Y0150R180 S1      
317m5318            VIA   -    MD0100PA01X+077808Y+057565X0200Y    R090 S0      
327m5318            PEX1  -BB46       A01X+077047Y+110138X0180Y         S1      
317m5319            J12   -W6   D0122PA01X+049965Y+146807X0282Y    R180 S3      
317m5319            VIA   -    MD0080PA01X+073681Y+125472X0160Y    R090 S0      
327m5319            PEX1  -A37        A01X+073681Y+125472X0180Y         S1      
317m5320            VIA   -    MD0080PA01X+026102Y+110138X0160Y    R270 S0      
327m5320            PEX0  -BB32       A01X+026102Y+110138X0180Y         S1      
327m5320            C50   -1          A01X+014320Y+044413X0120Y0150     S1      
317m5320            VIA   -    MD0100PA01X+013829Y+044403X0200Y    R270 S0      
317m5321            VIA   -    MD0080PA01X+069567Y+110138X0160Y    R270 S0      
327m5321            C273  -1          A01X+060268Y+040161X0120Y0150     S1      
317m5321            VIA   -    MD0100PA01X+059778Y+040151X0200Y    R270 S0      
327m5321            PEX1  -BB26       A01X+069567Y+110138X0180Y         S1      
317m5322            J5    -P3   D0122PA01X+064689Y+150468X0282Y    R180 S3      
317m5322            VIA   -    MD0080PA01X+060216Y+124724X0160Y         S0      
327m5322            PEX1  -C1         A01X+060216Y+124724X0180Y         S1      
317m5323            VIA   -    MD0100PA01X+025726Y+136010X0180Y         S0      
317m5323            J11   -E2   D0122PA01X+029177Y+160114X0282Y    R180 S3      
327m5323            C126  -2          A01X+025736Y+135519X0120Y0150R090 S1      
317m5324            VIA   -    MD0080PA01X+029468Y+113130X0160Y    R270 S0      
327m5324            PEX0  -AP41M      A01X+029468Y+113130X0180Y         S1      
317m5324            VIA   -    MD0100PA01X+033140Y+047782X0200Y    R090 S0      
327m5324            C29   -1          A01X+032649Y+047792X0120Y0150R180 S1      
327m5325            C190  -1          A01X+009185Y+135309X0120Y0150R090 S1      
317m5325            VIA   -    MD0100PA01X+009175Y+134819X0180Y         S0      
317m5325            VIA   -    MD0080PA01X+017126Y+119114X0160Y         S0      
327m5325            PEX0  -V8         A01X+017126Y+119114X0180Y         S1      
317m5326            VIA   -    MD0080PA01X+073307Y+110512X0160Y    R270 S0      
327m5326            C252  -1          A01X+061068Y+049057X0120Y0150     S1      
317m5326            VIA   -    MD0100PA01X+060578Y+049067X0200Y    R270 S0      
327m5326            PEX1  -BA36       A01X+073307Y+110512X0180Y         S1      
317m5327            J5    -O4   D0122PA01X+065555Y+150902X0282Y    R180 S3      
317m5327            VIA   -    MD0080PA01X+060965Y+125098X0160Y         S0      
327m5327            PEX1  -B3         A01X+060965Y+125098X0180Y         S1      
317m5328            VIA   -    MD0100PA01X+034294Y+138430X0180Y         S0      
317m5328            J11   -R5   D0122PA01X+031776Y+149445X0282Y    R180 S3      
327m5328            C104  -2          A01X+034304Y+137939X0120Y0150R090 S1      
317m5329            VIA   -    MD0100PA01X+067865Y+138430X0180Y         S0      
317m5329            J5    -H6   D0122PA01X+067287Y+158579X0282Y    R180 S3      
327m5329            C393  -2          A01X+067875Y+137939X0120Y0150R090 S1      
317m5330            VIA   -    MD0080PA01X+032461Y+110138X0160Y    R270 S0      
327m5330            PEX0  -BB49       A01X+032461Y+110138X0180Y         S1      
317m5330            VIA   -    MD0100PA01X+033140Y+053272X0200Y    R090 S0      
327m5330            C18   -1          A01X+032649Y+053262X0120Y0150R180 S1      
327m5331            C186  -1          A01X+010409Y+137729X0120Y0150R090 S1      
317m5331            VIA   -    MD0100PA01X+010399Y+137238X0180Y         S0      
317m5331            VIA   -    MD0080PA01X+017126Y+119862X0160Y         S0      
327m5331            PEX0  -T8         A01X+017126Y+119862X0180Y         S1      
317m5332            VIA   -    MD0080PA01X+070315Y+110512X0160Y    R270 S0      
327m5332            C268  -1          A01X+060028Y+041219X0120Y0150     S1      
317m5332            VIA   -    MD0100PA01X+059538Y+041229X0200Y    R270 S0      
327m5332            PEX1  -BA28       A01X+070315Y+110512X0180Y         S1      
317m5333            VIA   -    MD0080PA01X+060965Y+121732X0160Y         S0      
317m5333            J5    -O1   D0122PA01X+062957Y+150980X0282Y    R180 S3      
327m5333            PEX1  -L3         A01X+060965Y+121732X0180Y         S1      
317m5334            VIA   -    MD0100PA01X+054172Y+138430X0180Y         S0      
317m5334            J12   -F5   D0122PA01X+049098Y+159681X0282Y    R180 S3      
327m5334            C2266 -2          A01X+054182Y+137939X0120Y0150R090 S1      
317m5335            VIA   -    MD0080PA01X+027224Y+109390X0160Y    R270 S0      
327m5335            PEX0  -BD35       A01X+027224Y+109390X0180Y         S1      
327m5335            C44   -1          A01X+014320Y+048706X0120Y0150     S1      
317m5335            VIA   -    MD0100PA01X+013829Y+048696X0200Y    R270 S0      
317m5336            VIA   -    MD0080PA01X+075177Y+113130X0160Y    R270 S0      
327m5336            C240  -1          A01X+078358Y+047792X0120Y0150R180 S1      
317m5336            VIA   -    MD0100PA01X+078848Y+047782X0200Y    R090 S0      
327m5336            PEX1  -AP41       A01X+075177Y+113130X0180Y         S1      
317m5337            J12   -X8   D0122PA01X+051697Y+146295X0282Y    R180 S3      
317m5337            VIA   -    MD0080PA01X+074429Y+125098X0160Y    R090 S0      
327m5337            PEX1  -B39        A01X+074429Y+125098X0180Y         S1      
317m5338            VIA   -    MD0100PA01X+035518Y+140850X0180Y         S0      
317m5338            J11   -R7   D0122PA01X+033508Y+149445X0282Y    R180 S3      
327m5338            C100  -2          A01X+035528Y+140359X0120Y0150R090 S1      
317m5339            VIA   -    MD0080PA01X+027972Y+109390X0160Y    R270 S0      
327m5339            C40   -1          A01X+014320Y+051702X0120Y0150     S1      
317m5339            VIA   -    MD0100PA01X+013829Y+051692X0200Y    R270 S0      
327m5339            PEX0  -BD37       A01X+027972Y+109390X0180Y         S1      
327m5340            C187  -1          A01X+008825Y+140149X0120Y0150R090 S1      
317m5340            VIA   -    MD0100PA01X+008835Y+139658X0180Y         S0      
317m5340            VIA   -    MD0080PA01X+016752Y+119488X0160Y         S0      
327m5340            PEX0  -U7         A01X+016752Y+119488X0180Y         S1      
317m5341            VIA   -    MD0080PA01X+072559Y+110138X0160Y    R270 S0      
327m5341            C257  -1          A01X+061068Y+048000X0120Y0150     S1      
317m5341            VIA   -    MD0100PA01X+060578Y+047990X0200Y    R270 S0      
327m5341            PEX1  -BB34       A01X+072559Y+110138X0180Y         S1      
317m5342            J5    -P5   D0122PA01X+066421Y+150468X0282Y    R180 S3      
317m5342            VIA   -    MD0080PA01X+061339Y+124350X0160Y         S0      
327m5342            PEX1  -D4         A01X+061339Y+124350X0180Y         S1      
317m5343            VIA   -    MD0100PA01X+036402Y+138430X0180Y         S0      
317m5343            J11   -R8   D0122PA01X+034374Y+149366X0282Y    R180 S3      
327m5343            C97   -2          A01X+036392Y+137939X0120Y0150R090 S1      
317m5344            VIA   -    MD0080PA01X+030590Y+110138X0160Y    R270 S0      
327m5344            PEX0  -BB44       A01X+030590Y+110138X0180Y         S1      
327m5344            C8    -1          A01X+031609Y+058972X0120Y0150R180 S1      
317m5344            VIA   -    MD0100PA01X+032099Y+058982X0200Y    R090 S0      
327m5345            C167  -1          A01X+017393Y+137729X0120Y0150R090 S1      
317m5345            VIA   -    MD0100PA01X+017403Y+137238X0180Y         S0      
317m5345            VIA   -    MD0080PA01X+015630Y+122480X0160Y         S0      
327m5345            PEX0  -J4         A01X+015630Y+122480X0180Y         S1      
317m5346            VIA   -    MD0080PA01X+070689Y+109390X0160Y         S0      
327m5346            C267  -1          A01X+061068Y+042285X0120Y0150     S1      
317m5346            VIA   -    MD0100PA01X+060578Y+042275X0200Y    R270 S0      
327m5346            PEX1  -BD29       A01X+070689Y+109390X0180Y         S1      
317m5347            J12   -X3   D0122PA01X+047366Y+146374X0282Y    R180 S3      
317m5347            VIA   -    MD0080PA01X+072559Y+124724X0160Y         S0      
327m5347            PEX1  -C34        A01X+072559Y+124724X0180Y         S1      
317m5348            VIA   -    MD0100PA01X+068749Y+140850X0180Y         S0      
317m5348            J5    -I8   D0122PA01X+069020Y+158067X0282Y    R180 S3      
327m5348            C388  -2          A01X+068739Y+140359X0120Y0150R090 S1      
317m5349            VIA   -    MD0080PA01X+030964Y+109390X0160Y    R270 S0      
327m5349            PEX0  -BD45       A01X+030964Y+109390X0180Y         S1      
327m5349            C10   -1          A01X+032649Y+058266X0120Y0150R180 S1      
317m5349            VIA   -    MD0100PA01X+033140Y+058276X0200Y    R090 S0      
327m5350            C189  -1          A01X+008825Y+135309X0120Y0150R090 S1      
317m5350            VIA   -    MD0100PA01X+008835Y+134819X0180Y         S0      
317m5350            VIA   -    MD0080PA01X+017500Y+119114X0160Y         S0      
327m5350            PEX0  -V9         A01X+017500Y+119114X0180Y         S1      
317m5351            VIA   -    MD0080PA01X+071437Y+109764X0160Y         S0      
327m5351            C262  -1          A01X+061068Y+043342X0120Y0150     S1      
317m5351            VIA   -    MD0100PA01X+060578Y+043352X0200Y    R270 S0      
327m5351            PEX1  -BC31       A01X+071437Y+109764X0180Y         S1      
317m5352            J12   -Y5   D0122PA01X+049098Y+145862X0282Y    R180 S3      
317m5352            VIA   -    MD0080PA01X+073307Y+124350X0160Y         S0      
327m5352            PEX1  -D36        A01X+073307Y+124350X0180Y         S1      
317m5353            VIA   -    MD0100PA01X+068749Y+136010X0180Y         S0      
317m5353            J5    -J7   D0122PA01X+068154Y+157634X0282Y    R180 S3      
327m5353            C390  -2          A01X+068739Y+135519X0120Y0150R090 S1      
317m5354            VIA   -    MD0080PA01X+029842Y+112382X0160Y    R270 S0      
327m5354            PEX0  -AT42       A01X+029842Y+112382X0180Y         S1      
327m5354            C26   -1          A01X+032649Y+048849X0120Y0150R180 S1      
317m5354            VIA   -    MD0100PA01X+033140Y+048859X0200Y    R090 S0      
317m5355            J5    -N6   D0122PA01X+067287Y+151413X0282Y    R180 S3      
317m5355            VIA   -    MD0080PA01X+061713Y+125472X0160Y         S0      
327m5355            PEX1  -A5         A01X+061713Y+125472X0180Y         S1      
317m5356            VIA   -    MD0100PA01X+035178Y+140850X0180Y         S0      
317m5356            J11   -S7   D0122PA01X+033508Y+148933X0282Y    R180 S3      
327m5356            C99   -2          A01X+035168Y+140359X0120Y0150R090 S1      
317m5357            VIA   -    MD0100PA01X+055396Y+140850X0180Y         S0      
317m5357            J12   -F7   D0122PA01X+050831Y+159681X0282Y    R180 S3      
327m5357            C2262 -2          A01X+055406Y+140359X0120Y0150R090 S1      
317m5358            VIA   -    MD0080PA01X+026102Y+110512X0160Y    R270 S0      
327m5358            C49   -1          A01X+014320Y+044053X0120Y0150     S1      
317m5358            VIA   -    MD0100PA01X+013829Y+044063X0200Y    R270 S0      
327m5358            PEX0  -BA32       A01X+026102Y+110512X0180Y         S1      
317m5359            J12   -W4   D0122PA01X+048232Y+146807X0282Y    R180 S3      
317m5359            VIA   -    MD0080PA01X+072933Y+125472X0160Y    R090 S0      
327m5359            PEX1  -A35        A01X+072933Y+125472X0180Y         S1      
317m5360            VIA   -    MD0080PA01X+029094Y+110138X0160Y    R270 S0      
327m5360            C34   -1          A01X+015360Y+053831X0120Y0150     S1      
317m5360            VIA   -    MD0100PA01X+014869Y+053821X0200Y    R270 S0      
327m5360            PEX0  -BB40       A01X+029094Y+110138X0180Y         S1      
317m5361            J5    -O5   D0122PA01X+066421Y+150980X0282Y    R180 S3      
317m5361            VIA   -    MD0080PA01X+061339Y+124724X0160Y         S0      
327m5361            PEX1  -C4         A01X+061339Y+124724X0180Y         S1      
317m5362            VIA   -    MD0100PA01X+036742Y+138430X0180Y         S0      
317m5362            J11   -Q8   D0122PA01X+034374Y+149878X0282Y    R180 S3      
327m5362            C98   -2          A01X+036752Y+137939X0120Y0150R090 S1      
317m5363            VIA   -    MD0080PA01X+028346Y+110512X0160Y    R270 S0      
327m5363            C37   -1          A01X+015360Y+052053X0120Y0150     S1      
317m5363            VIA   -    MD0100PA01X+014869Y+052063X0200Y    R270 S0      
327m5363            PEX0  -BA38       A01X+028346Y+110512X0180Y         S1      
317m5364            J5    -N4   D0122PA01X+065555Y+151413X0282Y    R180 S3      
317m5364            VIA   -    MD0080PA01X+060965Y+125472X0160Y         S0      
327m5364            PEX1  -A3         A01X+060965Y+125472X0180Y         S1      
317m5365            VIA   -    MD0080PA01X+025728Y+109390X0160Y         S0      
327m5365            C52   -1          A01X+015360Y+043702X0120Y0150     S1      
317m5365            VIA   -    MD0100PA01X+014869Y+043692X0200Y    R270 S0      
327m5365            PEX0  -BD31       A01X+025728Y+109390X0180Y         S1      
317m5366            J12   -Y3   D0122PA01X+047366Y+145862X0282Y    R180 S3      
317m5366            VIA   -    MD0080PA01X+072559Y+124350X0160Y         S0      
327m5366            PEX1  -D34        A01X+072559Y+124350X0180Y         S1      
317m5367            VIA   -    MD0100PA01X+035518Y+136010X0180Y         S0      
317m5367            J11   -Q6   D0122PA01X+032642Y+149878X0282Y    R180 S3      
327m5367            C102  -2          A01X+035528Y+135519X0120Y0150R090 S1      
317m5368            VIA   -    MD0100PA01X+066641Y+140850X0180Y         S0      
317m5368            J5    -I5   D0122PA01X+066421Y+158146X0282Y    R180 S3      
327m5368            C395  -2          A01X+066651Y+140359X0120Y0150R090 S1      
317m5369            VIA   -    MD0080PA01X+031338Y+110512X0160Y    R090 S0      
327m5369            PEX0  -BA46       A01X+031338Y+110512X0180Y         S1      
327m5369            C11   -1          A01X+031609Y+057915X0120Y0150R180 S1      
317m5369            VIA   -    MD0100PA01X+032099Y+057905X0200Y    R090 S0      
327m5370            C182  -1          A01X+011633Y+140149X0120Y0150R090 S1      
317m5370            VIA   -    MD0100PA01X+011623Y+139658X0180Y         S0      
317m5370            VIA   -    MD0080PA01X+017126Y+120610X0160Y         S0      
327m5370            PEX0  -P8         A01X+017126Y+120610X0180Y         S1      
317m5371            J12   -X7   D0122PA01X+050831Y+146374X0282Y    R180 S3      
317m5371            VIA   -    MD0080PA01X+074055Y+124724X0160Y         S0      
327m5371            PEX1  -C38        A01X+074055Y+124724X0180Y         S1      
317m5372            VIA   -    MD0100PA01X+030282Y+136010X0180Y         S0      
317m5372            J11   -F8   D0122PA01X+034374Y+159602X0282Y    R180 S3      
327m5372            C113  -2          A01X+030272Y+135519X0120Y0150R090 S1      
317m5373            VIA   -    MD0080PA01X+027598Y+110512X0160Y    R270 S0      
327m5373            C41   -1          A01X+015360Y+049057X0120Y0150     S1      
317m5373            VIA   -    MD0100PA01X+014869Y+049067X0200Y    R270 S0      
327m5373            PEX0  -BA36       A01X+027598Y+110512X0180Y         S1      
327m5374            C184  -1          A01X+011633Y+135309X0120Y0150R090 S1      
317m5374            VIA   -    MD0100PA01X+011623Y+134819X0180Y         S0      
317m5374            VIA   -    MD0080PA01X+016378Y+120236X0160Y         S0      
327m5374            PEX0  -R6         A01X+016378Y+120236X0180Y         S1      
317m5375            J12   -Y7   D0122PA01X+050831Y+145862X0282Y    R180 S3      
317m5375            VIA   -    MD0080PA01X+074055Y+124350X0160Y         S0      
327m5375            PEX1  -D38        A01X+074055Y+124350X0180Y         S1      
317m5376            VIA   -    MD0100PA01X+025386Y+136010X0180Y         S0      
317m5376            J11   -F2   D0122PA01X+029177Y+159602X0282Y    R180 S3      
327m5376            C125  -2          A01X+025376Y+135519X0120Y0150R090 S1      
317m5377            VIA   -    MD0080PA01X+030216Y+111260X0160Y    R270 S0      
327m5377            PEX0  -AW43       A01X+030216Y+111260X0180Y         S1      
327m5377            C19   -1          A01X+031609Y+052911X0120Y0150R180 S1      
317m5377            VIA   -    MD0100PA01X+032099Y+052901X0200Y    R090 S0      
327m5378            C163  -1          A01X+018617Y+140149X0120Y0150R090 S1      
317m5378            VIA   -    MD0100PA01X+018627Y+139658X0180Y         S0      
317m5378            VIA   -    MD0080PA01X+016378Y+122480X0160Y         S0      
327m5378            PEX0  -J6         A01X+016378Y+122480X0180Y         S1      
317m5379            J5    -O8   D0122PA01X+069020Y+150902X0282Y    R180 S3      
317m5379            VIA   -    MD0080PA01X+062461Y+125098X0160Y         S0      
327m5379            PEX1  -B7         A01X+062461Y+125098X0180Y         S1      
317m5380            VIA   -    MD0100PA01X+030622Y+136010X0180Y         S0      
317m5380            J11   -E8   D0122PA01X+034374Y+160114X0282Y    R180 S3      
327m5380            C114  -2          A01X+030632Y+135519X0120Y0150R090 S1      
317m5381            VIA   -    MD0100PA01X+056620Y+138430X0180Y         S0      
317m5381            J12   -E8   D0122PA01X+051697Y+160114X0282Y    R180 S3      
327m5381            C2260 -2          A01X+056630Y+137939X0120Y0150R090 S1      
317m5382            VIA   -    MD0080PA01X+024232Y+109390X0160Y    R270 S0      
327m5382            C60   -1          A01X+015360Y+040867X0120Y0150     S1      
317m5382            VIA   -    MD0100PA01X+014869Y+040857X0200Y    R270 S0      
327m5382            PEX0  -BD27       A01X+024232Y+109390X0180Y         S1      
317m5383            J5    -O7   D0122PA01X+068154Y+150980X0282Y    R180 S3      
317m5383            VIA   -    MD0080PA01X+062087Y+124724X0160Y         S0      
327m5383            PEX1  -C6         A01X+062087Y+124724X0180Y         S1      
317m5384            VIA   -    MD0100PA01X+067525Y+138430X0180Y         S0      
317m5384            J5    -I6   D0122PA01X+067287Y+158067X0282Y    R180 S3      
327m5384            C392  -2          A01X+067515Y+137939X0120Y0150R090 S1      
317m5385            VIA   -    MD0080PA01X+029468Y+109764X0160Y    R270 S0      
327m5385            PEX0  -BC41       A01X+029468Y+109764X0180Y         S1      
327m5385            C1    -1          A01X+032649Y+061461X0120Y0150R180 S1      
317m5385            VIA   -    MD0100PA01X+033140Y+061451X0200Y    R090 S0      
317m5386            J12   -W2   D0122PA01X+046500Y+146807X0282Y    R180 S3      
317m5386            VIA   -    MD0080PA01X+072185Y+125472X0160Y    R090 S0      
327m5386            PEX1  -A33        A01X+072185Y+125472X0180Y         S1      
317m5387            VIA   -    MD0100PA01X+053832Y+138430X0180Y         S0      
317m5387            J12   -G5   D0122PA01X+049098Y+159169X0282Y    R180 S3      
327m5387            C2265 -2          A01X+053822Y+137939X0120Y0150R090 S1      
317m5388            VIA   -    MD0080PA01X+027224Y+109764X0160Y    R270 S0      
327m5388            PEX0  -BC35       A01X+027224Y+109764X0180Y         S1      
327m5388            C43   -1          A01X+014320Y+048346X0120Y0150     S1      
317m5388            VIA   -    MD0100PA01X+013829Y+048356X0200Y    R270 S0      
327m5389            C191  -1          A01X+007601Y+137729X0120Y0150R090 S1      
317m5389            VIA   -    MD0100PA01X+007611Y+137238X0180Y         S0      
317m5389            VIA   -    MD0080PA01X+016752Y+118740X0160Y         S0      
327m5389            PEX0  -W7         A01X+016752Y+118740X0180Y         S1      
317m5390            J12   -X1   D0122PA01X+045634Y+146374X0282Y    R180 S3      
317m5390            VIA   -    MD0080PA01X+071811Y+124724X0160Y         S0      
327m5390            PEX1  -C32        A01X+071811Y+124724X0180Y         S1      
317m5391            VIA   -    MD0080PA01X+030590Y+112008X0160Y    R270 S0      
327m5391            PEX0  -AU44       A01X+030590Y+112008X0180Y         S1      
327m5391            C24   -1          A01X+031609Y+051134X0120Y0150R180 S1      
317m5391            VIA   -    MD0100PA01X+032099Y+051144X0200Y    R090 S0      
317m5392            J5    -P7   D0122PA01X+068154Y+150468X0282Y    R180 S3      
317m5392            VIA   -    MD0080PA01X+062087Y+124350X0160Y         S0      
327m5392            PEX1  -D6         A01X+062087Y+124350X0180Y         S1      
317m5393            VIA   -    MD0080PA01X+032461Y+109016X0160Y    R270 S0      
327m5393            PEX0  -BE49       A01X+032461Y+109016X0180Y         S1      
327m5393            C16   -1          A01X+031609Y+056138X0120Y0150R180 S1      
317m5393            VIA   -    MD0100PA01X+032099Y+056148X0200Y    R090 S0      
317m5394            J12   -X2   D0122PA01X+046500Y+146295X0282Y    R180 S3      
317m5394            VIA   -    MD0080PA01X+072185Y+125098X0160Y    R090 S0      
327m5394            PEX1  -B33        A01X+072185Y+125098X0180Y         S1      
317m5395            VIA   -    MD0080PA01X+028720Y+109390X0160Y    R270 S0      
327m5395            PEX0  -BD39       A01X+028720Y+109390X0180Y         S1      
327m5395            C36   -1          A01X+014320Y+053119X0120Y0150     S1      
317m5395            VIA   -    MD0100PA01X+013829Y+053109X0200Y    R270 S0      
317m5396            J5    -O6   D0122PA01X+067287Y+150902X0282Y    R180 S3      
317m5396            VIA   -    MD0080PA01X+061713Y+125098X0160Y         S0      
327m5396            PEX1  -B5         A01X+061713Y+125098X0180Y         S1      
317m5397            VIA   -    MD0080PA01X+023858Y+110512X0160Y    R270 S0      
327m5397            PEX0  -BA26       A01X+023858Y+110512X0180Y         S1      
327m5397            C61   -1          A01X+014560Y+039801X0120Y0150     S1      
317m5397            VIA   -    MD0100PA01X+014069Y+039811X0200Y    R270 S0      
317m5398            VIA   -    MD0100PA01X+012847Y+137238X0180Y         S0      
327m5398            C180  -1          A01X+012857Y+137729X0120Y0150R090 S1      
317m5398            VIA   -    MD0080PA01X+016378Y+120984X0160Y         S0      
327m5398            PEX0  -N6         A01X+016378Y+120984X0180Y         S1      
317m5399            J12   -Y1   D0122PA01X+045634Y+145862X0282Y    R180 S3      
317m5399            VIA   -    MD0080PA01X+071811Y+124350X0160Y         S0      
327m5399            PEX1  -D32        A01X+071811Y+124350X0180Y         S1      
317m5400            VIA   -    MD0080PA01X+030590Y+110512X0160Y    R270 S0      
327m5400            C7    -1          A01X+031609Y+059332X0120Y0150R180 S1      
317m5400            VIA   -    MD0100PA01X+032099Y+059322X0200Y    R090 S0      
327m5400            PEX0  -BA44       A01X+030590Y+110512X0180Y         S1      
327m5401            C178  -1          A01X+014081Y+135309X0120Y0150R090 S1      
317m5401            VIA   -    MD0100PA01X+014071Y+134819X0180Y         S0      
317m5401            VIA   -    MD0080PA01X+017126Y+121358X0160Y         S0      
327m5401            PEX0  -M8         A01X+017126Y+121358X0180Y         S1      
317m5402            J5    -O3   D0122PA01X+064689Y+150980X0282Y    R180 S3      
317m5402            VIA   -    MD0080PA01X+060590Y+124724X0160Y         S0      
327m5402            PEX1  -C2         A01X+060590Y+124724X0180Y         S1      
317m5403            VIA   -    M      A01X+162396Y+044296X0200Y         S2      
017m5403            VIA   -    M      A18X+162396Y+044296X0260Y         S2      
017m5403                  -    MD0100PA00X+162396Y+044296                       
327m5403            U43   -4          A18X+164094Y+045871X0240Y0240R270 S2      
327m5403            R392  -1   M      A01X+162038Y+044587X0198Y0197     S1      
327m5403            R394  -2          A01X+162038Y+045387X0198Y0197R180 S1      
327m5403            R395  -1   M      A01X+162038Y+044987X0198Y0197     S1      
317m5404            VIA   -    MD0080PA01X+025354Y+110138X0160Y    R270 S0      
327m5404            C54   -1          A01X+014320Y+042996X0120Y0150     S1      
317m5404            VIA   -    MD0100PA01X+013829Y+042986X0200Y    R270 S0      
327m5404            PEX0  -BB30       A01X+025354Y+110138X0180Y         S1      
327m5405            C174  -1          A01X+014945Y+137729X0120Y0150R090 S1      
317m5405            VIA   -    MD0100PA01X+014955Y+137238X0180Y         S0      
317m5405            VIA   -    MD0080PA01X+014508Y+122854X0160Y    R270 S0      
327m5405            PEX0  -H1         A01X+014508Y+122854X0180Y         S1      
317m5406            J5    -N2   D0122PA01X+063823Y+151413X0282Y    R180 S3      
317m5406            VIA   -    MD0080PA01X+060590Y+122106X0160Y         S0      
327m5406            PEX1  -K2         A01X+060590Y+122106X0180Y         S1      
327m5407            VIA   -    M      A18X+163065Y+044304X0260Y         S2      
327m5407            R393  -2          A18X+163298Y+043832X0198Y0197R180 S2      
327m5407            U43   -2          A18X+164390Y+045163X0160Y0240R180 S2      
317m5408            VIA   -    MD0080PA01X+030216Y+109764X0160Y    R270 S0      
327m5408            C5    -1          A01X+032649Y+060044X0120Y0150R180 S1      
317m5408            VIA   -    MD0100PA01X+033140Y+060034X0200Y    R090 S0      
327m5408            PEX0  -BC43       A01X+030216Y+109764X0180Y         S1      
327m5409            C185  -1          A01X+010049Y+137729X0120Y0150R090 S1      
317m5409            VIA   -    MD0100PA01X+010059Y+137238X0180Y         S0      
317m5409            VIA   -    MD0080PA01X+017500Y+119862X0160Y         S0      
327m5409            PEX0  -T9         A01X+017500Y+119862X0180Y         S1      
317m5410            J12   -W8   D0122PA01X+051697Y+146807X0282Y    R180 S3      
317m5410            VIA   -    MD0080PA01X+074429Y+125472X0160Y    R090 S0      
327m5410            PEX1  -A39        A01X+074429Y+125472X0180Y         S1      
317m5411            VIA   -    MD0080PA01X+025354Y+110512X0160Y    R270 S0      
327m5411            PEX0  -BA30       A01X+025354Y+110512X0180Y         S1      
327m5411            C53   -1          A01X+014320Y+042636X0120Y0150     S1      
317m5411            VIA   -    MD0100PA01X+013829Y+042646X0200Y    R270 S0      
317m5412            J5    -O2   D0122PA01X+063823Y+150902X0282Y    R180 S3      
317m5412            VIA   -    MD0080PA01X+060216Y+122106X0160Y         S0      
327m5412            PEX1  -K1         A01X+060216Y+122106X0180Y         S1      
317m5413            VIA   -    MD0080PA01X+029468Y+111634X0160Y    R270 S0      
327m5413            PEX0  -AV41M      A01X+029468Y+111634X0180Y         S1      
317m5413            VIA   -    MD0100PA01X+033140Y+052195X0200Y    R090 S0      
327m5413            C21   -1          A01X+032649Y+052205X0120Y0150R180 S1      
317m5414            J12   -X5   D0122PA01X+049098Y+146374X0282Y    R180 S3      
317m5414            VIA   -    MD0080PA01X+073307Y+124724X0160Y         S0      
327m5414            PEX1  -C36        A01X+073307Y+124724X0180Y         S1      
317m5415            VIA   -    MD0080PA01X+030216Y+112756X0160Y    R270 S0      
327m5415            PEX0  -AR43       A01X+030216Y+112756X0180Y         S1      
327m5415            C27   -1          A01X+031609Y+048498X0120Y0150R180 S1      
317m5415            VIA   -    MD0100PA01X+032099Y+048488X0200Y    R090 S0      
327m5416            C188  -1          A01X+009185Y+140149X0120Y0150R090 S1      
317m5416            VIA   -    MD0100PA01X+009175Y+139658X0180Y         S0      
317m5416            VIA   -    MD0080PA01X+016378Y+119488X0160Y         S0      
327m5416            PEX0  -U6         A01X+016378Y+119488X0180Y         S1      
317m5417            J5    -N8   D0122PA01X+069020Y+151413X0282Y    R180 S3      
317m5417            VIA   -    MD0080PA01X+062461Y+125472X0160Y         S0      
327m5417            PEX1  -A7         A01X+062461Y+125472X0180Y         S1      
317VSSA_SENSE       VIA   -    MD0080PA00X+110600Y+114065X0160Y         S0      
317VSSA_SENSE       VIA   -    MD0080PA00X+156309Y+114065X0160Y         S0      
317VSSA_SENSE       VIA   -    MD0080PA00X+019183Y+114065X0160Y         S0      
317VSSA_SENSE       VIA   -    MD0080PA00X+064892Y+114065X0160Y         S0      
317VSSA_SENSE       VIA   -    MD0100PA00X+107687Y+104729X0200Y         S0      
317VSSA_SENSE       VIA   -    M      A01X+153199Y+105645X0200Y         S2      
017VSSA_SENSE       VIA   -    M      A18X+153199Y+105645X0260Y         S2      
017VSSA_SENSE             -    MD0100PA00X+153199Y+105645                       
327VSSA_SENSE       PEX0  -AL14       A01X+019370Y+114252X0180Y         S1      
317VSSA_SENSE       VIA   -    MD0100PA00X+016073Y+105659X0200Y         S0      
327VSSA_SENSE       PEX1  -AL14       A01X+065079Y+114252X0180Y         S1      
317VSSA_SENSE       VIA   -    MD0100PA00X+062159Y+103386X0200Y         S0      
327VSSA_SENSE       PEX2  -AL14       A01X+110787Y+114252X0180Y         S1      
327VSSA_SENSE       PEX3  -AL14       A01X+156496Y+114252X0180Y         S1      
317m5418            VIA   -    MD0080PA01X+029842Y+111634X0160Y    R270 S0      
327m5418            PEX0  -AV42       A01X+029842Y+111634X0180Y         S1      
327m5418            C22   -1          A01X+032649Y+051845X0120Y0150R180 S1      
317m5418            VIA   -    MD0100PA01X+033140Y+051855X0200Y    R090 S0      
317m5419            VIA   -    MD0080PA01X+061339Y+121732X0160Y         S0      
317m5419            J5    -P1   D0122PA01X+062957Y+150468X0282Y    R180 S3      
327m5419            PEX1  -L4         A01X+061339Y+121732X0180Y         S1      
317m5420            VIA   -    MD0080PA01X+024606Y+110138X0160Y    R270 S0      
327m5420            PEX0  -BB28       A01X+024606Y+110138X0180Y         S1      
327m5420            C58   -1          A01X+014320Y+041579X0120Y0150     S1      
317m5420            VIA   -    MD0100PA01X+013829Y+041569X0200Y    R270 S0      
317m5421            J12   -X4   D0122PA01X+048232Y+146295X0282Y    R180 S3      
317m5421            VIA   -    MD0080PA01X+072933Y+125098X0160Y    R090 S0      
327m5421            PEX1  -B35        A01X+072933Y+125098X0180Y         S1      
317m5422            VIA   -    M      A01X+025270Y+044296X0200Y         S2      
017m5422            VIA   -    M      A18X+025270Y+044296X0260Y         S2      
017m5422                  -    MD0100PA00X+025270Y+044296                       
327m5422            R86   -1   M      A01X+024912Y+044587X0198Y0197     S1      
327m5422            R88   -2          A01X+024912Y+045387X0198Y0197R180 S1      
327m5422            R89   -1   M      A01X+024912Y+044987X0198Y0197     S1      
327m5422            U13   -4          A18X+026968Y+045871X0240Y0240R270 S2      
317m5423            VIA   -    MD0080PA01X+032087Y+110138X0160Y    R270 S0      
327m5423            PEX0  -BB48       A01X+032087Y+110138X0180Y         S1      
317m5423            VIA   -    MD0100PA01X+033140Y+053612X0200Y    R090 S0      
327m5423            C17   -1          A01X+032649Y+053622X0120Y0150R180 S1      
317m5424            J3    -C1   D0122PA01X+010988Y+161217X0282Y    R180 S3      
317m5424            VIA   -    MD0080PA01X+015256Y+118740X0160Y         S0      
327m5424            PEX0  -W3         A01X+015256Y+118740X0180Y         S1      
327m5425            VIA   -    M      A18X+026011Y+044358X0260Y         S2      
327m5425            R87   -2          A18X+026172Y+043832X0198Y0197R180 S2      
327m5425            U13   -2          A18X+027264Y+045163X0160Y0240R180 S2      
317m5426            VIA   -    MD0080PA01X+024980Y+109390X0160Y         S0      
327m5426            C56   -1          A01X+015360Y+042285X0120Y0150     S1      
317m5426            VIA   -    MD0100PA01X+014869Y+042275X0200Y    R270 S0      
327m5426            PEX0  -BD29       A01X+024980Y+109390X0180Y         S1      
317m5427            VIA   -    MD0100PA01X+012507Y+137238X0180Y         S0      
327m5427            C179  -1          A01X+012497Y+137729X0120Y0150R090 S1      
317m5427            VIA   -    MD0080PA01X+016752Y+120984X0160Y         S0      
327m5427            PEX0  -N7         A01X+016752Y+120984X0180Y         S1      
317m5428            J3    -C7   D0122PA01X+016185Y+161217X0282Y    R180 S3      
317m5428            VIA   -    MD0080PA01X+015256Y+120984X0160Y         S0      
327m5428            PEX0  -N3         A01X+015256Y+120984X0180Y         S1      
327m5429            R239  -1   M      A01X+114435Y+055770X0198Y0197R180 S1      
327m5429            R241  -2          A01X+114435Y+054970X0198Y0197     S1      
327m5429            R242  -1   M      A01X+114435Y+055370X0198Y0197R180 S1      
317m5429            VIA   -    M      A01X+113767Y+056800X0200Y         S2      
017m5429            VIA   -    M      A18X+113767Y+056800X0260Y         S2      
017m5429                  -    MD0100PA00X+113767Y+056800                       
327m5429            U28   -4          A18X+113372Y+055780X0240Y0240R180 S2      
327HP_NIC2_PWRGD    VIA   -    M      A01X+067442Y+068969X0300Y         S1      
327HP_NIC2_PWRGD    R153  -2          A01X+066514Y+068969X0198Y0197     S1      
327HP_NIC2_PWRGD    U22   -1          A01X+070767Y+066991X0400Y0500R180 S1      
327HP_NIC2_PWRGD    R151  -2   M      A01X+070893Y+067589X0198Y0197     S1      
317m5430            VIA   -    MD0080PA01X+030964Y+109764X0160Y    R270 S0      
327m5430            PEX0  -BC45       A01X+030964Y+109764X0180Y         S1      
327m5430            C9    -1          A01X+032649Y+058626X0120Y0150R180 S1      
317m5430            VIA   -    MD0100PA01X+033140Y+058616X0200Y    R090 S0      
327m5431            C192  -1          A01X+007961Y+137729X0120Y0150R090 S1      
317m5431            VIA   -    MD0100PA01X+007951Y+137238X0180Y         S0      
317m5431            VIA   -    MD0080PA01X+016378Y+118740X0160Y         S0      
327m5431            PEX0  -W6         A01X+016378Y+118740X0180Y         S1      
317m5432            J3    -C6   D0122PA01X+015319Y+161138X0282Y    R180 S3      
317m5432            VIA   -    MD0080PA01X+014882Y+120610X0160Y         S0      
327m5432            PEX0  -P2         A01X+014882Y+120610X0180Y         S1      
327m5433            VIA   -    M      A18X+112967Y+054400X0260Y         S2      
327m5433            U28   -2          A18X+112663Y+055485X0160Y0240R090 S2      
327m5433            R240  -2          A18X+113467Y+053958X0198Y0197R270 S2      
317PRSNT_NIC2_N     VIA   -    MD0100PA00X+067846Y+045598X0200Y         S0      
327PRSNT_NIC2_N     R145  -2          A01X+058432Y+045566X0198Y0197R090 S1      
327PRSNT_NIC2_N     R141  -1   M      A01X+060811Y+045960X0198Y0197     S1      
327PRSNT_NIC2_N     R142  -1          A01X+067846Y+045880X0198Y0197R180 S1      
317PRSNT_NIC2_N     VIA   -    MD0100PA00X+060526Y+045871X0200Y         S0      
317PRSNT_NIC2_N     VIA   -    M      A01X+060515Y+037860X0200Y         S2      
017PRSNT_NIC2_N     VIA   -    M      A18X+060515Y+037860X0260Y         S2      
017PRSNT_NIC2_N           -    MD0100PA00X+060515Y+037860                       
327PRSNT_NIC2_N     R144  -1          A01X+060811Y+037860X0198Y0197     S1      
327PRSNT_NIC2_N     R143  -1          A01X+067866Y+054580X0198Y0197R180 S1      
317PRSNT_NIC2_N     VIA   -    MD0100PA00X+068209Y+054050X0200Y         S0      
317m5434            VIA   -    MD0080PA01X+030590Y+111260X0160Y    R270 S0      
327m5434            PEX0  -AW44       A01X+030590Y+111260X0180Y         S1      
327m5434            C20   -1          A01X+031609Y+052551X0120Y0150R180 S1      
317m5434            VIA   -    MD0100PA01X+032099Y+052561X0200Y    R090 S0      
327m5435            C166  -1          A01X+018977Y+135309X0120Y0150R090 S1      
317m5435            VIA   -    MD0100PA01X+018967Y+134819X0180Y         S0      
317m5435            VIA   -    MD0080PA01X+016004Y+123602X0160Y    R270 S0      
327m5435            PEX0  -F5         A01X+016004Y+123602X0180Y         S1      
317m5436            J3    -D7   D0122PA01X+016185Y+160705X0282Y    R180 S3      
317m5436            VIA   -    MD0080PA01X+015630Y+120984X0160Y         S0      
327m5436            PEX0  -N4         A01X+015630Y+120984X0180Y         S1      
317PRSNT_NIC5_N     VIA   -    M      A01X+116330Y+046587X0200Y         S2      
017PRSNT_NIC5_N     VIA   -    M      A18X+116330Y+046587X0260Y         S2      
017PRSNT_NIC5_N           -    MD0100PA00X+116330Y+046587                       
327PRSNT_NIC5_N     R296  -1          A01X+116330Y+046286X0198Y0197     S1      
317PRSNT_NIC5_N     VIA   -    MD0100PA00X+115954Y+054671X0200Y    R180 S0      
327PRSNT_NIC5_N     R297  -1          A01X+123283Y+062691X0198Y0197R180 S1      
317PRSNT_NIC5_N     VIA   -    MD0100PA00X+123593Y+062623X0200Y    R180 S0      
317PRSNT_NIC5_N     VIA   -    MD0100PA00X+125309Y+055310X0200Y         S0      
327PRSNT_NIC5_N     R294  -1   M      A01X+123283Y+054591X0198Y0197R180 S1      
327PRSNT_NIC5_N     R298  -2          A01X+125646Y+055514X0198Y0197R270 S1      
327PRSNT_NIC5_N     R295  -1   M      A01X+116248Y+054671X0198Y0197     S1      
327m5437            VIA   -    M      A01X+065160Y+070437X0300Y         S1      
327m5437            Q3    -3          A01X+065665Y+070228X0170Y0240R180 S1      
327m5437            Q3    -2          A01X+065921Y+070228X0170Y0240R180 S1      
327m5437            R152  -2   M      A01X+065787Y+071013X0198Y0197R180 S1      
317m5438            VIA   -    MD0080PA01X+029842Y+110138X0160Y    R270 S0      
327m5438            PEX0  -BB42       A01X+029842Y+110138X0180Y         S1      
327m5438            C4    -1          A01X+031609Y+060390X0120Y0150R180 S1      
317m5438            VIA   -    MD0100PA01X+032099Y+060400X0200Y    R090 S0      
317m5439            J11   -M7   D0122PA01X+033508Y+156098X0282Y    R180 S3      
317m5439            VIA   -    MD0080PA01X+025354Y+124350X0160Y         S0      
327m5439            PEX0  -D30        A01X+025354Y+124350X0180Y         S1      
317HP_NIC5_PWRGD    VIA   -    M      A01X+122925Y+031489X0200Y         S2      
017HP_NIC5_PWRGD    VIA   -    M      A18X+122925Y+031489X0260Y         S2      
017HP_NIC5_PWRGD          -    MD0100PA00X+122925Y+031489                       
327HP_NIC5_PWRGD    R306  -2          A01X+122644Y+031874X0198Y0197R270 S1      
327HP_NIC5_PWRGD    R304  -2   M      A01X+122644Y+031489X0198Y0197R090 S1      
327HP_NIC5_PWRGD    U37   -1          A01X+123360Y+031285X0400Y0500     S1      
317m5440            VIA   -    M      A01X+066564Y+064606X0200Y         S2      
017m5440            VIA   -    M      A18X+066564Y+064606X0260Y         S2      
017m5440                  -    MD0100PA00X+066564Y+064606                       
327m5440            U20   -4          A01X+065260Y+065316X0160Y0360R270 S1      
327m5440            R147  -2   M      A01X+065806Y+065631X0198Y0197R090 S1      
327m5440            R150  -2          A01X+067906Y+062140X0198Y0197     S1      
327m5440            R149  -2   M      A01X+067906Y+062540X0198Y0197     S1      
327m5440            R148  -2   M      A01X+066206Y+065631X0198Y0197R090 S1      
317m5441            VIA   -    MD0080PA01X+025728Y+109764X0160Y         S0      
327m5441            C51   -1          A01X+015360Y+043342X0120Y0150     S1      
317m5441            VIA   -    MD0100PA01X+014869Y+043352X0200Y    R270 S0      
327m5441            PEX0  -BC31       A01X+025728Y+109764X0180Y         S1      
317m5442            J11   -K4   D0122PA01X+030909Y+157043X0282Y    R180 S3      
317m5442            VIA   -    MD0080PA01X+024232Y+125472X0160Y    R090 S0      
327m5442            PEX0  -A27        A01X+024232Y+125472X0180Y         S1      
327m5443            R302  -2   M      A01X+114486Y+038072X0198Y0197R180 S1      
327m5443            R303  -2          A01X+114486Y+038472X0198Y0197R180 S1      
327m5443            VIA   -    M      A01X+116967Y+037350X0300Y    R180 S1      
327m5443            R300  -2   M      A01X+123559Y+034232X0198Y0197R270 S1      
327m5443            U35   -4          A01X+122612Y+034232X0160Y0360R270 S1      
327m5443            R301  -2   M      A01X+123159Y+034232X0198Y0197R270 S1      
317m5444            VIA   -    MD0080PA01X+031712Y+109390X0160Y    R270 S0      
327m5444            PEX0  -BD47       A01X+031712Y+109390X0180Y         S1      
327m5444            C14   -1          A01X+032649Y+056849X0120Y0150R180 S1      
317m5444            VIA   -    MD0100PA01X+033140Y+056859X0200Y    R090 S0      
317m5445            J11   -L1   D0122PA01X+028311Y+156610X0282Y    R180 S3      
317m5445            VIA   -    MD0080PA01X+023110Y+124724X0160Y         S0      
327m5445            PEX0  -C24        A01X+023110Y+124724X0180Y         S1      
327m5446            VIA   -    M      A01X+120901Y+031791X0300Y         S1      
327m5446            R305  -2          A01X+120426Y+031787X0198Y0197     S1      
327m5446            Q6    -2          A01X+121401Y+031929X0170Y0240R270 S1      
327m5446            Q6    -3          A01X+121401Y+031673X0170Y0240R270 S1      
317m5447            VIA   -    MD0080PA01X+029468Y+109390X0160Y    R270 S0      
327m5447            PEX0  -BD41       A01X+029468Y+109390X0180Y         S1      
327m5447            C2    -1          A01X+032649Y+061101X0120Y0150R180 S1      
317m5447            VIA   -    MD0100PA01X+033140Y+061111X0200Y    R090 S0      
317m5448            J3    -C3   D0122PA01X+012720Y+161217X0282Y    R180 S3      
317m5448            VIA   -    MD0080PA01X+015256Y+119488X0160Y         S0      
327m5448            PEX0  -U3         A01X+015256Y+119488X0180Y         S1      
317m5449            VIA   -    MD0080PA01X+024980Y+109764X0160Y         S0      
327m5449            PEX0  -BC29       A01X+024980Y+109764X0180Y         S1      
327m5449            C55   -1          A01X+015360Y+041925X0120Y0150     S1      
317m5449            VIA   -    MD0100PA01X+014869Y+041935X0200Y    R270 S0      
317m5450            J11   -M3   D0122PA01X+030043Y+156098X0282Y    R180 S3      
317m5450            VIA   -    MD0080PA01X+023858Y+124350X0160Y         S0      
327m5450            PEX0  -D26        A01X+023858Y+124350X0180Y         S1      
317m5451            VIA   -    MD0080PA01X+023858Y+110138X0160Y    R270 S0      
327m5451            C62   -1          A01X+014560Y+040161X0120Y0150     S1      
317m5451            VIA   -    MD0100PA01X+014069Y+040151X0200Y    R270 S0      
327m5451            PEX0  -BB26       A01X+023858Y+110138X0180Y         S1      
317m5452            J11   -K2   D0122PA01X+029177Y+157043X0282Y    R180 S3      
317m5452            VIA   -    MD0080PA01X+023484Y+125472X0160Y    R090 S0      
327m5452            PEX0  -A25        A01X+023484Y+125472X0180Y         S1      
317m5453            VIA   -    MD0080PA01X+028346Y+110138X0160Y    R270 S0      
327m5453            C38   -1          A01X+015360Y+052413X0120Y0150     S1      
317m5453            VIA   -    MD0100PA01X+014869Y+052403X0200Y    R270 S0      
327m5453            PEX0  -BB38       A01X+028346Y+110138X0180Y         S1      
317m5454            J3    -B6   D0122PA01X+015319Y+161650X0282Y    R180 S3      
317m5454            VIA   -    MD0080PA01X+014508Y+120610X0160Y         S0      
327m5454            PEX0  -P1         A01X+014508Y+120610X0180Y         S1      
317m5455            VIA   -    MD0080PA01X+030216Y+113504X0160Y    R270 S0      
327m5455            PEX0  -AN43       A01X+030216Y+113504X0180Y         S1      
327m5455            C31   -1          A01X+031609Y+047081X0120Y0150R180 S1      
317m5455            VIA   -    MD0100PA01X+032099Y+047071X0200Y    R090 S0      
317m5456            J3    -C4   D0122PA01X+013587Y+161138X0282Y    R180 S3      
317m5456            VIA   -    MD0080PA01X+014882Y+119862X0160Y         S0      
327m5456            PEX0  -T2         A01X+014882Y+119862X0180Y         S1      
317m5457            VIA   -    MD0080PA01X+029468Y+112382X0160Y    R270 S0      
327m5457            PEX0  -AT41M      A01X+029468Y+112382X0180Y         S1      
317m5457            VIA   -    MD0100PA01X+033140Y+049199X0200Y    R090 S0      
327m5457            C25   -1          A01X+032649Y+049209X0120Y0150R180 S1      
317m5458            J11   -K6   D0122PA01X+032642Y+157043X0282Y    R180 S3      
317m5458            VIA   -    MD0080PA01X+024980Y+125472X0160Y    R090 S0      
327m5458            PEX0  -A29        A01X+024980Y+125472X0180Y         S1      
317m5459            VIA   -    MD0100PA01X+011623Y+136010X0180Y         S0      
317m5459            J3    -I5   D0122PA01X+014453Y+158146X0282Y    R180 S3      
327m5459            C184  -2          A01X+011633Y+135519X0120Y0150R090 S1      
317m5460            VIA   -    MD0080PA01X+023484Y+109764X0160Y    R270 S0      
327m5460            PEX0  -BC25       A01X+023484Y+109764X0180Y         S1      
327m5460            C63   -1          A01X+015360Y+039090X0120Y0150     S1      
317m5460            VIA   -    MD0100PA01X+014869Y+039100X0200Y    R270 S0      
317m5461            J3    -C2   D0122PA01X+011854Y+161138X0282Y    R180 S3      
317m5461            VIA   -    MD0080PA01X+014882Y+119114X0160Y         S0      
327m5461            PEX0  -V2         A01X+014882Y+119114X0180Y         S1      
317m5462            VIA   -    MD0100PA01X+011623Y+140850X0180Y         S0      
317m5462            J3    -H6   D0122PA01X+015319Y+158579X0282Y    R180 S3      
327m5462            C182  -2          A01X+011633Y+140359X0120Y0150R090 S1      
317m5463            VIA   -    MD0080PA01X+024232Y+109764X0160Y    R270 S0      
327m5463            PEX0  -BC27       A01X+024232Y+109764X0180Y         S1      
327m5463            C59   -1          A01X+015360Y+040507X0120Y0150     S1      
317m5463            VIA   -    MD0100PA01X+014869Y+040517X0200Y    R270 S0      
317m5464            J3    -C5   D0122PA01X+014453Y+161217X0282Y    R180 S3      
317m5464            VIA   -    MD0080PA01X+015256Y+120236X0160Y         S0      
327m5464            PEX0  -R3         A01X+015256Y+120236X0180Y         S1      
317m5465            VIA   -    MD0080PA01X+029842Y+110512X0160Y    R270 S0      
327m5465            PEX0  -BA42       A01X+029842Y+110512X0180Y         S1      
327m5465            C3    -1          A01X+031609Y+060750X0120Y0150R180 S1      
317m5465            VIA   -    MD0100PA01X+032099Y+060740X0200Y    R090 S0      
317m5466            J3    -B2   D0122PA01X+011854Y+161650X0282Y    R180 S3      
317m5466            VIA   -    MD0080PA01X+014508Y+119114X0160Y         S0      
327m5466            PEX0  -V1         A01X+014508Y+119114X0180Y         S1      
317m5467            VIA   -    MD0100PA01X+011283Y+140850X0180Y         S0      
317m5467            J3    -I6   D0122PA01X+015319Y+158067X0282Y    R180 S3      
327m5467            C181  -2          A01X+011273Y+140359X0120Y0150R090 S1      
317m5468            VIA   -    MD0080PA01X+030590Y+113504X0160Y    R270 S0      
327m5468            PEX0  -AN44       A01X+030590Y+113504X0180Y         S1      
327m5468            C32   -1          A01X+031609Y+046721X0120Y0150R180 S1      
317m5468            VIA   -    MD0100PA01X+032099Y+046731X0200Y    R090 S0      
317m5469            J3    -D1   D0122PA01X+010988Y+160705X0282Y    R180 S3      
317m5469            VIA   -    MD0080PA01X+015630Y+118740X0160Y         S0      
327m5469            PEX0  -W4         A01X+015630Y+118740X0180Y         S1      
317m5470            VIA   -    MD0080PA01X+024606Y+110512X0160Y    R270 S0      
327m5470            PEX0  -BA28       A01X+024606Y+110512X0180Y         S1      
327m5470            C57   -1          A01X+014320Y+041219X0120Y0150     S1      
317m5470            VIA   -    MD0100PA01X+013829Y+041229X0200Y    R270 S0      
317m5471            VIA   -    MD0080PA01X+025728Y+125472X0160Y    R090 S0      
317m5471            J11   -K8   D0122PA01X+034374Y+157043X0282Y    R180 S3      
327m5471            PEX0  -A31        A01X+025728Y+125472X0180Y         S1      
317m5472            VIA   -    MD0100PA01X+012847Y+138430X0180Y         S0      
317m5472            J3    -I7   D0122PA01X+016185Y+158146X0282Y    R180 S3      
327m5472            C180  -2          A01X+012857Y+137939X0120Y0150R090 S1      
317m5473            VIA   -    MD0100PA01X+052608Y+140850X0180Y         S0      
317m5473            J12   -F4   D0122PA01X+048232Y+159602X0282Y    R180 S3      
327m5473            C2267 -2          A01X+052598Y+140359X0120Y0150R090 S1      
317m5474            VIA   -    MD0080PA01X+023484Y+109390X0160Y    R270 S0      
327m5474            PEX0  -BD25       A01X+023484Y+109390X0180Y         S1      
327m5474            C64   -1          A01X+015360Y+039450X0120Y0150     S1      
317m5474            VIA   -    MD0100PA01X+014869Y+039440X0200Y    R270 S0      
317m5475            J11   -L7   D0122PA01X+033508Y+156610X0282Y    R180 S3      
317m5475            VIA   -    MD0080PA01X+025354Y+124724X0160Y         S0      
327m5475            PEX0  -C30        A01X+025354Y+124724X0180Y         S1      
317m5476            VIA   -    MD0100PA01X+050160Y+140850X0180Y         S0      
317m5476            J12   -G1   D0122PA01X+045634Y+159169X0282Y    R180 S3      
327m5476            C2273 -2          A01X+050150Y+140359X0120Y0150R090 S1      
317m5477            VIA   -    MD0080PA01X+026850Y+110512X0160Y    R270 S0      
327m5477            PEX0  -BA34       A01X+026850Y+110512X0180Y         S1      
327m5477            C45   -1          A01X+015360Y+047640X0120Y0150     S1      
317m5477            VIA   -    MD0100PA01X+014869Y+047650X0200Y    R270 S0      
317m5478            VIA   -    MD0080PA01X+025728Y+125098X0160Y    R090 S0      
317m5478            J11   -L8   D0122PA01X+034374Y+156532X0282Y    R180 S3      
327m5478            PEX0  -B31        A01X+025728Y+125098X0180Y         S1      
317m5479            VIA   -    MD0080PA01X+032087Y+109016X0160Y    R270 S0      
327m5479            PEX0  -BE48       A01X+032087Y+109016X0180Y         S1      
327m5479            C15   -1          A01X+031609Y+056498X0120Y0150R180 S1      
317m5479            VIA   -    MD0100PA01X+032099Y+056488X0200Y    R090 S0      
317m5480            J11   -L5   D0122PA01X+031776Y+156610X0282Y    R180 S3      
317m5480            VIA   -    MD0080PA01X+024606Y+124724X0160Y         S0      
327m5480            PEX0  -C28        A01X+024606Y+124724X0180Y         S1      
317m5481            VIA   -    MD0100PA01X+012507Y+138430X0180Y         S0      
317m5481            J3    -J7   D0122PA01X+016185Y+157634X0282Y    R180 S3      
327m5481            C179  -2          A01X+012497Y+137939X0120Y0150R090 S1      
317m5482            VIA   -    MD0100PA01X+027834Y+140850X0180Y         S0      
317m5482            J11   -F6   D0122PA01X+032642Y+159602X0282Y    R180 S3      
327m5482            C117  -2          A01X+027824Y+140359X0120Y0150R090 S1      
317m5483            VIA   -    MD0080PA01X+031338Y+110138X0160Y    R270 S0      
327m5483            PEX0  -BB46       A01X+031338Y+110138X0180Y         S1      
327m5483            C12   -1          A01X+031609Y+057555X0120Y0150R180 S1      
317m5483            VIA   -    MD0100PA01X+032099Y+057565X0200Y    R090 S0      
317m5484            J3    -B4   D0122PA01X+013587Y+161650X0282Y    R180 S3      
317m5484            VIA   -    MD0080PA01X+014508Y+119862X0160Y         S0      
327m5484            PEX0  -T1         A01X+014508Y+119862X0180Y         S1      
317m5485            VIA   -    MD0080PA01X+030590Y+112756X0160Y    R270 S0      
327m5485            PEX0  -AR44       A01X+030590Y+112756X0180Y         S1      
327m5485            C28   -1          A01X+031609Y+048138X0120Y0150R180 S1      
317m5485            VIA   -    MD0100PA01X+032099Y+048148X0200Y    R090 S0      
317m5486            J11   -L2   D0122PA01X+029177Y+156532X0282Y    R180 S3      
317m5486            VIA   -    MD0080PA01X+023484Y+125098X0160Y    R090 S0      
327m5486            PEX0  -B25        A01X+023484Y+125098X0180Y         S1      
317m5487            VIA   -    MD0100PA01X+029058Y+134819X0180Y         S0      
317m5487            VIA   -    MD0080PA01X+018996Y+123228X0160Y    R270 S0      
327m5487            PEX0  -G13        A01X+018996Y+123228X0180Y         S1      
327m5487            C139  -1          A01X+029048Y+135309X0120Y0150R090 S1      
317m5488            VIA   -    MD0100PA01X+011283Y+136010X0180Y         S0      
317m5488            J3    -J5   D0122PA01X+014453Y+157634X0282Y    R180 S3      
327m5488            C183  -2          A01X+011273Y+135519X0120Y0150R090 S1      
317m5489            VIA   -    MD0100PA01X+065077Y+138430X0180Y         S0      
317m5489            J5    -J3   D0122PA01X+064689Y+157634X0282Y    R180 S3      
327m5489            C398  -2          A01X+065067Y+137939X0120Y0150R090 S1      
317m5490            VIA   -    MD0080PA01X+030216Y+112008X0160Y    R270 S0      
327m5490            PEX0  -AU43       A01X+030216Y+112008X0180Y         S1      
327m5490            C23   -1          A01X+031609Y+051494X0120Y0150R180 S1      
317m5490            VIA   -    MD0100PA01X+032099Y+051484X0200Y    R090 S0      
317m5491            J11   -L4   D0122PA01X+030909Y+156532X0282Y    R180 S3      
317m5491            VIA   -    MD0080PA01X+024232Y+125098X0160Y    R090 S0      
327m5491            PEX0  -B27        A01X+024232Y+125098X0180Y         S1      
317m5492            VIA   -    MD0100PA01X+036742Y+139658X0180Y         S0      
317m5492            VIA   -    MD0080PA01X+022736Y+123602X0160Y    R270 S0      
327m5492            C160  -1          A01X+036752Y+140149X0120Y0150R090 S1      
327m5492            PEX0  -F23        A01X+022736Y+123602X0180Y         S1      
317m5493            VIA   -    MD0100PA01X+066301Y+136010X0180Y         S0      
317m5493            J5    -I4   D0122PA01X+065555Y+158067X0282Y    R180 S3      
327m5493            C396  -2          A01X+066291Y+135519X0120Y0150R090 S1      
317m5494            VIA   -    MD0100PA01X+029398Y+138430X0180Y         S0      
317m5494            J11   -F7   D0122PA01X+033508Y+159681X0282Y    R180 S3      
327m5494            C116  -2          A01X+029408Y+137939X0120Y0150R090 S1      
317m5495            VIA   -    MD0080PA01X+026476Y+109764X0160Y    R270 S0      
327m5495            C47   -1          A01X+014320Y+046929X0120Y0150     S1      
317m5495            VIA   -    MD0100PA01X+013829Y+046939X0200Y    R270 S0      
327m5495            PEX0  -BC33       A01X+026476Y+109764X0180Y         S1      
317m5496            J11   -M1   D0122PA01X+028311Y+156098X0282Y    R180 S3      
317m5496            VIA   -    MD0080PA01X+023110Y+124350X0160Y         S0      
327m5496            PEX0  -D24        A01X+023110Y+124350X0180Y         S1      
317m5497            VIA   -    MD0100PA01X+028174Y+140850X0180Y         S0      
317m5497            J11   -E6   D0122PA01X+032642Y+160114X0282Y    R180 S3      
327m5497            C118  -2          A01X+028184Y+140359X0120Y0150R090 S1      
317m5498            VIA   -    MD0080PA01X+154626Y+109390X0160Y    R270 S0      
327m5498            PEX3  -BD9        A01X+154626Y+109390X0180Y         S1      
317m5498            VIA   -    MD0100PA01X+145767Y+013251X0200Y    R090 S0      
327m5498            C699  -1          A01X+145276Y+013241X0120Y0150R180 S1      
317m5499            J3    -D3   D0122PA01X+012720Y+160705X0282Y    R180 S3      
317m5499            VIA   -    MD0080PA01X+015630Y+119488X0160Y         S0      
327m5499            PEX0  -U4         A01X+015630Y+119488X0180Y         S1      
317m5500            VIA   -    MD0100PA01X+029058Y+139658X0180Y         S0      
317m5500            VIA   -    MD0080PA01X+019370Y+122480X0160Y         S0      
327m5500            PEX0  -J14        A01X+019370Y+122480X0180Y         S1      
327m5500            C141  -1          A01X+029048Y+140149X0120Y0150R090 S1      
317m5501            J11   -X1   D0122PA01X+028311Y+146374X0282Y    R180 S3      
317m5501            VIA   -    MD0080PA01X+026102Y+124724X0160Y         S0      
327m5501            PEX0  -C32        A01X+026102Y+124724X0180Y         S1      
317m5502            VIA   -    MD0100PA01X+027834Y+136010X0180Y         S0      
317m5502            J11   -G5   D0122PA01X+031776Y+159169X0282Y    R180 S3      
327m5502            C119  -2          A01X+027824Y+135519X0120Y0150R090 S1      
317m5503            VIA   -    MD0080PA01X+154626Y+109764X0160Y    R270 S0      
327m5503            PEX3  -BC9        A01X+154626Y+109764X0180Y         S1      
317m5503            VIA   -    MD0100PA01X+145767Y+013591X0200Y    R090 S0      
327m5503            C698  -1          A01X+145276Y+013601X0120Y0150R180 S1      
317m5504            J11   -L6   D0122PA01X+032642Y+156532X0282Y    R180 S3      
317m5504            VIA   -    MD0080PA01X+024980Y+125098X0160Y    R090 S0      
327m5504            PEX0  -B29        A01X+024980Y+125098X0180Y         S1      
317m5505            VIA   -    MD0100PA01X+132825Y+138430X0180Y         S0      
317m5505            J13   -S5   D0122PA01X+133972Y+148933X0282Y    R180 S3      
327m5505            C525  -2          A01X+132815Y+137939X0120Y0150R090 S1      
317m5506            VIA   -    MD0100PA01X+031846Y+139658X0180Y         S0      
317m5506            VIA   -    MD0080PA01X+020492Y+123602X0160Y    R270 S0      
327m5506            C148  -1          A01X+031856Y+140149X0120Y0150R090 S1      
327m5506            PEX0  -F17        A01X+020492Y+123602X0180Y         S1      
317m5507            VIA   -    MD0080PA01X+156496Y+110138X0160Y    R270 S0      
327m5507            PEX3  -BB14       A01X+156496Y+110138X0180Y         S1      
317m5507            VIA   -    MD0100PA01X+154963Y+012540X0200Y    R090 S0      
327m5507            C709  -1          A01X+154472Y+012530X0120Y0150R180 S1      
317m5508            J11   -M5   D0122PA01X+031776Y+156098X0282Y    R180 S3      
317m5508            VIA   -    MD0080PA01X+024606Y+124350X0160Y         S0      
327m5508            PEX0  -D28        A01X+024606Y+124350X0180Y         S1      
317m5509            J11   -Y1   D0122PA01X+028311Y+145862X0282Y    R180 S3      
317m5509            VIA   -    MD0080PA01X+026102Y+124350X0160Y         S0      
327m5509            PEX0  -D32        A01X+026102Y+124350X0180Y         S1      
317m5510            VIA   -    MD0080PA01X+157992Y+110512X0160Y    R270 S0      
327m5510            C716  -1          A01X+164708Y+012890X0120Y0150R180 S1      
317m5510            VIA   -    MD0100PA01X+165199Y+012880X0200Y    R090 S0      
327m5510            PEX3  -BA18       A01X+157992Y+110512X0180Y         S1      
317m5511            J11   -L3   D0122PA01X+030043Y+156610X0282Y    R180 S3      
317m5511            VIA   -    MD0080PA01X+023858Y+124724X0160Y         S0      
327m5511            PEX0  -C26        A01X+023858Y+124724X0180Y         S1      
317m5512            VIA   -    MD0100PA01X+034294Y+139658X0180Y         S0      
317m5512            VIA   -    MD0080PA01X+021614Y+122854X0160Y         S0      
327m5512            PEX0  -H20        A01X+021614Y+122854X0180Y         S1      
327m5512            C154  -1          A01X+034304Y+140149X0120Y0150R090 S1      
317m5513            J3    -P1   D0122PA01X+010988Y+150468X0282Y    R180 S3      
317m5513            VIA   -    MD0080PA01X+015630Y+121732X0160Y         S0      
327m5513            PEX0  -L4         A01X+015630Y+121732X0180Y         S1      
317m5514            VIA   -    MD0100PA01X+029058Y+138430X0180Y         S0      
317m5514            J11   -G7   D0122PA01X+033508Y+159169X0282Y    R180 S3      
327m5514            C115  -2          A01X+029048Y+137939X0120Y0150R090 S1      
327m5515            C761  -1          A01X+152607Y+140149X0120Y0150R090 S1      
317m5515            VIA   -    MD0100PA01X+152597Y+139658X0180Y         S0      
317m5515            VIA   -    MD0080PA01X+160236Y+122854X0160Y    R270 S0      
327m5515            PEX3  -H24        A01X+160236Y+122854X0180Y         S1      
317m5516            J3    -B8   D0122PA01X+017051Y+161650X0282Y    R180 S3      
317m5516            VIA   -    MD0080PA01X+014508Y+121358X0160Y         S0      
327m5516            PEX0  -M1         A01X+014508Y+121358X0180Y         S1      
317m5517            VIA   -    MD0100PA01X+130717Y+138430X0180Y         S0      
317m5517            J13   -Q2   D0122PA01X+131374Y+149878X0282Y    R180 S3      
327m5517            C532  -2          A01X+130727Y+137939X0120Y0150R090 S1      
327m5518            C754  -1          A01X+154695Y+140149X0120Y0150R090 S1      
317m5518            VIA   -    MD0100PA01X+154705Y+139658X0180Y         S0      
317m5518            VIA   -    MD0080PA01X+161358Y+123228X0160Y    R270 S0      
327m5518            PEX3  -G27        A01X+161358Y+123228X0180Y         S1      
317m5519            J3    -C8   D0122PA01X+017051Y+161138X0282Y    R180 S3      
317m5519            VIA   -    MD0080PA01X+014882Y+121358X0160Y         S0      
327m5519            PEX0  -M2         A01X+014882Y+121358X0180Y         S1      
317m5520            VIA   -    MD0100PA01X+111931Y+140850X0180Y         S0      
317m5520            J7    -U1   D0122PA01X+113185Y+147910X0282Y    R180 S3      
327m5520            C598  -2          A01X+111941Y+140359X0120Y0150R090 S1      
317m5521            VIA   -    MD0100PA01X+028174Y+136010X0180Y         S0      
317m5521            J11   -F5   D0122PA01X+031776Y+159681X0282Y    R180 S3      
327m5521            C120  -2          A01X+028184Y+135519X0120Y0150R090 S1      
317m5522            VIA   -    MD0080PA01X+157244Y+110512X0160Y    R270 S0      
327m5522            PEX3  -BA16       A01X+157244Y+110512X0180Y         S1      
317m5522            VIA   -    MD0100PA01X+154963Y+011462X0200Y    R090 S0      
327m5522            C712  -1          A01X+154472Y+011472X0120Y0150R180 S1      
317m5523            J3    -D5   D0122PA01X+014453Y+160705X0282Y    R180 S3      
317m5523            VIA   -    MD0080PA01X+015630Y+120236X0160Y         S0      
327m5523            PEX0  -R4         A01X+015630Y+120236X0180Y         S1      
317m5524            VIA   -    MD0100PA01X+062969Y+140850X0180Y         S0      
317m5524            J5    -I1   D0122PA01X+062957Y+158146X0282Y    R180 S3      
327m5524            C403  -2          A01X+062979Y+140359X0120Y0150R090 S1      
317m5525            VIA   -    MD0080PA01X+155374Y+109764X0160Y    R270 S0      
327m5525            PEX3  -BC11       A01X+155374Y+109764X0180Y         S1      
317m5525            VIA   -    MD0100PA01X+145767Y+012174X0200Y    R090 S0      
327m5525            C702  -1          A01X+145276Y+012184X0120Y0150R180 S1      
317m5526            VIA   -    MD0100PA01X+135613Y+138430X0180Y         S0      
317m5526            J13   -Q8   D0122PA01X+136571Y+149878X0282Y    R180 S3      
327m5526            C520  -2          A01X+135623Y+137939X0120Y0150R090 S1      
317m5527            VIA   -    MD0100PA01X+031846Y+134819X0180Y         S0      
317m5527            VIA   -    MD0080PA01X+020118Y+122854X0160Y         S0      
327m5527            PEX0  -H16        A01X+020118Y+122854X0180Y         S1      
327m5527            C146  -1          A01X+031856Y+135309X0120Y0150R090 S1      
317m5528            VIA   -    MD0080PA01X+157244Y+110138X0160Y    R270 S0      
327m5528            PEX3  -BB16       A01X+157244Y+110138X0180Y         S1      
317m5528            VIA   -    MD0100PA01X+154963Y+011122X0200Y    R090 S0      
327m5528            C713  -1          A01X+154472Y+011112X0120Y0150R180 S1      
317m5529            VIA   -    MD0100PA01X+052948Y+140850X0180Y         S0      
317m5529            J12   -E4   D0122PA01X+048232Y+160114X0282Y    R180 S3      
327m5529            C2268 -2          A01X+052958Y+140359X0120Y0150R090 S1      
327m5530            C741  -1          A01X+155055Y+137729X0120Y0150R090 S1      
317m5530            VIA   -    MD0100PA01X+155045Y+137238X0180Y         S0      
317m5530            VIA   -    MD0080PA01X+163976Y+122854X0160Y    R270 S0      
327m5530            PEX3  -H34        A01X+163976Y+122854X0180Y         S1      
317m5531            VIA   -    MD0100PA01X+131941Y+140850X0180Y         S0      
317m5531            J13   -Q4   D0122PA01X+133106Y+149878X0282Y    R180 S3      
327m5531            C528  -2          A01X+131951Y+140359X0120Y0150R090 S1      
317m5532            VIA   -    MD0100PA01X+036742Y+134819X0180Y         S0      
317m5532            VIA   -    MD0080PA01X+022362Y+122854X0160Y         S0      
327m5532            PEX0  -H22        A01X+022362Y+122854X0180Y         S1      
327m5532            C158  -1          A01X+036752Y+135309X0120Y0150R090 S1      
317m5533            VIA   -    MD0100PA01X+064193Y+140850X0180Y         S0      
317m5533            J5    -H2   D0122PA01X+063823Y+158579X0282Y    R180 S3      
327m5533            C401  -2          A01X+064203Y+140359X0120Y0150R090 S1      
327m5534            C734  -1          A01X+157143Y+137729X0120Y0150R090 S1      
317m5534            VIA   -    MD0100PA01X+157153Y+137238X0180Y         S0      
317m5534            VIA   -    MD0080PA01X+165098Y+123228X0160Y    R270 S0      
327m5534            PEX3  -G37        A01X+165098Y+123228X0180Y         S1      
327m5535            C736  -1          A01X+155919Y+140149X0120Y0150R090 S1      
317m5535            VIA   -    MD0100PA01X+155929Y+139658X0180Y         S0      
317m5535            VIA   -    MD0080PA01X+164724Y+122480X0160Y    R270 S0      
327m5535            PEX3  -J36        A01X+164724Y+122480X0180Y         S1      
317m5536            VIA   -    MD0100PA01X+131601Y+140850X0180Y         S0      
317m5536            J13   -R4   D0122PA01X+133106Y+149366X0282Y    R180 S3      
327m5536            C527  -2          A01X+131591Y+140359X0120Y0150R090 S1      
317m5537            VIA   -    MD0100PA01X+066641Y+136010X0180Y         S0      
317m5537            J5    -H4   D0122PA01X+065555Y+158579X0282Y    R180 S3      
327m5537            C397  -2          A01X+066651Y+135519X0120Y0150R090 S1      
327m5538            C735  -1          A01X+157503Y+137729X0120Y0150R090 S1      
317m5538            VIA   -    MD0100PA01X+157493Y+137238X0180Y         S0      
317m5538            VIA   -    MD0080PA01X+165098Y+123602X0160Y    R270 S0      
327m5538            PEX3  -F37        A01X+165098Y+123602X0180Y         S1      
317m5539            VIA   -    MD0100PA01X+114039Y+140850X0180Y         S0      
317m5539            J7    -U4   D0122PA01X+115783Y+147831X0282Y    R180 S3      
327m5539            C591  -2          A01X+114029Y+140359X0120Y0150R090 S1      
327m5540            C742  -1          A01X+153471Y+140149X0120Y0150R090 S1      
317m5540            VIA   -    MD0100PA01X+153481Y+139658X0180Y         S0      
317m5540            VIA   -    MD0080PA01X+163602Y+123228X0160Y    R270 S0      
327m5540            PEX3  -G33        A01X+163602Y+123228X0180Y         S1      
327m5541            C749  -1          A01X+157503Y+140149X0120Y0150R090 S1      
317m5541            VIA   -    MD0100PA01X+157493Y+139658X0180Y         S0      
317m5541            VIA   -    MD0080PA01X+162480Y+122854X0160Y    R270 S0      
327m5541            PEX3  -H30        A01X+162480Y+122854X0180Y         S1      
317m5542            VIA   -    MD0100PA01X+129493Y+140850X0180Y         S0      
317m5542            J13   -R1   D0122PA01X+130508Y+149445X0282Y    R180 S3      
327m5542            C534  -2          A01X+129503Y+140359X0120Y0150R090 S1      
317m5543            VIA   -    MD0100PA01X+032730Y+137238X0180Y         S0      
317m5543            VIA   -    MD0080PA01X+020866Y+122480X0160Y         S0      
327m5543            PEX0  -J18        A01X+020866Y+122480X0180Y         S1      
327m5543            C149  -1          A01X+032720Y+137729X0120Y0150R090 S1      
327m5544            C739  -1          A01X+156279Y+135309X0120Y0150R090 S1      
317m5544            VIA   -    MD0100PA01X+156269Y+134819X0180Y         S0      
317m5544            VIA   -    MD0080PA01X+164350Y+123602X0160Y    R270 S0      
327m5544            PEX3  -F35        A01X+164350Y+123602X0180Y         S1      
317m5545            VIA   -    MD0100PA01X+036402Y+139658X0180Y         S0      
317m5545            VIA   -    MD0080PA01X+022736Y+123228X0160Y    R270 S0      
327m5545            C159  -1          A01X+036392Y+140149X0120Y0150R090 S1      
327m5545            PEX0  -G23        A01X+022736Y+123228X0180Y         S1      
317m5546            VIA   -    MD0080PA01X+156870Y+109390X0160Y    R270 S0      
327m5546            PEX3  -BD15       A01X+156870Y+109390X0180Y         S1      
317m5546            VIA   -    MD0100PA01X+156003Y+011834X0200Y    R090 S0      
327m5546            C711  -1          A01X+155512Y+011824X0120Y0150R180 S1      
317m5547            VIA   -    MD0080PA01X+160236Y+110512X0160Y    R270 S0      
327m5547            PEX3  -BA24       A01X+160236Y+110512X0180Y         S1      
317m5547            VIA   -    MD0100PA01X+175435Y+011462X0200Y    R090 S0      
327m5547            C728  -1          A01X+174944Y+011472X0120Y0150R180 S1      
317m5548            VIA   -    MD0100PA01X+118051Y+138430X0180Y         S0      
317m5548            J7    -T8   D0122PA01X+119248Y+148343X0282Y    R180 S3      
327m5548            C584  -2          A01X+118061Y+137939X0120Y0150R090 S1      
317m5549            VIA   -    MD0080PA01X+158740Y+110138X0160Y    R270 S0      
327m5549            PEX3  -BB20       A01X+158740Y+110138X0180Y         S1      
317m5549            VIA   -    MD0100PA01X+165199Y+011122X0200Y    R090 S0      
327m5549            C721  -1          A01X+164708Y+011112X0120Y0150R180 S1      
317m5550            VIA   -    MD0100PA01X+025726Y+137238X0180Y         S0      
317m5550            VIA   -    MD0080PA01X+017500Y+123602X0160Y    R270 S0      
327m5550            PEX0  -F9         A01X+017500Y+123602X0180Y         S1      
327m5550            C132  -1          A01X+025736Y+137729X0120Y0150R090 S1      
327m5551            C744  -1          A01X+153471Y+135309X0120Y0150R090 S1      
317m5551            VIA   -    MD0100PA01X+153481Y+134819X0180Y         S0      
317m5551            VIA   -    MD0080PA01X+163228Y+122480X0160Y    R270 S0      
327m5551            PEX3  -J32        A01X+163228Y+122480X0180Y         S1      
317m5552            VIA   -    MD0100PA01X+134049Y+140850X0180Y         S0      
317m5552            J13   -S7   D0122PA01X+135705Y+148933X0282Y    R180 S3      
327m5552            C521  -2          A01X+134039Y+140359X0120Y0150R090 S1      
317m5553            VIA   -    MD0080PA01X+155374Y+109390X0160Y    R270 S0      
327m5553            PEX3  -BD11       A01X+155374Y+109390X0180Y         S1      
317m5553            VIA   -    MD0100PA01X+145767Y+011834X0200Y    R090 S0      
327m5553            C703  -1          A01X+145276Y+011824X0120Y0150R180 S1      
317m5554            VIA   -    MD0100PA01X+131601Y+136010X0180Y         S0      
317m5554            J13   -S3   D0122PA01X+132240Y+148933X0282Y    R180 S3      
327m5554            C529  -2          A01X+131591Y+135519X0120Y0150R090 S1      
317m5555            VIA   -    MD0100PA01X+028174Y+137238X0180Y         S0      
317m5555            VIA   -    MD0080PA01X+018622Y+122854X0160Y         S0      
327m5555            PEX0  -H12        A01X+018622Y+122854X0180Y         S1      
327m5555            C138  -1          A01X+028184Y+137729X0120Y0150R090 S1      
317m5556            VIA   -    MD0080PA01X+159114Y+109390X0160Y    R270 S0      
327m5556            PEX3  -BD21       A01X+159114Y+109390X0180Y         S1      
317m5556            VIA   -    MD0100PA01X+176475Y+013251X0200Y    R090 S0      
327m5556            C723  -1          A01X+175985Y+013241X0120Y0150R180 S1      
317m5557            VIA   -    MD0100PA01X+116827Y+136010X0180Y         S0      
317m5557            J7    -T6   D0122PA01X+117516Y+148343X0282Y    R180 S3      
327m5557            C588  -2          A01X+116837Y+135519X0120Y0150R090 S1      
317m5558            VIA   -    MD0100PA01X+026950Y+138430X0180Y         S0      
317m5558            J11   -E4   D0122PA01X+030909Y+160114X0282Y    R180 S3      
327m5558            C122  -2          A01X+026960Y+137939X0120Y0150R090 S1      
317m5559            VIA   -    MD0080PA01X+155000Y+110512X0160Y    R270 S0      
317m5559            VIA   -    MD0100PA01X+144726Y+012880X0200Y    R090 S0      
327m5559            C700  -1          A01X+144236Y+012890X0120Y0150R180 S1      
327m5559            PEX3  -BA10       A01X+155000Y+110512X0180Y         S1      
317m5560            VIA   -    MD0100PA01X+010059Y+138430X0180Y         S0      
317m5560            J3    -I4   D0122PA01X+013587Y+158067X0282Y    R180 S3      
327m5560            C185  -2          A01X+010049Y+137939X0120Y0150R090 S1      
317m5561            VIA   -    MD0100PA01X+065417Y+138430X0180Y         S0      
317m5561            J5    -I3   D0122PA01X+064689Y+158146X0282Y    R180 S3      
327m5561            C399  -2          A01X+065427Y+137939X0120Y0150R090 S1      
317m5562            VIA   -    MD0080PA01X+155000Y+110138X0160Y    R270 S0      
327m5562            PEX3  -BB10       A01X+155000Y+110138X0180Y         S1      
317m5562            VIA   -    MD0100PA01X+144726Y+012540X0200Y    R090 S0      
327m5562            C701  -1          A01X+144236Y+012530X0120Y0150R180 S1      
317m5563            J11   -W6   D0122PA01X+032642Y+146807X0282Y    R180 S3      
317m5563            VIA   -    MD0080PA01X+027972Y+125472X0160Y    R090 S0      
327m5563            PEX0  -A37        A01X+027972Y+125472X0180Y         S1      
317m5564            VIA   -    MD0100PA01X+129153Y+140850X0180Y         S0      
317m5564            J13   -S1   D0122PA01X+130508Y+148933X0282Y    R180 S3      
327m5564            C533  -2          A01X+129143Y+140359X0120Y0150R090 S1      
317m5565            VIA   -    MD0080PA01X+159862Y+109390X0160Y    R270 S0      
327m5565            PEX3  -BD23       A01X+159862Y+109390X0180Y         S1      
317m5565            VIA   -    MD0100PA01X+176475Y+011834X0200Y    R090 S0      
327m5565            C727  -1          A01X+175985Y+011824X0120Y0150R180 S1      
317m5566            J3    -O8   D0122PA01X+017051Y+150902X0282Y    R180 S3      
317m5566            VIA   -    MD0080PA01X+016752Y+125098X0160Y         S0      
327m5566            PEX0  -B7         A01X+016752Y+125098X0180Y         S1      
317m5567            VIA   -    MD0100PA01X+134049Y+136010X0180Y         S0      
317m5567            J13   -R6   D0122PA01X+134839Y+149366X0282Y    R180 S3      
327m5567            C523  -2          A01X+134039Y+135519X0120Y0150R090 S1      
317m5568            VIA   -    MD0080PA01X+157992Y+110138X0160Y    R270 S0      
327m5568            PEX3  -BB18       A01X+157992Y+110138X0180Y         S1      
317m5568            VIA   -    MD0100PA01X+165199Y+012540X0200Y    R090 S0      
327m5568            C717  -1          A01X+164708Y+012530X0120Y0150R180 S1      
317m5569            J3    -O7   D0122PA01X+016185Y+150980X0282Y    R180 S3      
317m5569            VIA   -    MD0080PA01X+016378Y+124724X0160Y         S0      
327m5569            PEX0  -C6         A01X+016378Y+124724X0180Y         S1      
317m5570            VIA   -    MD0080PA01X+022362Y+122480X0160Y         S0      
317m5570            VIA   -    MD0100PA01X+036402Y+134819X0180Y         S0      
327m5570            PEX0  -J22        A01X+022362Y+122480X0180Y         S1      
327m5570            C157  -1          A01X+036392Y+135309X0120Y0150R090 S1      
327m5571            C731  -1          A01X+158727Y+140149X0120Y0150R090 S1      
317m5571            VIA   -    MD0100PA01X+158717Y+139658X0180Y         S0      
317m5571            VIA   -    MD0080PA01X+165846Y+123602X0160Y    R270 S0      
327m5571            PEX3  -F39        A01X+165846Y+123602X0180Y         S1      
317m5572            J3    -O6   D0122PA01X+015319Y+150902X0282Y    R180 S3      
317m5572            VIA   -    MD0080PA01X+016004Y+125098X0160Y         S0      
327m5572            PEX0  -B5         A01X+016004Y+125098X0180Y         S1      
317m5573            VIA   -    MD0100PA01X+033954Y+139658X0180Y         S0      
317m5573            VIA   -    MD0080PA01X+021614Y+122480X0160Y         S0      
327m5573            PEX0  -J20        A01X+021614Y+122480X0180Y         S1      
327m5573            C153  -1          A01X+033944Y+140149X0120Y0150R090 S1      
317m5574            VIA   -    MD0100PA01X+026610Y+138430X0180Y         S0      
317m5574            J11   -F4   D0122PA01X+030909Y+159602X0282Y    R180 S3      
327m5574            C121  -2          A01X+026600Y+137939X0120Y0150R090 S1      
317m5575            VIA   -    MD0100PA01X+050500Y+140850X0180Y         S0      
317m5575            J12   -F1   D0122PA01X+045634Y+159681X0282Y    R180 S3      
327m5575            C2274 -2          A01X+050510Y+140359X0120Y0150R090 S1      
317m5576            VIA   -    MD0080PA01X+158740Y+110512X0160Y    R270 S0      
317m5576            VIA   -    MD0100PA01X+165199Y+011462X0200Y    R090 S0      
327m5576            C720  -1          A01X+164708Y+011472X0120Y0150R180 S1      
327m5576            PEX3  -BA20       A01X+158740Y+110512X0180Y         S1      
317m5577            J11   -X8   D0122PA01X+034374Y+146295X0282Y    R180 S3      
317m5577            VIA   -    MD0080PA01X+028720Y+125098X0160Y    R090 S0      
327m5577            PEX0  -B39        A01X+028720Y+125098X0180Y         S1      
317m5578            VIA   -    MD0100PA01X+034294Y+134819X0180Y         S0      
317m5578            VIA   -    MD0080PA01X+021240Y+123602X0160Y    R270 S0      
327m5578            C152  -1          A01X+034304Y+135309X0120Y0150R090 S1      
327m5578            PEX0  -F19        A01X+021240Y+123602X0180Y         S1      
317m5579            VIA   -    MD0080PA01X+157618Y+109390X0160Y    R270 S0      
327m5579            PEX3  -BD17       A01X+157618Y+109390X0180Y         S1      
317m5579            VIA   -    MD0100PA01X+166239Y+013251X0200Y    R090 S0      
327m5579            C715  -1          A01X+165748Y+013241X0120Y0150R180 S1      
317m5580            J3    -P7   D0122PA01X+016185Y+150468X0282Y    R180 S3      
317m5580            VIA   -    MD0080PA01X+016378Y+124350X0160Y         S0      
327m5580            PEX0  -D6         A01X+016378Y+124350X0180Y         S1      
317m5581            VIA   -    MD0100PA01X+029398Y+134819X0180Y         S0      
317m5581            VIA   -    MD0080PA01X+018996Y+123602X0160Y    R270 S0      
327m5581            PEX0  -F13        A01X+018996Y+123602X0180Y         S1      
327m5581            C140  -1          A01X+029408Y+135309X0120Y0150R090 S1      
327m5582            C732  -1          A01X+158367Y+135309X0120Y0150R090 S1      
317m5582            VIA   -    MD0100PA01X+158377Y+134819X0180Y         S0      
317m5582            VIA   -    MD0080PA01X+165472Y+122480X0160Y    R270 S0      
327m5582            PEX3  -J38        A01X+165472Y+122480X0180Y         S1      
317m5583            J3    -O5   D0122PA01X+014453Y+150980X0282Y    R180 S3      
317m5583            VIA   -    MD0080PA01X+015630Y+124724X0160Y         S0      
327m5583            PEX0  -C4         A01X+015630Y+124724X0180Y         S1      
317m5584            VIA   -    MD0100PA01X+134389Y+140850X0180Y         S0      
317m5584            J13   -R7   D0122PA01X+135705Y+149445X0282Y    R180 S3      
327m5584            C522  -2          A01X+134399Y+140359X0120Y0150R090 S1      
327m5585            C738  -1          A01X+155919Y+135309X0120Y0150R090 S1      
317m5585            VIA   -    MD0100PA01X+155929Y+134819X0180Y         S0      
317m5585            VIA   -    MD0080PA01X+164350Y+123228X0160Y    R270 S0      
327m5585            PEX3  -G35        A01X+164350Y+123228X0180Y         S1      
317m5586            J11   -X7   D0122PA01X+033508Y+146374X0282Y    R180 S3      
317m5586            VIA   -    MD0080PA01X+028346Y+124724X0160Y         S0      
327m5586            PEX0  -C38        A01X+028346Y+124724X0180Y         S1      
317m5587            VIA   -    MD0100PA01X+116487Y+140850X0180Y         S0      
317m5587            J7    -V7   D0122PA01X+118382Y+147398X0282Y    R180 S3      
327m5587            C585  -2          A01X+116477Y+140359X0120Y0150R090 S1      
327GND              C3358 -2          A18X+108812Y+117431X0120Y0150     S2      
327GND              C3355 -2          A18X+108812Y+117805X0120Y0150     S2      
327GND              C3356 -2          A18X+108812Y+118179X0120Y0150     S2      
327GND              C3182 -2          A18X+063104Y+117618X0120Y0150     S2      
327GND              C3183 -2          A18X+063104Y+117992X0120Y0150     S2      
327GND              C3181 -2          A18X+063104Y+117250X0120Y0150     S2      
327GND              C2008 -2          A18X+090184Y+084372X0164Y0164R090 S2      
327GND              C2026 -2          A18X+090814Y+084372X0164Y0164R090 S2      
327GND              C2007 -2          A18X+090499Y+084372X0164Y0164R090 S2      
317GND              VIA   -    MD0100PA00X+135690Y+137488X0180Y         S0      
317GND              VIA   -    MD0100PA00X+094060Y+037060X0200Y    R090 S0      
327GND              C2623 -2          A01X+094244Y+036463X0198Y0197R270 S1      
327GND              PEX1  -J39        A01X+074429Y+122480X0180Y         S1      
317GND              VIA   -    MD0080PA00X+074429Y+122480X0160Y         S0      
317GND              VIA   -    MD0080PA00X+030846Y+138430X0160Y         S0      
327GND              Y6    -2          A01X+098306Y+032027X0480Y0590R180 S1      
327GND              C2637 -2          A01X+099040Y+032132X0198Y0197R090 S1      
327GND              C2636 -2          A01X+099040Y+031094X0198Y0197R270 S1      
327GND              Y6    -4          A01X+097676Y+031193X0480Y0590R180 S1      
327GND              PC276 -2          A01X+181338Y+113441X0198Y0197     S1      
327GND              PC279 -2          A01X+182108Y+111959X0630Y1190R090 S1      
327GND              PC278 -2          A01X+177196Y+112612X0630Y1190R270 S1      
327GND              C4406 -2          A01X+181890Y+104676X0120Y0150     S1      
327GND              C4393 -2          A01X+181896Y+105122X0120Y0150     S1      
327GND              C4392 -2          A01X+181907Y+105678X0120Y0150     S1      
327GND              C4407 -2          A01X+181888Y+104155X0120Y0150     S1      
327GND              C4413 -2          A01X+182481Y+099790X0400Y0500R090 S1      
327GND              C4399 -2          A01X+181113Y+099786X0400Y0500R090 S1      
327GND              C4412 -2          A01X+181796Y+099786X0400Y0500R090 S1      
327GND              C4398 -2          A01X+180401Y+099786X0400Y0500R090 S1      
327GND              C4397 -2          A01X+179772Y+099945X0280Y0320R180 S1      
327GND              C4396 -2          A01X+179228Y+099945X0280Y0320R180 S1      
327GND              C4411 -2          A01X+178139Y+099945X0280Y0320R180 S1      
327GND              C4410 -2          A01X+177595Y+099945X0280Y0320R180 S1      
327GND              C4395 -2          A01X+178678Y+099945X0280Y0320R180 S1      
327GND              C4409 -2          A01X+176500Y+099945X0280Y0320R180 S1      
327GND              C4408 -2          A01X+175927Y+099945X0280Y0320R180 S1      
327GND              C4394 -2          A01X+177049Y+099945X0280Y0320R180 S1      
327GND              C4433 -2          A01X+179264Y+098506X0198Y0197     S1      
327GND              J67   -1          A01X+156376Y+099040X0500Y1350R090 S1      
327GND              U433  -TH         A01X+179586Y+097556X0690Y1050R180 S1      
327GND              C4431 -2          A01X+179646Y+096456X0400Y0500     S1      
327GND              C4429 -2          A01X+178946Y+096318X0198Y0197R270 S1      
327GND              C4430 -2          A01X+178226Y+096866X0400Y0500R090 S1      
327GND              J54   -5          A01X+179644Y+082902X0170Y0590R090 S1      
327GND              C2025 -2          A18X+089869Y+087206X0164Y0164R090 S2      
327GND              C3622 -2          A18X+090814Y+087206X0164Y0164R090 S2      
327GND              C2014 -2          A18X+090499Y+087206X0164Y0164R090 S2      
327GND              C3611 -2          A18X+091129Y+086891X0164Y0164     S2      
327GND              C2017 -2          A18X+090184Y+087206X0164Y0164R090 S2      
327GND              C3610 -2          A18X+091129Y+086576X0164Y0164     S2      
327GND              C3624 -2          A18X+089554Y+086891X0164Y0164R180 S2      
327GND              C2006 -2          A18X+092074Y+086262X0164Y0164R270 S2      
327GND              C3623 -2          A18X+090184Y+085632X0164Y0164R270 S2      
327GND              C2019 -2          A18X+091129Y+085946X0164Y0164     S2      
327GND              C3608 -2          A18X+091129Y+085317X0164Y0164     S2      
327GND              C2018 -2          A18X+089554Y+086262X0164Y0164R180 S2      
327GND              C2009 -2          A18X+089554Y+085632X0164Y0164R180 S2      
327GND              C2013 -2          A18X+089554Y+085946X0164Y0164R180 S2      
327GND              C2023 -2          A18X+093427Y+085632X0164Y0164R270 S2      
327GND              C2022 -2          A18X+093077Y+085632X0164Y0164R270 S2      
327GND              C2021 -2          A18X+092389Y+085632X0164Y0164R270 S2      
327GND              C2024 -2          A18X+092744Y+085632X0164Y0164R270 S2      
327GND              C3163 -2          A18X+064246Y+118909X0280Y0320R090 S2      
327GND              C3173 -2          A18X+063850Y+118534X0120Y0150     S2      
327GND              C3243 -2          A18X+063985Y+117490X0120Y0150     S2      
327GND              C3199 -2          A18X+063854Y+118180X0120Y0150     S2      
327GND              C3200 -2          A18X+063854Y+117800X0120Y0150     S2      
327GND              C3202 -2          A18X+063850Y+117057X0120Y0150     S2      
327GND              C3203 -2          A18X+063850Y+116683X0120Y0150     S2      
327GND              C3218 -2          A18X+063850Y+115935X0120Y0150     S2      
327GND              C3217 -2          A18X+063850Y+116250X0120Y0150     S2      
327GND              C3231 -2          A18X+063850Y+115561X0120Y0150     S2      
327GND              C3230 -2          A18X+063850Y+115187X0120Y0150     S2      
327GND              C3234 -2          A18X+064004Y+114813X0120Y0150     S2      
327GND              C3299 -2          A18X+118081Y+112651X0120Y0150R090 S2      
327GND              C3313 -2          A18X+117707Y+112651X0120Y0150R090 S2      
327GND              C3324 -2          A18X+117333Y+112651X0120Y0150R090 S2      
327GND              C3328 -2          A18X+116959Y+112651X0120Y0150R090 S2      
327GND              C3312 -2          A18X+116585Y+112651X0120Y0150R090 S2      
327GND              C3327 -2          A18X+116211Y+112651X0120Y0150R090 S2      
327GND              C3306 -2          A18X+115836Y+112651X0120Y0150R090 S2      
327GND              C3304 -2          A18X+115462Y+112651X0120Y0150R090 S2      
327GND              C3303 -2          A18X+115088Y+112651X0120Y0150R090 S2      
327GND              C3307 -2          A18X+114340Y+112651X0120Y0150R090 S2      
327GND              C3300 -2          A18X+113966Y+112651X0120Y0150R090 S2      
327GND              C3309 -2          A18X+113592Y+112651X0120Y0150R090 S2      
327GND              C3308 -2          A18X+113218Y+112651X0120Y0150R090 S2      
327GND              C3332 -2          A18X+112844Y+112651X0120Y0150R090 S2      
327GND              C3334 -2          A18X+112470Y+112651X0120Y0150R090 S2      
327GND              C3331 -2          A18X+112096Y+112651X0120Y0150R090 S2      
327GND              C3320 -2          A18X+111722Y+112651X0120Y0150R090 S2      
327GND              C3294 -2          A18X+111348Y+112651X0120Y0150R090 S2      
327GND              C3292 -2          A18X+114712Y+112381X0280Y0320R180 S2      
327GND              C3158 -2          A18X+071998Y+112651X0120Y0150R090 S2      
327GND              C3126 -2          A18X+072372Y+112651X0120Y0150R090 S2      
327GND              C3148 -2          A18X+071624Y+112651X0120Y0150R090 S2      
327GND              C3159 -2          A18X+070876Y+112651X0120Y0150R090 S2      
327GND              C3142 -2          A18X+071250Y+112651X0120Y0150R090 S2      
327GND              C3138 -2          A18X+070502Y+112651X0120Y0150R090 S2      
327GND              C3130 -2          A18X+069393Y+112651X0120Y0150R090 S2      
327GND              C3131 -2          A18X+069754Y+112651X0120Y0150R090 S2      
327GND              C3135 -2          A18X+068613Y+112651X0120Y0150R090 S2      
327GND              C3132 -2          A18X+070128Y+112651X0120Y0150R090 S2      
327GND              C3153 -2          A18X+067136Y+112651X0120Y0150R090 S2      
327GND              C3125 -2          A18X+068258Y+112651X0120Y0150R090 S2      
327GND              C3133 -2          A18X+067510Y+112651X0120Y0150R090 S2      
327GND              C3134 -2          A18X+067884Y+112651X0120Y0150R090 S2      
327GND              C3120 -2          A18X+065640Y+112651X0120Y0150R090 S2      
327GND              C3144 -2          A18X+066014Y+112651X0120Y0150R090 S2      
327GND              C3146 -2          A18X+066388Y+112651X0120Y0150R090 S2      
327GND              C3150 -2          A18X+066762Y+112651X0120Y0150R090 S2      
327GND              C3118 -2          A18X+069003Y+112381X0280Y0320R180 S2      
327GND              C1439 -2          A18X+072185Y+114895X0120Y0150R090 S2      
327GND              C1422 -2          A18X+071437Y+114895X0120Y0150R090 S2      
327GND              C1495 -2          A18X+070689Y+114895X0120Y0150R090 S2      
327GND              C1493 -2          A18X+071063Y+114895X0120Y0150R090 S2      
327GND              C1441 -2          A18X+071811Y+114895X0120Y0150R090 S2      
327GND              C1461 -2          A18X+070315Y+114895X0120Y0150R090 S2      
327GND              C1478 -2          A18X+069567Y+114895X0120Y0150R090 S2      
327GND              C1487 -2          A18X+069193Y+114895X0120Y0150R090 S2      
327GND              C1416 -2          A18X+068819Y+114895X0120Y0150R090 S2      
327GND              C1464 -2          A18X+069941Y+114895X0120Y0150R090 S2      
327GND              C1471 -2          A18X+067697Y+114895X0120Y0150R090 S2      
327GND              C1479 -2          A18X+068071Y+114895X0120Y0150R090 S2      
327GND              C1488 -2          A18X+068445Y+114895X0120Y0150R090 S2      
327GND              C1456 -2          A18X+067323Y+114895X0120Y0150R090 S2      
327GND              C1490 -2          A18X+066949Y+114895X0120Y0150R090 S2      
327GND              C1434 -2          A18X+066201Y+114895X0120Y0150R090 S2      
327GND              C1435 -2          A18X+066575Y+114895X0120Y0150R090 S2      
327GND              C1442 -2          A18X+065827Y+114895X0120Y0150R090 S2      
327GND              PEX3  -Y9         A01X+154626Y+118366X0180Y         S1      
327GND              PEX3  -Y10 M      A01X+155000Y+118366X0180Y         S1      
317GND              VIA   -    MD0080PA00X+154813Y+118553X0160Y         S0      
327GND              PEX2  -Y9  M      A01X+108917Y+118366X0180Y         S1      
327GND              PEX2  -Y10 M      A01X+109291Y+118366X0180Y         S1      
317GND              VIA   -    MD0080PA00X+109104Y+118553X0160Y         S0      
327GND              PEX2  -AM4        A01X+107047Y+113878X0180Y         S1      
327GND              PEX2  -AM5        A01X+107421Y+113878X0180Y         S1      
327GND              PEX2  -AM6        A01X+107795Y+113878X0180Y         S1      
327GND              PEX2  -AM7        A01X+108169Y+113878X0180Y         S1      
327GND              C3180 -2          A18X+063852Y+114439X0120Y0150     S2      
327GND              C1392 -2          A18X+065184Y+117825X0120Y0150R180 S2      
327GND              C1371 -2          A18X+064974Y+118179X0120Y0150     S2      
327GND              C1365 -2          A18X+065164Y+118510X0120Y0150R180 S2      
327GND              C1447 -2          A18X+071998Y+117349X0120Y0150R270 S2      
327GND              C1448 -2          A18X+072080Y+116683X0120Y0150     S2      
327GND              C1373 -2          A18X+069590Y+116683X0120Y0150R180 S2      
327GND              C1374 -2          A18X+069918Y+116683X0120Y0150     S2      
327GND              C1393 -2          A18X+070592Y+116683X0120Y0150     S2      
327GND              C3215 -2          A18X+064518Y+116935X0120Y0150R270 S2      
327GND              C3242 -2          A18X+064518Y+117221X0120Y0150R090 S2      
327GND              C3214 -2          A18X+064518Y+116215X0120Y0150R090 S2      
327GND              C3233 -2          A18X+064518Y+114521X0120Y0150R090 S2      
327GND              C3185 -2          A18X+065184Y+113691X0120Y0150R180 S2      
327GND              C1367 -2          A18X+064892Y+117349X0120Y0150R270 S2      
327GND              C1391 -2          A18X+064982Y+116683X0120Y0150     S2      
327GND              C1400 -2          A18X+065266Y+117139X0120Y0150R090 S2      
327GND              C1359 -2          A18X+065184Y+114439X0120Y0150R180 S2      
327GND              C1360 -2          A18X+064974Y+114813X0120Y0150     S2      
327GND              C1361 -2          A18X+065184Y+115187X0120Y0150R180 S2      
327GND              C1368 -2          A18X+064892Y+115643X0120Y0150R090 S2      
327GND              C1381 -2          A18X+065266Y+115853X0120Y0150R270 S2      
327GND              C1382 -2          A18X+065640Y+115643X0120Y0150R090 S2      
327GND              C1370 -2          A18X+065730Y+116683X0120Y0150     S2      
327GND              C1388 -2          A18X+065640Y+117349X0120Y0150R270 S2      
327GND              C1401 -2          A18X+066014Y+117139X0120Y0150R090 S2      
327GND              C1395 -2          A18X+066388Y+117349X0120Y0150R270 S2      
327GND              C1364 -2          A18X+066478Y+116683X0120Y0150     S2      
327GND              C1379 -2          A18X+066762Y+117139X0120Y0150R090 S2      
327GND              C1387 -2          A18X+066014Y+115853X0120Y0150R270 S2      
327GND              C1378 -2          A18X+066388Y+115643X0120Y0150R090 S2      
327GND              C1390 -2          A18X+066762Y+115853X0120Y0150R270 S2      
327GND              C1356 -2          A18X+066533Y+116229X0280Y0320R090 S2      
327GND              C1389 -2          A18X+067136Y+115643X0120Y0150R090 S2      
327GND              C1366 -2          A18X+067226Y+116683X0120Y0150     S2      
327GND              C1394 -2          A18X+067136Y+117349X0120Y0150R270 S2      
327GND              C1403 -2          A18X+067510Y+117139X0120Y0150R090 S2      
327GND              C1404 -2          A18X+067884Y+117349X0120Y0150R270 S2      
327GND              C1363 -2          A18X+067974Y+116683X0120Y0150     S2      
327GND              C1355 -2          A18X+068029Y+116229X0280Y0320R090 S2      
327GND              C1377 -2          A18X+067510Y+115853X0120Y0150R270 S2      
327GND              C1376 -2          A18X+067884Y+115643X0120Y0150R090 S2      
327GND              C1402 -2          A18X+068258Y+115853X0120Y0150R270 S2      
327GND              C1380 -2          A18X+068632Y+115643X0120Y0150R090 S2      
327GND              C1407 -2          A18X+068258Y+117139X0120Y0150R090 S2      
327GND              C1383 -2          A18X+068632Y+117349X0120Y0150R270 S2      
327GND              C1362 -2          A18X+068722Y+116683X0120Y0150     S2      
327GND              C1406 -2          A18X+069380Y+115853X0120Y0150R270 S2      
327GND              C1396 -2          A18X+069754Y+115643X0120Y0150R090 S2      
327GND              C1397 -2          A18X+070128Y+115853X0120Y0150R270 S2      
327GND              C1357 -2          A18X+069899Y+116229X0280Y0320R090 S2      
327GND              C1385 -2          A18X+070502Y+115643X0120Y0150R090 S2      
327GND              C1408 -2          A18X+070876Y+115853X0120Y0150R270 S2      
327GND              C1409 -2          A18X+071250Y+115643X0120Y0150R090 S2      
327GND              C1386 -2          A18X+071624Y+115853X0120Y0150R270 S2      
327GND              C1420 -2          A18X+071998Y+115643X0120Y0150R090 S2      
327GND              C1405 -2          A18X+069380Y+117139X0120Y0150R090 S2      
327GND              C1411 -2          A18X+069754Y+117349X0120Y0150R270 S2      
327GND              C1410 -2          A18X+070128Y+117139X0120Y0150R090 S2      
327GND              C1398 -2          A18X+070502Y+117349X0120Y0150R270 S2      
327GND              C1384 -2          A18X+070876Y+117139X0120Y0150R090 S2      
327GND              C1399 -2          A18X+071250Y+117349X0120Y0150R270 S2      
327GND              C1375 -2          A18X+071340Y+116683X0120Y0150     S2      
327GND              C1369 -2          A18X+071624Y+117139X0120Y0150R090 S2      
327GND              C3176 -2          A18X+073412Y+113691X0120Y0150R180 S2      
327GND              C3177 -2          A18X+073412Y+114065X0120Y0150R180 S2      
327GND              C3167 -2          A18X+073412Y+114439X0120Y0150R180 S2      
327GND              C1358 -2          A18X+072664Y+115561X0120Y0150R180 S2      
327GND              C1418 -2          A18X+073045Y+116280X0120Y0150R180 S2      
327GND              C1417 -2   M      A18X+073038Y+115935X0120Y0150R180 S2      
327GND              C1419 -2          A18X+073038Y+116683X0120Y0150R180 S2      
327GND              C1421 -2          A18X+073038Y+117057X0120Y0150R180 S2      
327GND              C1372 -2          A18X+072664Y+117431X0120Y0150R180 S2      
327GND              C3188 -2          A18X+073038Y+118179X0120Y0150R180 S2      
327GND              C3168 -2          A18X+072828Y+118553X0120Y0150     S2      
327GND              C3166 -2          A18X+072828Y+118927X0120Y0150     S2      
327GND              C3165 -2          A18X+072828Y+119301X0120Y0150     S2      
327GND              C3186 -2          A18X+073120Y+119675X0120Y0150R090 S2      
327GND              C3338 -2          A18X+108042Y+112541X0280Y0320R090 S2      
327GND              C3357 -2          A18X+110892Y+113691X0120Y0150R180 S2      
327GND              C3336 -2          A18X+109954Y+118909X0280Y0320R090 S2      
327GND              C3347 -2          A18X+109562Y+118520X0120Y0150     S2      
327GND              C3373 -2          A18X+109562Y+118180X0120Y0150     S2      
327GND              C3374 -2          A18X+109562Y+117800X0120Y0150     S2      
327GND              C3416 -2          A18X+109712Y+117431X0120Y0150     S2      
327GND              C3377 -2          A18X+109562Y+117057X0120Y0150     S2      
327GND              C3376 -2          A18X+109562Y+116683X0120Y0150     S2      
327GND              C3391 -2          A18X+109562Y+116245X0120Y0150     S2      
327GND              C3392 -2          A18X+109562Y+115935X0120Y0150     S2      
327GND              C3405 -2          A18X+109562Y+115561X0120Y0150     S2      
327GND              C3404 -2          A18X+109562Y+115187X0120Y0150     S2      
327GND              PEX2  -AG12       A01X+110039Y+115748X0180Y         S1      
327GND              C3388 -2          A18X+110226Y+116185X0120Y0150R090 S2      
327GND              C3389 -2          A18X+110226Y+116893X0120Y0150R270 S2      
327GND              C3417 -2          A18X+110226Y+117221X0120Y0150R090 S2      
327GND              C1639 -2          A18X+110872Y+118510X0120Y0150R180 S2      
327GND              C1619 -2          A18X+110682Y+118179X0120Y0150     S2      
327GND              C1634 -2          A18X+110892Y+117825X0120Y0150R180 S2      
327GND              C1626 -2          A18X+110700Y+116683X0120Y0150     S2      
327GND              C1633 -2          A18X+110600Y+117349X0120Y0150R270 S2      
327GND              C3407 -2   M      A18X+109712Y+114813X0120Y0150     S2      
327GND              PEX2  -AJ12       A01X+110039Y+115000X0180Y         S1      
327GND              C1614 -2          A18X+110892Y+114439X0120Y0150R180 S2      
327GND              C1616 -2          A18X+110682Y+114813X0120Y0150     S2      
327GND              C1615 -2          A18X+110892Y+115187X0120Y0150R180 S2      
327GND              C1638 -2          A18X+110600Y+115643X0120Y0150R090 S2      
327GND              C1622 -2          A18X+110974Y+115853X0120Y0150R270 S2      
327GND              C1642 -2          A18X+110974Y+117139X0120Y0150R090 S2      
327GND              C1662 -2          A18X+111348Y+117349X0120Y0150R270 S2      
327GND              C1628 -2          A18X+111448Y+116683X0120Y0150     S2      
327GND              C1660 -2          A18X+111722Y+117139X0120Y0150R090 S2      
327GND              C1647 -2          A18X+112096Y+117349X0120Y0150R270 S2      
327GND              C1618 -2          A18X+112196Y+116683X0120Y0150     S2      
327GND              C1620 -2          A18X+112470Y+117139X0120Y0150R090 S2      
327GND              C1663 -2          A18X+112844Y+117349X0120Y0150R270 S2      
327GND              C1636 -2          A18X+112944Y+116683X0120Y0150     S2      
327GND              C1664 -2          A18X+113218Y+117139X0120Y0150R090 S2      
327GND              C1624 -2          A18X+113592Y+117349X0120Y0150R270 S2      
327GND              C1627 -2          A18X+113692Y+116683X0120Y0150     S2      
327GND              C1661 -2          A18X+113966Y+117139X0120Y0150R090 S2      
327GND              C1631 -2          A18X+114430Y+116683X0120Y0150     S2      
327GND              C1643 -2          A18X+114346Y+117349X0120Y0150R270 S2      
327GND              C1651 -2          A18X+115088Y+117139X0120Y0150R090 S2      
327GND              C1649 -2          A18X+115462Y+117349X0120Y0150R270 S2      
327GND              C1645 -2          A18X+115836Y+117139X0120Y0150R090 S2      
327GND              C1648 -2          A18X+116211Y+117349X0120Y0150R270 S2      
327GND              C1656 -2          A18X+116585Y+117139X0120Y0150R090 S2      
327GND              C1652 -2          A18X+116959Y+117349X0120Y0150R270 S2      
327GND              C1629 -2          A18X+117333Y+117139X0120Y0150R090 S2      
327GND              C1695 -2          A18X+117707Y+117349X0120Y0150R270 S2      
327GND              C1644 -2          A18X+111348Y+115643X0120Y0150R090 S2      
327GND              C1666 -2          A18X+111722Y+115853X0120Y0150R270 S2      
327GND              C1625 -2          A18X+112096Y+115643X0120Y0150R090 S2      
327GND              C1611 -2          A18X+112242Y+116229X0280Y0320R090 S2      
327GND              C1665 -2          A18X+112470Y+115853X0120Y0150R270 S2      
327GND              C1657 -2          A18X+112844Y+115643X0120Y0150R090 S2      
327GND              C1646 -2          A18X+113218Y+115853X0120Y0150R270 S2      
327GND              C1621 -2          A18X+113592Y+115643X0120Y0150R090 S2      
327GND              C1653 -2          A18X+113966Y+115853X0120Y0150R270 S2      
327GND              C1610 -2          A18X+113738Y+116229X0280Y0320R090 S2      
327GND              C1654 -2          A18X+114340Y+115643X0120Y0150R090 S2      
327GND              C1637 -2          A18X+115322Y+116690X0120Y0150R180 S2      
327GND              C1635 -2          A18X+115612Y+116690X0120Y0150     S2      
327GND              C1617 -2          A18X+116301Y+116683X0120Y0150     S2      
327GND              C1632 -2          A18X+117049Y+116683X0120Y0150     S2      
327GND              C1650 -2          A18X+115088Y+115853X0120Y0150R270 S2      
327GND              C1658 -2          A18X+115836Y+115853X0120Y0150R270 S2      
327GND              C1623 -2          A18X+115462Y+115643X0120Y0150R090 S2      
327GND              C1641 -2          A18X+116210Y+115643X0120Y0150R090 S2      
327GND              C1655 -2          A18X+116585Y+115853X0120Y0150R270 S2      
327GND              C1640 -2          A18X+116959Y+115643X0120Y0150R090 S2      
327GND              C1659 -2          A18X+117333Y+115853X0120Y0150R270 S2      
327GND              C1673 -2          A18X+117707Y+115643X0120Y0150R090 S2      
327GND              C1612 -2          A18X+115608Y+116229X0280Y0320R090 S2      
327GND              C3341 -2          A18X+119121Y+114439X0120Y0150R180 S2      
327GND              C3350 -2          A18X+119121Y+114065X0120Y0150R180 S2      
327GND              C3351 -2          A18X+119121Y+113691X0120Y0150R180 S2      
327GND              C1672 -2          A18X+118747Y+115935X0120Y0150R180 S2      
327GND              C1613 -2          A18X+118373Y+115561X0120Y0150R180 S2      
327GND              C1675 -2          A18X+117789Y+116683X0120Y0150     S2      
327GND              C1676 -2          A18X+118747Y+116683X0120Y0150R180 S2      
327GND              C1674 -2          A18X+118747Y+117057X0120Y0150R180 S2      
327GND              C1630 -2          A18X+118373Y+117431X0120Y0150R180 S2      
327GND              C3362 -2          A18X+118747Y+118179X0120Y0150R180 S2      
327GND              C3339 -2          A18X+118537Y+118553X0120Y0150     S2      
327GND              C3340 -2          A18X+118537Y+118927X0120Y0150     S2      
327GND              C3342 -2          A18X+118537Y+119301X0120Y0150     S2      
327GND              C1905 -2          A18X+157057Y+117349X0120Y0150R270 S2      
327GND              C1936 -2          A18X+163497Y+116683X0120Y0150     S2      
327GND              C1880 -2          A18X+157431Y+115853X0120Y0150R270 S2      
327GND              C1916 -2          A18X+158179Y+115853X0120Y0150R270 S2      
327GND              C1866 -2          A18X+157950Y+116229X0280Y0320R090 S2      
327GND              C1917 -2          A18X+158553Y+115643X0120Y0150R090 S2      
327GND              C1918 -2          A18X+158927Y+115853X0120Y0150R270 S2      
327GND              C1883 -2          A18X+159301Y+115643X0120Y0150R090 S2      
327GND              C1906 -2          A18X+159675Y+115853X0120Y0150R270 S2      
327GND              C1867 -2          A18X+159446Y+116229X0280Y0320R090 S2      
327GND              C1908 -2          A18X+160049Y+115643X0120Y0150R090 S2      
327GND              C1920 -2          A18X+160797Y+115853X0120Y0150R270 S2      
327GND              C1921 -2          A18X+161171Y+115643X0120Y0150R090 S2      
327GND              C1865 -2          A18X+161316Y+116229X0280Y0320R090 S2      
327GND              C1886 -2          A18X+161545Y+115853X0120Y0150R270 S2      
327GND              C1910 -2          A18X+161919Y+115643X0120Y0150R090 S2      
327GND              C1911 -2          A18X+162293Y+115853X0120Y0150R270 S2      
327GND              C1899 -2          A18X+162667Y+115643X0120Y0150R090 S2      
327GND              C1900 -2          A18X+163041Y+115853X0120Y0150R270 S2      
327GND              C1930 -2          A18X+163416Y+115643X0120Y0150R090 S2      
327GND              C3532 -2          A18X+156601Y+113691X0120Y0150R180 S2      
327GND              C1903 -2          A18X+157805Y+115643X0120Y0150R090 S2      
327GND              C1915 -2          A18X+157057Y+115643X0120Y0150R090 S2      
327GND              C1879 -2          A18X+156683Y+115853X0120Y0150R270 S2      
327GND              C3562 -2          A18X+155935Y+116185X0120Y0150R090 S2      
327GND              C3590 -2          A18X+155935Y+117221X0120Y0150R090 S2      
327GND              C3563 -2          A18X+155935Y+116893X0120Y0150R270 S2      
327GND              C1871 -2          A18X+156601Y+114439X0120Y0150R180 S2      
327GND              C1870 -2          A18X+156391Y+114813X0120Y0150     S2      
327GND              C1869 -2          A18X+156601Y+115187X0120Y0150R180 S2      
327GND              C1891 -2          A18X+156309Y+115643X0120Y0150R090 S2      
327GND              C3523 -2          A18X+155269Y+114439X0120Y0150     S2      
327GND              C3526 -2          A18X+164829Y+113691X0120Y0150R180 S2      
327GND              C3528 -2          A18X+164829Y+114065X0120Y0150R180 S2      
327GND              C3514 -2          A18X+164829Y+114439X0120Y0150R180 S2      
327GND              C1868 -2          A18X+164081Y+115561X0120Y0150R180 S2      
327GND              C1927 -2          A18X+164455Y+115935X0120Y0150R180 S2      
327GND              C1928 -2          A18X+164455Y+116683X0120Y0150R180 S2      
327GND              C1929 -2          A18X+164455Y+117057X0120Y0150R180 S2      
327GND              C3530 -2          A18X+164455Y+118179X0120Y0150R180 S2      
327GND              C3515 -2          A18X+164245Y+118553X0120Y0150     S2      
327GND              PEX1  -AJ12       A01X+064331Y+115000X0180Y         S1      
327GND              C3516 -2          A18X+164245Y+118927X0120Y0150     S2      
327GND              PEX1  -AG12       A01X+064331Y+115748X0180Y         S1      
327GND              C3513 -2          A18X+164245Y+119301X0120Y0150     S2      
327GND              C1873 -2          A18X+156581Y+118510X0120Y0150R180 S2      
327GND              C1894 -2          A18X+156391Y+118179X0120Y0150     S2      
327GND              C1893 -2          A18X+156601Y+117825X0120Y0150R180 S2      
327GND              C1872 -2          A18X+156309Y+117349X0120Y0150R270 S2      
327GND              C1892 -2          A18X+156409Y+116683X0120Y0150     S2      
327GND              C1902 -2          A18X+156683Y+117139X0120Y0150R090 S2      
327GND              C1874 -2          A18X+157157Y+116683X0120Y0150     S2      
327GND              C1904 -2          A18X+157431Y+117139X0120Y0150R090 S2      
327GND              C1882 -2          A18X+157805Y+117349X0120Y0150R270 S2      
327GND              C1895 -2          A18X+157905Y+116683X0120Y0150     S2      
327GND              C1884 -2          A18X+159301Y+117349X0120Y0150R270 S2      
327GND              C1881 -2          A18X+158179Y+117139X0120Y0150R090 S2      
327GND              C1907 -2          A18X+158553Y+117349X0120Y0150R270 S2      
327GND              C1885 -2          A18X+158927Y+117139X0120Y0150R090 S2      
327GND              C1896 -2          A18X+158653Y+116683X0120Y0150     S2      
327GND              C1875 -2          A18X+159401Y+116683X0120Y0150     S2      
327GND              C1919 -2          A18X+159675Y+117139X0120Y0150R090 S2      
327GND              C1898 -2          A18X+160055Y+117349X0120Y0150R270 S2      
327GND              C1877 -2          A18X+160139Y+116683X0120Y0150     S2      
327GND              C1887 -2          A18X+160797Y+117139X0120Y0150R090 S2      
327GND              C1909 -2          A18X+161171Y+117349X0120Y0150R270 S2      
327GND              C1914 -2          A18X+161545Y+117139X0120Y0150R090 S2      
327GND              C1876 -2          A18X+161031Y+116690X0120Y0150R180 S2      
327GND              C1897 -2          A18X+161321Y+116690X0120Y0150     S2      
327GND              C1888 -2          A18X+162009Y+116683X0120Y0150     S2      
327GND              C1901 -2          A18X+161919Y+117349X0120Y0150R270 S2      
327GND              C1913 -2          A18X+162293Y+117139X0120Y0150R090 S2      
327GND              C1890 -2          A18X+164081Y+117431X0120Y0150R180 S2      
327GND              C1948 -2          A18X+163415Y+117349X0120Y0150R270 S2      
327GND              C1912 -2          A18X+162667Y+117349X0120Y0150R270 S2      
327GND              C1889 -2          A18X+163041Y+117139X0120Y0150R090 S2      
327GND              C1878 -2          A18X+162757Y+116683X0120Y0150     S2      
327GND              C3220 -2          A18X+064518Y+115235X0120Y0150R090 S2      
327GND              C3221 -2   M      A18X+064518Y+115935X0120Y0150R270 S2      
327GND              C3197 -2          A18X+064518Y+117805X0120Y0150R090 S2      
327GND              C3196 -2          A18X+064518Y+118553X0120Y0150R270 S2      
327GND              PEX3  -AG12       A01X+155748Y+115748X0180Y         S1      
327GND              C3349 -2          A18X+108812Y+115000X0120Y0150     S2      
327GND              C3354 -2          A18X+108812Y+115374X0120Y0150     S2      
327GND              C3335 -2          A18X+108812Y+115748X0120Y0150     S2      
327GND              C3348 -2          A18X+108812Y+116122X0120Y0150     S2      
327GND              C3352 -2          A18X+108812Y+116496X0120Y0150     S2      
327GND              C3353 -2          A18X+109560Y+114258X0120Y0150     S2      
327GND              C3408 -2          A18X+110226Y+114439X0120Y0150R090 S2      
327GND              C3394 -2          A18X+110226Y+115187X0120Y0150R090 S2      
327GND              C3395 -2          A18X+110226Y+115905X0120Y0150R270 S2      
327GND              C3371 -2          A18X+110227Y+117825X0120Y0150R090 S2      
327GND              C3370 -2          A18X+110227Y+118530X0120Y0150R270 S2      
327GND              C3343 -2          A18X+110226Y+119301X0120Y0150     S2      
327GND              C3360 -2          A18X+110974Y+119301X0120Y0150R180 S2      
327GND              C3271 -2          A18X+111535Y+113399X0120Y0150R090 S2      
327GND              C3279 -2          A18X+111909Y+113399X0120Y0150R090 S2      
327GND              C3282 -2          A18X+112283Y+113399X0120Y0150R090 S2      
327GND              C1688 -2          A18X+111909Y+114147X0120Y0150R090 S2      
327GND              C1686 -2          A18X+111535Y+114147X0120Y0150R090 S2      
327GND              C1698 -2          A18X+112283Y+114147X0120Y0150R090 S2      
327GND              C1685 -2          A18X+111535Y+114895X0120Y0150R090 S2      
327GND              C1697 -2          A18X+111909Y+114895X0120Y0150R090 S2      
327GND              C1700 -2          A18X+112283Y+114895X0120Y0150R090 S2      
327GND              C1677 -2          A18X+111535Y+118097X0120Y0150R270 S2      
327GND              C1691 -2          A18X+111909Y+118097X0120Y0150R270 S2      
327GND              C1689 -2          A18X+112283Y+118097X0120Y0150R270 S2      
327GND              C1681 -2          A18X+111167Y+118845X0120Y0150R270 S2      
327GND              C1702 -2          A18X+111535Y+118845X0120Y0150R270 S2      
327GND              C1696 -2          A18X+111909Y+118845X0120Y0150R270 S2      
327GND              C1687 -2          A18X+112283Y+118845X0120Y0150R270 S2      
327GND              C3264 -2          A18X+111535Y+119593X0120Y0150R270 S2      
327GND              C3252 -2          A18X+111909Y+119593X0120Y0150R270 S2      
327GND              C3260 -2          A18X+112283Y+119593X0120Y0150R270 S2      
327GND              C3318 -2          A18X+111327Y+120341X0120Y0150R270 S2      
327GND              C3326 -2          A18X+111701Y+120341X0120Y0150R270 S2      
327GND              C3333 -2          A18X+112075Y+120341X0120Y0150R270 S2      
327GND              C3325 -2          A18X+112449Y+120341X0120Y0150R270 S2      
327GND              C3281 -2          A18X+112657Y+113399X0120Y0150R090 S2      
327GND              C3278 -2          A18X+113031Y+113399X0120Y0150R090 S2      
327GND              C3290 -2          A18X+113405Y+113399X0120Y0150R090 S2      
327GND              C3291 -2          A18X+113780Y+113399X0120Y0150R090 S2      
327GND              C1730 -2          A18X+112657Y+114147X0120Y0150R090 S2      
327GND              C1746 -2          A18X+113031Y+114147X0120Y0150R090 S2      
327GND              C1741 -2          A18X+113405Y+114147X0120Y0150R090 S2      
327GND              C1721 -2          A18X+113780Y+114147X0120Y0150R090 S2      
327GND              C1744 -2          A18X+112657Y+114895X0120Y0150R090 S2      
327GND              C1743 -2          A18X+113031Y+114895X0120Y0150R090 S2      
327GND              C1732 -2          A18X+113405Y+114895X0120Y0150R090 S2      
327GND              C1726 -2          A18X+113780Y+114895X0120Y0150R090 S2      
327GND              C1710 -2          A18X+112657Y+118097X0120Y0150R270 S2      
327GND              C1723 -2          A18X+113031Y+118097X0120Y0150R270 S2      
327GND              C1729 -2          A18X+113405Y+118097X0120Y0150R270 S2      
327GND              C1709 -2          A18X+113780Y+118097X0120Y0150R270 S2      
327GND              C1714 -2          A18X+112657Y+118845X0120Y0150R270 S2      
327GND              C1712 -2          A18X+113031Y+118845X0120Y0150R270 S2      
327GND              C1733 -2          A18X+113405Y+118845X0120Y0150R270 S2      
327GND              C1736 -2          A18X+113780Y+118845X0120Y0150R270 S2      
327GND              C3261 -2          A18X+112657Y+119593X0120Y0150R270 S2      
327GND              C3263 -2          A18X+113031Y+119593X0120Y0150R270 S2      
327GND              C3266 -2          A18X+113405Y+119593X0120Y0150R270 S2      
327GND              C3262 -2          A18X+113780Y+119593X0120Y0150R270 S2      
327GND              C3319 -2          A18X+112823Y+120341X0120Y0150R270 S2      
327GND              C3310 -2          A18X+113197Y+120341X0120Y0150R270 S2      
327GND              C3311 -2          A18X+113571Y+120341X0120Y0150R270 S2      
327GND              C3329 -2          A18X+113945Y+120341X0120Y0150R270 S2      
327GND              C3268 -2          A18X+114154Y+113399X0120Y0150R090 S2      
327GND              C3283 -2          A18X+114528Y+113399X0120Y0150R090 S2      
327GND              C3289 -2          A18X+114902Y+113399X0120Y0150R090 S2      
327GND              C3269 -2          A18X+115276Y+113399X0120Y0150R090 S2      
327GND              C3286 -2          A18X+115650Y+113399X0120Y0150R090 S2      
327GND              C1750 -2          A18X+114154Y+114147X0120Y0150R090 S2      
327GND              C1690 -2          A18X+114528Y+114147X0120Y0150R090 S2      
327GND              C1739 -2          A18X+114902Y+114147X0120Y0150R090 S2      
327GND              C1731 -2          A18X+115650Y+114147X0120Y0150R090 S2      
327GND              C1707 -2          A18X+115276Y+114147X0120Y0150R090 S2      
327GND              C1708 -2          A18X+114154Y+114895X0120Y0150R090 S2      
327GND              C1671 -2          A18X+114528Y+114895X0120Y0150R090 S2      
327GND              C1715 -2          A18X+114902Y+114895X0120Y0150R090 S2      
327GND              C1725 -2          A18X+115276Y+114895X0120Y0150R090 S2      
327GND              C1742 -2          A18X+115650Y+114895X0120Y0150R090 S2      
327GND              C1747 -2          A18X+114154Y+118097X0120Y0150R270 S2      
327GND              C1701 -2          A18X+114528Y+118097X0120Y0150R270 S2      
327GND              C1718 -2          A18X+114902Y+118097X0120Y0150R270 S2      
327GND              C1713 -2          A18X+115276Y+118097X0120Y0150R270 S2      
327GND              C1745 -2          A18X+115650Y+118097X0120Y0150R270 S2      
327GND              C1737 -2          A18X+114154Y+118845X0120Y0150R270 S2      
327GND              C1683 -2          A18X+114528Y+118845X0120Y0150R270 S2      
327GND              C1728 -2          A18X+114902Y+118845X0120Y0150R270 S2      
327GND              C1716 -2          A18X+115276Y+118845X0120Y0150R270 S2      
327GND              C1735 -2          A18X+115650Y+118845X0120Y0150R270 S2      
327GND              C3265 -2          A18X+114154Y+119593X0120Y0150R270 S2      
327GND              C3280 -2          A18X+114528Y+119593X0120Y0150R270 S2      
327GND              C3251 -2          A18X+114902Y+119593X0120Y0150R270 S2      
327GND              C3259 -2          A18X+115276Y+119593X0120Y0150R270 S2      
327GND              C3256 -2          A18X+115650Y+119593X0120Y0150R270 S2      
327GND              C3330 -2          A18X+114319Y+120341X0120Y0150R270 S2      
327GND              C3293 -2          A18X+114709Y+120588X0280Y0320     S2      
327GND              C3315 -2          A18X+115099Y+120341X0120Y0150R270 S2      
327GND              C3322 -2          A18X+115473Y+120341X0120Y0150R270 S2      
327GND              C3287 -2          A18X+116024Y+113399X0120Y0150R090 S2      
327GND              C3276 -2          A18X+116398Y+113399X0120Y0150R090 S2      
327GND              C3275 -2          A18X+116772Y+113399X0120Y0150R090 S2      
327GND              C3273 -2          A18X+117146Y+113399X0120Y0150R090 S2      
327GND              C1748 -2          A18X+116398Y+114147X0120Y0150R090 S2      
327GND              C1711 -2          A18X+116024Y+114147X0120Y0150R090 S2      
327GND              C1738 -2          A18X+116772Y+114147X0120Y0150R090 S2      
327GND              C1678 -2          A18X+117146Y+114147X0120Y0150R090 S2      
327GND              C1727 -2          A18X+116024Y+114895X0120Y0150R090 S2      
327GND              C1720 -2          A18X+116398Y+114895X0120Y0150R090 S2      
327GND              C1734 -2          A18X+116772Y+114895X0120Y0150R090 S2      
327GND              C1680 -2          A18X+117146Y+114895X0120Y0150R090 S2      
327GND              C1719 -2          A18X+116024Y+118097X0120Y0150R270 S2      
327GND              C1724 -2          A18X+116398Y+118097X0120Y0150R270 S2      
327GND              C1722 -2          A18X+116772Y+118097X0120Y0150R270 S2      
327GND              C1693 -2          A18X+117146Y+118097X0120Y0150R270 S2      
327GND              C1749 -2          A18X+116024Y+118845X0120Y0150R270 S2      
327GND              C1740 -2          A18X+116398Y+118845X0120Y0150R270 S2      
327GND              C1717 -2          A18X+116772Y+118845X0120Y0150R270 S2      
327GND              C1679 -2          A18X+117146Y+118845X0120Y0150R270 S2      
327GND              C3254 -2          A18X+116024Y+119593X0120Y0150R270 S2      
327GND              C3257 -2          A18X+116398Y+119593X0120Y0150R270 S2      
327GND              C3267 -2          A18X+116772Y+119593X0120Y0150R270 S2      
327GND              C3250 -2          A18X+117146Y+119593X0120Y0150R270 S2      
327GND              C3314 -2          A18X+115847Y+120341X0120Y0150R270 S2      
327GND              C3321 -2          A18X+116221Y+120341X0120Y0150R270 S2      
327GND              C3301 -2          A18X+116595Y+120341X0120Y0150R270 S2      
327GND              C3302 -2          A18X+116969Y+120341X0120Y0150R270 S2      
327GND              C3270 -2          A18X+117520Y+113399X0120Y0150R090 S2      
327GND              C3284 -2          A18X+117894Y+113399X0120Y0150R090 S2      
327GND              C3344 -2          A18X+118455Y+112943X0120Y0150     S2      
327GND              C3345 -2          A18X+118455Y+113317X0120Y0150     S2      
327GND              C1682 -2          A18X+117520Y+114147X0120Y0150R090 S2      
327GND              C1705 -2          A18X+117894Y+114147X0120Y0150R090 S2      
327GND              C1699 -2          A18X+117520Y+114895X0120Y0150R090 S2      
327GND              C1706 -2          A18X+117894Y+114895X0120Y0150R090 S2      
327GND              C1704 -2          A18X+118455Y+117805X0120Y0150R180 S2      
327GND              C1684 -2          A18X+117520Y+118097X0120Y0150R270 S2      
327GND              C1694 -2          A18X+117894Y+118097X0120Y0150R270 S2      
327GND              C1692 -2          A18X+117520Y+118845X0120Y0150R270 S2      
327GND              C1703 -2          A18X+117894Y+118845X0120Y0150R270 S2      
327GND              C3255 -2          A18X+117520Y+119593X0120Y0150R270 S2      
327GND              C3272 -2          A18X+117894Y+119593X0120Y0150R270 S2      
327GND              C3305 -2          A18X+117343Y+120341X0120Y0150R270 S2      
327GND              C3317 -2          A18X+117717Y+120341X0120Y0150R270 S2      
327GND              C3323 -2          A18X+118091Y+120341X0120Y0150R270 S2      
327GND              C3359 -2          A18X+118829Y+119675X0120Y0150R090 S2      
327GND              C3346 -2          A18X+118829Y+120423X0120Y0150R270 S2      
327GND              C3288 -2          A18X+119495Y+115561X0120Y0150R180 S2      
327GND              C3274 -2          A18X+119495Y+115935X0120Y0150R180 S2      
327GND              C3285 -2          A18X+119495Y+116683X0120Y0150R180 S2      
327GND              C3258 -2          A18X+119495Y+117057X0120Y0150R180 S2      
327GND              C3298 -2          A18X+120243Y+115748X0120Y0150R180 S2      
327GND              C3297 -2          A18X+120243Y+116122X0120Y0150R180 S2      
327GND              C3316 -2          A18X+120243Y+116496X0120Y0150R180 S2      
327GND              C3296 -2          A18X+120243Y+116870X0120Y0150R180 S2      
327GND              C3295 -2          A18X+120243Y+117244X0120Y0150R180 S2      
327GND              C3361 -2          A18X+119951Y+118179X0120Y0150R180 S2      
327GND              C3337 -2          A18X+119203Y+118179X0120Y0150     S2      
327GND              C3277 -2          A18X+119495Y+117431X0120Y0150R180 S2      
327GND              C3249 -2          A18X+120937Y+116309X0280Y0320R090 S2      
327GND              C3253 -2          A18X+122614Y+116308X0280Y0320R270 S2      
327GND              C3512 -2          A18X+153751Y+112541X0280Y0320R090 S2      
327GND              C3591 -2          A18X+155421Y+117431X0120Y0150     S2      
327GND              C3548 -2          A18X+155271Y+117800X0120Y0150     S2      
327GND              C3547 -2          A18X+155271Y+118180X0120Y0150     S2      
327GND              C3521 -2          A18X+155271Y+118520X0120Y0150     S2      
327GND              C3566 -2          A18X+155271Y+115935X0120Y0150     S2      
327GND              C3565 -2          A18X+155271Y+116245X0120Y0150     S2      
327GND              C3551 -2          A18X+155271Y+116683X0120Y0150     S2      
327GND              C3550 -2          A18X+155271Y+117057X0120Y0150     S2      
327GND              C3578 -2          A18X+155271Y+115187X0120Y0150     S2      
327GND              C3579 -2          A18X+155271Y+115561X0120Y0150     S2      
327GND              C3581 -2          A18X+155421Y+114813X0120Y0150     S2      
327GND              C3527 -2          A18X+154521Y+116496X0120Y0150     S2      
327GND              C3524 -2          A18X+154521Y+116122X0120Y0150     S2      
327GND              C3509 -2          A18X+154521Y+115748X0120Y0150     S2      
327GND              C3522 -2          A18X+154521Y+115374X0120Y0150     S2      
327GND              C3525 -2          A18X+154521Y+115000X0120Y0150     S2      
327GND              C1935 -2          A18X+163602Y+114895X0120Y0150R090 S2      
327GND              C1960 -2          A18X+163228Y+114895X0120Y0150R090 S2      
327GND              C1933 -2          A18X+162854Y+114895X0120Y0150R090 S2      
327GND              C1991 -2          A18X+162480Y+114895X0120Y0150R090 S2      
327GND              C1979 -2          A18X+162106Y+114895X0120Y0150R090 S2      
327GND              C1978 -2          A18X+161732Y+114895X0120Y0150R090 S2      
327GND              C1963 -2          A18X+161358Y+114895X0120Y0150R090 S2      
327GND              C2001 -2          A18X+160984Y+114895X0120Y0150R090 S2      
327GND              C1988 -2          A18X+160610Y+114895X0120Y0150R090 S2      
327GND              C1926 -2          A18X+160236Y+114895X0120Y0150R090 S2      
327GND              C1997 -2          A18X+159862Y+114895X0120Y0150R090 S2      
327GND              C1996 -2          A18X+159488Y+114895X0120Y0150R090 S2      
327GND              C1984 -2          A18X+159114Y+114895X0120Y0150R090 S2      
327GND              C1983 -2          A18X+158740Y+114895X0120Y0150R090 S2      
327GND              C1981 -2          A18X+158366Y+114895X0120Y0150R090 S2      
327GND              C1955 -2          A18X+157992Y+114895X0120Y0150R090 S2      
327GND              C1942 -2          A18X+157618Y+114895X0120Y0150R090 S2      
327GND              C1954 -2          A18X+157244Y+114895X0120Y0150R090 S2      
327GND              C3482 -2          A18X+163789Y+112651X0120Y0150R090 S2      
327GND              C3506 -2          A18X+163415Y+112651X0120Y0150R090 S2      
327GND              C3507 -2          A18X+163041Y+112651X0120Y0150R090 S2      
327GND              C3504 -2          A18X+162667Y+112651X0120Y0150R090 S2      
327GND              C3505 -2          A18X+162293Y+112651X0120Y0150R090 S2      
327GND              C3503 -2          A18X+161919Y+112651X0120Y0150R090 S2      
327GND              C3481 -2          A18X+161545Y+112651X0120Y0150R090 S2      
327GND              C3478 -2          A18X+161171Y+112651X0120Y0150R090 S2      
327GND              C3479 -2          A18X+160797Y+112651X0120Y0150R090 S2      
327GND              C3473 -2          A18X+160049Y+112651X0120Y0150R090 S2      
327GND              C3476 -2          A18X+159675Y+112651X0120Y0150R090 S2      
327GND              C3474 -2          A18X+159301Y+112651X0120Y0150R090 S2      
327GND              C3475 -2          A18X+158927Y+112651X0120Y0150R090 S2      
327GND              C3501 -2          A18X+158553Y+112651X0120Y0150R090 S2      
327GND              C3500 -2          A18X+158179Y+112651X0120Y0150R090 S2      
327GND              C3491 -2          A18X+157805Y+112651X0120Y0150R090 S2      
327GND              C3502 -2          A18X+157431Y+112651X0120Y0150R090 S2      
327GND              C3472 -2          A18X+157057Y+112651X0120Y0150R090 S2      
327GND              C3467 -2          A18X+160420Y+112381X0280Y0320R180 S2      
327GND              C3441 -2          A18X+163602Y+113399X0120Y0150R090 S2      
327GND              C3445 -2          A18X+163228Y+113399X0120Y0150R090 S2      
327GND              C3444 -2          A18X+162854Y+113399X0120Y0150R090 S2      
327GND              C3443 -2          A18X+162480Y+113399X0120Y0150R090 S2      
327GND              C3442 -2          A18X+162106Y+113399X0120Y0150R090 S2      
327GND              C3446 -2          A18X+161732Y+113399X0120Y0150R090 S2      
327GND              C3447 -2          A18X+161358Y+113399X0120Y0150R090 S2      
327GND              C3448 -2          A18X+160984Y+113399X0120Y0150R090 S2      
327GND              C3453 -2          A18X+160610Y+113399X0120Y0150R090 S2      
327GND              C3457 -2          A18X+160236Y+113399X0120Y0150R090 S2      
327GND              C3458 -2          A18X+159862Y+113399X0120Y0150R090 S2      
327GND              C3463 -2          A18X+159488Y+113399X0120Y0150R090 S2      
327GND              C3454 -2          A18X+159114Y+113399X0120Y0150R090 S2      
327GND              C3461 -2          A18X+158740Y+113399X0120Y0150R090 S2      
327GND              C3451 -2          A18X+158366Y+113399X0120Y0150R090 S2      
327GND              C3449 -2          A18X+157992Y+113399X0120Y0150R090 S2      
327GND              C3450 -2          A18X+157618Y+113399X0120Y0150R090 S2      
327GND              C3456 -2          A18X+157244Y+113399X0120Y0150R090 S2      
327GND              C1959 -2          A18X+163602Y+114147X0120Y0150R090 S2      
327GND              C1947 -2          A18X+163228Y+114147X0120Y0150R090 S2      
327GND              C1958 -2          A18X+162854Y+114147X0120Y0150R090 S2      
327GND              C2003 -2          A18X+162480Y+114147X0120Y0150R090 S2      
327GND              C1966 -2          A18X+162106Y+114147X0120Y0150R090 S2      
327GND              C1965 -2          A18X+161732Y+114147X0120Y0150R090 S2      
327GND              C1975 -2          A18X+161358Y+114147X0120Y0150R090 S2      
327GND              C1962 -2          A18X+160984Y+114147X0120Y0150R090 S2      
327GND              C2000 -2          A18X+160610Y+114147X0120Y0150R090 S2      
327GND              C1938 -2          A18X+160236Y+114147X0120Y0150R090 S2      
327GND              C1971 -2          A18X+159862Y+114147X0120Y0150R090 S2      
327GND              C1970 -2          A18X+159488Y+114147X0120Y0150R090 S2      
327GND              C1995 -2          A18X+159114Y+114147X0120Y0150R090 S2      
327GND              C1982 -2          A18X+158740Y+114147X0120Y0150R090 S2      
327GND              C1968 -2          A18X+158366Y+114147X0120Y0150R090 S2      
327GND              C1953 -2          A18X+157992Y+114147X0120Y0150R090 S2      
327GND              C1941 -2          A18X+157618Y+114147X0120Y0150R090 S2      
327GND              C1940 -2          A18X+157244Y+114147X0120Y0150R090 S2      
327GND              C3455 -2          A18X+163602Y+119593X0120Y0150R270 S2      
327GND              C3425 -2          A18X+163228Y+119593X0120Y0150R270 S2      
327GND              C3426 -2          A18X+162854Y+119593X0120Y0150R270 S2      
327GND              C3460 -2          A18X+162480Y+119593X0120Y0150R270 S2      
327GND              C3439 -2          A18X+162106Y+119593X0120Y0150R270 S2      
327GND              C3429 -2          A18X+161732Y+119593X0120Y0150R270 S2      
327GND              C3427 -2          A18X+161358Y+119593X0120Y0150R270 S2      
327GND              C3434 -2          A18X+160984Y+119593X0120Y0150R270 S2      
327GND              C3428 -2          A18X+160610Y+119593X0120Y0150R270 S2      
327GND              C3462 -2          A18X+160236Y+119593X0120Y0150R270 S2      
327GND              C3430 -2          A18X+159862Y+119593X0120Y0150R270 S2      
327GND              C3435 -2          A18X+159488Y+119593X0120Y0150R270 S2      
327GND              C3431 -2          A18X+159114Y+119593X0120Y0150R270 S2      
327GND              C3432 -2          A18X+158740Y+119593X0120Y0150R270 S2      
327GND              C3436 -2          A18X+158366Y+119593X0120Y0150R270 S2      
327GND              C3437 -2          A18X+157992Y+119593X0120Y0150R270 S2      
327GND              C3433 -2          A18X+157618Y+119593X0120Y0150R270 S2      
327GND              C3438 -2          A18X+157244Y+119593X0120Y0150R270 S2      
327GND              C3494 -2          A18X+163800Y+120341X0120Y0150R270 S2      
327GND              C3484 -2          A18X+163426Y+120341X0120Y0150R270 S2      
327GND              C3483 -2          A18X+163052Y+120341X0120Y0150R270 S2      
327GND              C3477 -2          A18X+162678Y+120341X0120Y0150R270 S2      
327GND              C3480 -2          A18X+162304Y+120341X0120Y0150R270 S2      
327GND              C3485 -2          A18X+161930Y+120341X0120Y0150R270 S2      
327GND              C3486 -2          A18X+161556Y+120341X0120Y0150R270 S2      
327GND              C3466 -2          A18X+160418Y+120588X0280Y0320     S2      
327GND              C3496 -2          A18X+161182Y+120341X0120Y0150R270 S2      
327GND              C3495 -2          A18X+160808Y+120341X0120Y0150R270 S2      
327GND              C3497 -2          A18X+160028Y+120341X0120Y0150R270 S2      
327GND              C3487 -2          A18X+159654Y+120341X0120Y0150R270 S2      
327GND              C3488 -2          A18X+159280Y+120341X0120Y0150R270 S2      
327GND              C3498 -2          A18X+158906Y+120341X0120Y0150R270 S2      
327GND              C3499 -2          A18X+158532Y+120341X0120Y0150R270 S2      
327GND              C3489 -2          A18X+158158Y+120341X0120Y0150R270 S2      
327GND              C3492 -2          A18X+157784Y+120341X0120Y0150R270 S2      
327GND              C3490 -2          A18X+157410Y+120341X0120Y0150R270 S2      
327GND              C3493 -2          A18X+157036Y+120341X0120Y0150R270 S2      
327GND              C1950 -2          A18X+163602Y+118845X0120Y0150R270 S2      
327GND              C1937 -2          A18X+163228Y+118845X0120Y0150R270 S2      
327GND              C1946 -2          A18X+162854Y+118845X0120Y0150R270 S2      
327GND              C1993 -2          A18X+162480Y+118845X0120Y0150R270 S2      
327GND              C1980 -2          A18X+162106Y+118845X0120Y0150R270 S2      
327GND              C1967 -2          A18X+161732Y+118845X0120Y0150R270 S2      
327GND              C2002 -2          A18X+161358Y+118845X0120Y0150R270 S2      
327GND              C1990 -2          A18X+160984Y+118845X0120Y0150R270 S2      
327GND              C1989 -2          A18X+160610Y+118845X0120Y0150R270 S2      
327GND              C1951 -2          A18X+160236Y+118845X0120Y0150R270 S2      
327GND              C1999 -2          A18X+159862Y+118845X0120Y0150R270 S2      
327GND              C1987 -2          A18X+159488Y+118845X0120Y0150R270 S2      
327GND              C1986 -2          A18X+159114Y+118845X0120Y0150R270 S2      
327GND              C1974 -2          A18X+158740Y+118845X0120Y0150R270 S2      
327GND              C1969 -2          A18X+158366Y+118845X0120Y0150R270 S2      
327GND              C1945 -2          A18X+157992Y+118845X0120Y0150R270 S2      
327GND              C1932 -2          A18X+157618Y+118845X0120Y0150R270 S2      
327GND              C1957 -2          A18X+157244Y+118845X0120Y0150R270 S2      
327GND              C1952 -2          A18X+156876Y+118845X0120Y0150R270 S2      
327GND              C1961 -2          A18X+163602Y+118097X0120Y0150R270 S2      
327GND              C1949 -2          A18X+163228Y+118097X0120Y0150R270 S2      
327GND              C1934 -2          A18X+162854Y+118097X0120Y0150R270 S2      
327GND              C2005 -2          A18X+162480Y+118097X0120Y0150R270 S2      
327GND              C2004 -2          A18X+162106Y+118097X0120Y0150R270 S2      
327GND              C1992 -2          A18X+161732Y+118097X0120Y0150R270 S2      
327GND              C1977 -2          A18X+161358Y+118097X0120Y0150R270 S2      
327GND              C1943 -2          A18X+160984Y+118097X0120Y0150R270 S2      
327GND              C1976 -2          A18X+160610Y+118097X0120Y0150R270 S2      
327GND              C1964 -2          A18X+160236Y+118097X0120Y0150R270 S2      
327GND              C1939 -2          A18X+159862Y+118097X0120Y0150R270 S2      
327GND              C1973 -2          A18X+159488Y+118097X0120Y0150R270 S2      
327GND              C1998 -2          A18X+159114Y+118097X0120Y0150R270 S2      
327GND              C1985 -2          A18X+158740Y+118097X0120Y0150R270 S2      
327GND              C1972 -2          A18X+158366Y+118097X0120Y0150R270 S2      
327GND              C1994 -2          A18X+157992Y+118097X0120Y0150R270 S2      
327GND              C1956 -2          A18X+157618Y+118097X0120Y0150R270 S2      
327GND              C1944 -2          A18X+157244Y+118097X0120Y0150R270 S2      
327GND              PEX3  -AM7        A01X+153878Y+113878X0180Y         S1      
327GND              PEX3  -AM6        A01X+153504Y+113878X0180Y         S1      
327GND              PEX3  -AM5        A01X+153130Y+113878X0180Y         S1      
327GND              PEX3  -AM4        A01X+152756Y+113878X0180Y         S1      
327GND              PEX3  -AJ12       A01X+155748Y+115000X0180Y         S1      
327GND              C3510 -2          A18X+155663Y+118909X0280Y0320R090 S2      
327GND              C3517 -2          A18X+155935Y+119301X0120Y0150     S2      
327GND              C3536 -2          A18X+156683Y+119301X0120Y0150R180 S2      
327GND              C3519 -2          A18X+164163Y+113317X0120Y0150     S2      
327GND              C3520 -2          A18X+164163Y+112943X0120Y0150     S2      
327GND              C1931 -2          A18X+164163Y+117805X0120Y0150R180 S2      
327GND              C3452 -2          A18X+165203Y+115561X0120Y0150R180 S2      
327GND              C3469 -2          A18X+165951Y+117244X0120Y0150R180 S2      
327GND              C3468 -2          A18X+165951Y+116870X0120Y0150R180 S2      
327GND              C3508 -2          A18X+165951Y+116496X0120Y0150R180 S2      
327GND              C3470 -2          A18X+165951Y+116122X0120Y0150R180 S2      
327GND              C3471 -2          A18X+165951Y+115748X0120Y0150R180 S2      
327GND              C3440 -2          A18X+165203Y+117057X0120Y0150R180 S2      
327GND              C3459 -2          A18X+165203Y+116683X0120Y0150R180 S2      
327GND              C3464 -2          A18X+165203Y+115935X0120Y0150R180 S2      
327GND              C3511 -2          A18X+164911Y+118179X0120Y0150     S2      
327GND              C3531 -2          A18X+165659Y+118179X0120Y0150R180 S2      
327GND              C3465 -2          A18X+165203Y+117431X0120Y0150R180 S2      
327GND              C3518 -2          A18X+164537Y+120423X0120Y0150R270 S2      
327GND              C3529 -2          A18X+164537Y+119675X0120Y0150R090 S2      
327GND              C3424 -2          A18X+168322Y+116308X0280Y0320R270 S2      
327GND              C3423 -2          A18X+166646Y+116309X0280Y0320R090 S2      
327GND              C3534 -2          A18X+154521Y+118179X0120Y0150     S2      
327GND              C3535 -2          A18X+154521Y+117805X0120Y0150     S2      
327GND              C3533 -2          A18X+154521Y+117431X0120Y0150     S2      
327GND              C3582 -2          A18X+155935Y+114439X0120Y0150R090 S2      
327GND              C3568 -2          A18X+155935Y+115187X0120Y0150R090 S2      
327GND              C3569 -2   M      A18X+155935Y+115905X0120Y0150R270 S2      
327GND              C3545 -2          A18X+155936Y+117825X0120Y0150R090 S2      
327GND              C3544 -2          A18X+155936Y+118530X0120Y0150R270 S2      
327GND              C1155 -2          A18X+022923Y+115643X0120Y0150R090 S2      
327GND              C2953 -2          A18X+026663Y+112651X0120Y0150R090 S2      
327GND              C2963 -2          A18X+026289Y+112651X0120Y0150R090 S2      
327GND              C2969 -2          A18X+024793Y+112651X0120Y0150R090 S2      
327GND              C2979 -2          A18X+025915Y+112651X0120Y0150R090 S2      
327GND              C2965 -2          A18X+025541Y+112651X0120Y0150R090 S2      
327GND              C2968 -2          A18X+025167Y+112651X0120Y0150R090 S2      
327GND              C2959 -2          A18X+023684Y+112651X0120Y0150R090 S2      
327GND              C2960 -2          A18X+024045Y+112651X0120Y0150R090 S2      
327GND              C2961 -2          A18X+024419Y+112651X0120Y0150R090 S2      
327GND              C2955 -2          A18X+021801Y+112651X0120Y0150R090 S2      
327GND              C2951 -2          A18X+022549Y+112651X0120Y0150R090 S2      
327GND              C2957 -2          A18X+022175Y+112651X0120Y0150R090 S2      
327GND              C2958 -2          A18X+022904Y+112651X0120Y0150R090 S2      
327GND              C2971 -2          A18X+021053Y+112651X0120Y0150R090 S2      
327GND              C2972 -2          A18X+021427Y+112651X0120Y0150R090 S2      
327GND              C2981 -2          A18X+020679Y+112651X0120Y0150R090 S2      
327GND              C2985 -2          A18X+020305Y+112651X0120Y0150R090 S2      
327GND              C2946 -2          A18X+019931Y+112651X0120Y0150R090 S2      
327GND              C2944 -2          A18X+023294Y+112381X0280Y0320R180 S2      
327GND              C3002 -2          A18X+027703Y+113691X0120Y0150R180 S2      
327GND              C3003 -2          A18X+027703Y+114065X0120Y0150R180 S2      
327GND              C2994 -2          A18X+027703Y+114439X0120Y0150R180 S2      
327GND              C1106 -2          A18X+019475Y+115187X0120Y0150R180 S2      
327GND              C1103 -2          A18X+019265Y+114813X0120Y0150     S2      
327GND              C1104 -2          A18X+019475Y+114439X0120Y0150R180 S2      
327GND              C3006 -2          A18X+018143Y+114439X0120Y0150     S2      
327GND              C3010 -2          A18X+019475Y+113691X0120Y0150R180 S2      
327GND              C2988 -2          A18X+018537Y+118909X0280Y0320R090 S2      
327GND              C3001 -2          A18X+018145Y+118520X0120Y0150     S2      
327GND              C3026 -2          A18X+018145Y+117800X0120Y0150     S2      
327GND              C3025 -2          A18X+018145Y+118180X0120Y0150     S2      
327GND              C3028 -2          A18X+018145Y+117057X0120Y0150     S2      
327GND              C3029 -2          A18X+018145Y+116683X0120Y0150     S2      
327GND              C3043 -2          A18X+018145Y+116245X0120Y0150     S2      
327GND              C3184 -2          A18X+065266Y+119301X0120Y0150R180 S2      
327GND              C3164 -2          A18X+074242Y+118179X0120Y0150R180 S2      
327GND              C3171 -2          A18X+072746Y+112943X0120Y0150     S2      
327GND              C3170 -2          A18X+072746Y+113317X0120Y0150     S2      
327GND              PEX1  -AM7        A01X+062461Y+113878X0180Y         S1      
327GND              PEX1  -AM6        A01X+062087Y+113878X0180Y         S1      
327GND              PEX1  -AM5        A01X+061713Y+113878X0180Y         S1      
327GND              PEX1  -AM4        A01X+061339Y+113878X0180Y         S1      
327GND              C3172 -2          A18X+073120Y+120423X0120Y0150R270 S2      
327GND              C3069 -2   M      A18X+018295Y+117431X0120Y0150     S2      
327GND              C3040 -2          A18X+018809Y+116185X0120Y0150R090 S2      
327GND              C3044 -2   M      A18X+018145Y+115935X0120Y0150     S2      
327GND              C3057 -2   M      A18X+018145Y+115561X0120Y0150     S2      
327GND              C3056 -2   M      A18X+018145Y+115187X0120Y0150     S2      
327GND              C3060 -2   M      A18X+018295Y+114813X0120Y0150     S2      
327GND              C1127 -2          A18X+025631Y+116683X0120Y0150     S2      
327GND              C1130 -2          A18X+024883Y+116683X0120Y0150     S2      
327GND              C1107 -2          A18X+024195Y+116690X0120Y0150     S2      
327GND              C1128 -2          A18X+023905Y+116690X0120Y0150R180 S2      
327GND              C1112 -2          A18X+023013Y+116683X0120Y0150     S2      
327GND              C1109 -2          A18X+022275Y+116683X0120Y0150     S2      
327GND              C1113 -2          A18X+021527Y+116683X0120Y0150     S2      
327GND              C1111 -2          A18X+020779Y+116683X0120Y0150     S2      
327GND              C1129 -2          A18X+020031Y+116683X0120Y0150     S2      
327GND              C1124 -2          A18X+019283Y+116683X0120Y0150     S2      
327GND              C1125 -2          A18X+025915Y+117139X0120Y0150R090 S2      
327GND              C1143 -2          A18X+025541Y+117349X0120Y0150R270 S2      
327GND              C1116 -2          A18X+025167Y+117139X0120Y0150R090 S2      
327GND              C1145 -2          A18X+024793Y+117349X0120Y0150R270 S2      
327GND              C1115 -2          A18X+024419Y+117139X0120Y0150R090 S2      
327GND              C1117 -2          A18X+024045Y+117349X0120Y0150R270 S2      
327GND              C1114 -2          A18X+023671Y+117139X0120Y0150R090 S2      
327GND              C1133 -2          A18X+022929Y+117349X0120Y0150R270 S2      
327GND              C1118 -2          A18X+022549Y+117139X0120Y0150R090 S2      
327GND              C1154 -2          A18X+022175Y+117349X0120Y0150R270 S2      
327GND              C1151 -2          A18X+021801Y+117139X0120Y0150R090 S2      
327GND              C1148 -2          A18X+021427Y+117349X0120Y0150R270 S2      
327GND              C1121 -2          A18X+021053Y+117139X0120Y0150R090 S2      
327GND              C1122 -2          A18X+020679Y+117349X0120Y0150R270 S2      
327GND              C1140 -2          A18X+020305Y+117139X0120Y0150R090 S2      
327GND              C1138 -2          A18X+019931Y+117349X0120Y0150R270 S2      
327GND              C1152 -2          A18X+019557Y+117139X0120Y0150R090 S2      
327GND              C1123 -2          A18X+019183Y+117349X0120Y0150R270 S2      
327GND              C3041 -2          A18X+018809Y+116893X0120Y0150R270 S2      
327GND              C3068 -2          A18X+018809Y+117221X0120Y0150R090 S2      
327GND              C1132 -2          A18X+019475Y+117825X0120Y0150R180 S2      
327GND              C1131 -2          A18X+019265Y+118179X0120Y0150     S2      
327GND              C1110 -2          A18X+019455Y+118510X0120Y0150R180 S2      
327GND              C2993 -2          A18X+027119Y+119301X0120Y0150     S2      
327GND              C2992 -2          A18X+027119Y+118927X0120Y0150     S2      
327GND              C2991 -2          A18X+027119Y+118553X0120Y0150     S2      
327GND              C3013 -2          A18X+027329Y+118179X0120Y0150R180 S2      
327GND              C1174 -2          A18X+026289Y+117349X0120Y0150R270 S2      
327GND              C1164 -2          A18X+027037Y+117805X0120Y0150R180 S2      
327GND              C1126 -2          A18X+026955Y+117431X0120Y0150R180 S2      
327GND              C1192 -2          A18X+026371Y+116683X0120Y0150     S2      
327GND              C1161 -2          A18X+027329Y+117057X0120Y0150R180 S2      
327GND              C1162 -2          A18X+027329Y+116683X0120Y0150R180 S2      
327GND              C1163 -2          A18X+027329Y+115935X0120Y0150R180 S2      
327GND              C1105 -2          A18X+026955Y+115561X0120Y0150R180 S2      
327GND              C1166 -2          A18X+026290Y+115643X0120Y0150R090 S2      
327GND              C1120 -2          A18X+025915Y+115853X0120Y0150R270 S2      
327GND              C1144 -2          A18X+025541Y+115643X0120Y0150R090 S2      
327GND              C1141 -2          A18X+025167Y+115853X0120Y0150R270 S2      
327GND              C1142 -2          A18X+024793Y+115643X0120Y0150R090 S2      
327GND              C1146 -2          A18X+024419Y+115853X0120Y0150R270 S2      
327GND              C1135 -2          A18X+024045Y+115643X0120Y0150R090 S2      
327GND              C1136 -2          A18X+023671Y+115853X0120Y0150R270 S2      
327GND              C1108 -2          A18X+019183Y+115643X0120Y0150R090 S2      
327GND              C1137 -2          A18X+019557Y+115853X0120Y0150R270 S2      
327GND              C1119 -2          A18X+019931Y+115643X0120Y0150R090 S2      
327GND              C1139 -2          A18X+020305Y+115853X0120Y0150R270 S2      
327GND              C1134 -2          A18X+020679Y+115643X0120Y0150R090 S2      
327GND              C1153 -2          A18X+021053Y+115853X0120Y0150R270 S2      
327GND              C1150 -2          A18X+021427Y+115643X0120Y0150R090 S2      
327GND              C1147 -2          A18X+021801Y+115853X0120Y0150R270 S2      
327GND              C1156 -2          A18X+022175Y+115643X0120Y0150R090 S2      
327GND              C1149 -2          A18X+022549Y+115853X0120Y0150R270 S2      
327GND              PEX0  -AG12       A01X+018622Y+115748X0180Y         S1      
327GND              C3059 -2          A18X+018809Y+114439X0120Y0150R090 S2      
327GND              C3046 -2          A18X+018809Y+115187X0120Y0150R090 S2      
327GND              C3047 -2          A18X+018809Y+115905X0120Y0150R270 S2      
327GND              PEX0  -AE12       A01X+018622Y+116496X0180Y         S1      
327GND              C3023 -2          A18X+018810Y+117825X0120Y0150R090 S2      
327GND              C3022 -2          A18X+018810Y+118530X0120Y0150R270 S2      
327GND              PEX0  -AM6        A01X+016378Y+113878X0180Y         S1      
327GND              PEX0  -AM5        A01X+016004Y+113878X0180Y         S1      
327GND              PEX0  -AM4        A01X+015630Y+113878X0180Y         S1      
317GND              VIA   -    MD0080PA00X+017313Y+118553X0160Y         S0      
317GND              VIA   -    MD0080PA00X+017687Y+118553X0160Y         S0      
327GND              C3011 -2          A18X+019557Y+119301X0120Y0150R180 S2      
327GND              C2998 -2          A18X+027411Y+120423X0120Y0150R270 S2      
327GND              C3014 -2          A18X+027411Y+119675X0120Y0150R090 S2      
327GND              C3012 -2          A18X+028533Y+118179X0120Y0150R180 S2      
327GND              C2989 -2          A18X+027785Y+118179X0120Y0150     S2      
317GND              VIA   -    MD0100PA00X+144636Y+053295X0200Y    R180 S0      
317GND              VIA   -    MD0100PA00X+144356Y+053295X0200Y    R180 S0      
317GND              VIA   -    MD0100PA00X+007480Y+053275X0200Y    R180 S0      
317GND              VIA   -    MD0100PA00X+007200Y+053275X0200Y    R180 S0      
317GND              VIA   -    M      A01X+098627Y+053295X0200Y    R180 S2      
017GND              VIA   -    M      A18X+098627Y+053295X0260Y    R180 S2      
017GND                    -    MD0100PA00X+098627Y+053295                       
317GND              VIA   -    MD0100PA00X+098907Y+053295X0200Y    R180 S0      
317GND              VIA   -    MD0100PA00X+053228Y+053285X0200Y    R180 S0      
317GND              VIA   -    MD0100PA00X+052948Y+053285X0200Y    R180 S0      
327GND              PEX3  -L11        A01X+155374Y+121732X0180Y         S1      
317GND              VIA   -    MD0080PA00X+155374Y+121732X0160Y         S0      
327GND              PEX3  -AM40       A01X+166220Y+113878X0180Y         S1      
317GND              VIA   -    MD0080PA00X+166220Y+113878X0160Y         S0      
327GND              PEX3  -AW40       A01X+166220Y+111260X0180Y         S1      
327GND              PEX3  -AW20       A01X+158740Y+111260X0180Y         S1      
317GND              VIA   -    MD0080PA00X+158740Y+111260X0160Y         S0      
327GND              PEX3  -AW11       A01X+155374Y+111260X0180Y         S1      
317GND              VIA   -    MD0080PA00X+155187Y+111073X0160Y         S0      
317GND              VIA   -    MD0080PA00X+155000Y+121732X0160Y         S0      
317GND              VIA   -    MD0080PA00X+155000Y+121358X0160Y         S0      
317GND              VIA   -    MD0080PA00X+155000Y+120984X0160Y         S0      
317GND              VIA   -    MD0080PA00X+155000Y+120610X0160Y         S0      
317GND              VIA   -    MD0080PA00X+155000Y+120236X0160Y         S0      
317GND              VIA   -    MD0080PA00X+155000Y+119862X0160Y         S0      
317GND              VIA   -    MD0080PA00X+155000Y+119488X0160Y         S0      
317GND              VIA   -    MD0080PA00X+155000Y+119114X0160Y         S0      
317GND              VIA   -    MD0080PA00X+155000Y+118740X0160Y         S0      
317GND              VIA   -    MD0080PA00X+155000Y+110886X0160Y         S0      
317GND              VIA   -    MD0080PA00X+155374Y+110886X0160Y         S0      
317GND              VIA   -    MD0080PA00X+155748Y+110886X0160Y         S0      
317GND              VIA   -    MD0080PA00X+156122Y+110886X0160Y         S0      
317GND              VIA   -    MD0080PA00X+156496Y+110886X0160Y         S0      
317GND              VIA   -    MD0080PA00X+156870Y+110886X0160Y         S0      
317GND              VIA   -    MD0080PA00X+157244Y+110886X0160Y         S0      
317GND              VIA   -    MD0080PA00X+157618Y+110886X0160Y         S0      
317GND              VIA   -    MD0080PA00X+157992Y+110886X0160Y         S0      
317GND              VIA   -    MD0080PA00X+158366Y+110886X0160Y         S0      
317GND              VIA   -    MD0080PA00X+158740Y+110886X0160Y         S0      
317GND              VIA   -    MD0080PA00X+159114Y+110886X0160Y         S0      
317GND              VIA   -    MD0080PA00X+159488Y+110886X0160Y         S0      
317GND              VIA   -    MD0080PA00X+159862Y+110886X0160Y         S0      
317GND              VIA   -    MD0080PA00X+160236Y+110886X0160Y         S0      
317GND              VIA   -    MD0080PA00X+160610Y+110886X0160Y         S0      
317GND              VIA   -    MD0080PA00X+160984Y+110886X0160Y         S0      
317GND              VIA   -    MD0080PA00X+161358Y+110886X0160Y         S0      
317GND              VIA   -    MD0080PA00X+161732Y+110886X0160Y         S0      
317GND              VIA   -    MD0080PA00X+162106Y+110886X0160Y         S0      
317GND              VIA   -    MD0080PA00X+162480Y+110886X0160Y         S0      
317GND              VIA   -    MD0080PA00X+162854Y+110886X0160Y         S0      
317GND              VIA   -    MD0080PA00X+163228Y+110886X0160Y         S0      
317GND              VIA   -    MD0080PA00X+163602Y+110886X0160Y         S0      
317GND              VIA   -    MD0080PA00X+163976Y+110886X0160Y         S0      
317GND              VIA   -    MD0080PA00X+164350Y+110886X0160Y         S0      
317GND              VIA   -    MD0080PA00X+164724Y+110886X0160Y         S0      
317GND              VIA   -    MD0080PA00X+165098Y+110886X0160Y         S0      
317GND              VIA   -    MD0080PA00X+165472Y+110886X0160Y         S0      
317GND              VIA   -    MD0080PA00X+165846Y+110886X0160Y         S0      
317GND              VIA   -    MD0080PA00X+166220Y+110886X0160Y         S0      
317GND              VIA   -    MD0080PA00X+166220Y+111634X0160Y         S0      
317GND              VIA   -    MD0080PA00X+166220Y+112008X0160Y         S0      
317GND              VIA   -    MD0080PA00X+166220Y+112382X0160Y         S0      
327GND              PEX3  -AY41       A01X+166594Y+110886X0180Y         S1      
317GND              VIA   -    MD0080PA00X+166594Y+110886X0160Y         S0      
317GND              VIA   -    MD0080PA00X+166220Y+112756X0160Y         S0      
317GND              VIA   -    MD0080PA00X+166220Y+113130X0160Y         S0      
317GND              VIA   -    MD0080PA00X+166220Y+113504X0160Y         S0      
327GND              PEX2  -AW40       A01X+120512Y+111260X0180Y         S1      
327GND              R1392 -2          A18X+113812Y+121703X0198Y0197R270 S2      
327GND              PEX2  -K10        A01X+109291Y+122106X0180Y         S1      
317GND              VIA   -    MD0080PA00X+109291Y+122106X0160Y         S0      
327GND              PEX2  -K11        A01X+109665Y+122106X0180Y         S1      
317GND              VIA   -    MD0080PA00X+109665Y+122106X0160Y         S0      
327GND              PEX2  -K12        A01X+110039Y+122106X0180Y         S1      
317GND              VIA   -    MD0080PA00X+110039Y+122106X0160Y         S0      
327GND              PEX2  -K13        A01X+110413Y+122106X0180Y         S1      
317GND              VIA   -    MD0080PA00X+110413Y+122106X0160Y         S0      
327GND              PEX2  -K14        A01X+110787Y+122106X0180Y         S1      
317GND              VIA   -    MD0080PA00X+110787Y+122106X0160Y         S0      
327GND              PEX2  -K15        A01X+111161Y+122106X0180Y         S1      
317GND              VIA   -    MD0080PA00X+111161Y+122106X0160Y         S0      
327GND              PEX2  -K16        A01X+111535Y+122106X0180Y         S1      
317GND              VIA   -    MD0080PA00X+111535Y+122106X0160Y         S0      
327GND              PEX2  -K17        A01X+111909Y+122106X0180Y         S1      
317GND              VIA   -    MD0080PA00X+111909Y+122106X0160Y         S0      
327GND              PEX2  -K18        A01X+112283Y+122106X0180Y         S1      
317GND              VIA   -    MD0080PA00X+112283Y+122106X0160Y         S0      
327GND              PEX2  -K19        A01X+112657Y+122106X0180Y         S1      
317GND              VIA   -    MD0080PA00X+112657Y+122106X0160Y         S0      
327GND              PEX2  -K20        A01X+113031Y+122106X0180Y         S1      
317GND              VIA   -    MD0080PA00X+113031Y+122106X0160Y         S0      
327GND              PEX2  -K21        A01X+113405Y+122106X0180Y         S1      
317GND              VIA   -    MD0080PA00X+113405Y+122106X0160Y         S0      
327GND              PEX2  -K22        A01X+113780Y+122106X0180Y         S1      
317GND              VIA   -    MD0080PA00X+113780Y+122106X0160Y         S0      
327GND              PEX2  -K23        A01X+114154Y+122106X0180Y         S1      
317GND              VIA   -    MD0080PA00X+114154Y+122106X0160Y         S0      
327GND              PEX2  -K24        A01X+114528Y+122106X0180Y         S1      
317GND              VIA   -    MD0080PA00X+114528Y+122106X0160Y         S0      
327GND              PEX2  -K26        A01X+115276Y+122106X0180Y         S1      
317GND              VIA   -    MD0080PA00X+115276Y+122106X0160Y         S0      
327GND              PEX2  -K27        A01X+115650Y+122106X0180Y         S1      
317GND              VIA   -    MD0080PA00X+115650Y+122106X0160Y         S0      
327GND              PEX2  -K28        A01X+116024Y+122106X0180Y         S1      
317GND              VIA   -    MD0080PA00X+116024Y+122106X0160Y         S0      
327GND              PEX2  -K29        A01X+116398Y+122106X0180Y         S1      
317GND              VIA   -    MD0080PA00X+116398Y+122106X0160Y         S0      
327GND              PEX2  -K30        A01X+116772Y+122106X0180Y         S1      
317GND              VIA   -    MD0080PA00X+116772Y+122106X0160Y         S0      
327GND              PEX2  -K31        A01X+117146Y+122106X0180Y         S1      
317GND              VIA   -    MD0080PA00X+117146Y+122106X0160Y         S0      
327GND              PEX2  -K32        A01X+117520Y+122106X0180Y         S1      
317GND              VIA   -    MD0080PA00X+117520Y+122106X0160Y         S0      
327GND              PEX2  -K33        A01X+117894Y+122106X0180Y         S1      
317GND              VIA   -    MD0080PA00X+117894Y+122106X0160Y         S0      
327GND              PEX2  -K34        A01X+118268Y+122106X0180Y         S1      
317GND              VIA   -    MD0080PA00X+118268Y+122106X0160Y         S0      
327GND              PEX2  -K35        A01X+118642Y+122106X0180Y         S1      
317GND              VIA   -    MD0080PA00X+118642Y+122106X0160Y         S0      
327GND              PEX2  -K36        A01X+119016Y+122106X0180Y         S1      
317GND              VIA   -    MD0080PA00X+119016Y+122106X0160Y         S0      
327GND              PEX2  -K37        A01X+119390Y+122106X0180Y         S1      
317GND              VIA   -    MD0080PA00X+119390Y+122106X0160Y         S0      
327GND              PEX2  -K38        A01X+119764Y+122106X0180Y         S1      
317GND              VIA   -    MD0080PA00X+119764Y+122106X0160Y         S0      
327GND              PEX2  -K39        A01X+120138Y+122106X0180Y         S1      
317GND              VIA   -    MD0080PA00X+120138Y+122106X0160Y         S0      
327GND              PEX2  -K40        A01X+120512Y+122106X0180Y         S1      
317GND              VIA   -    MD0080PA00X+120512Y+122106X0160Y         S0      
327GND              PEX2  -L40        A01X+120512Y+121732X0180Y         S1      
317GND              VIA   -    MD0080PA00X+120512Y+121732X0160Y         S0      
327GND              PEX2  -M40        A01X+120512Y+121358X0180Y         S1      
317GND              VIA   -    MD0080PA00X+120512Y+121358X0160Y         S0      
327GND              PEX2  -N40        A01X+120512Y+120984X0180Y         S1      
317GND              VIA   -    MD0080PA00X+120512Y+120984X0160Y         S0      
327GND              PEX2  -P40        A01X+120512Y+120610X0180Y         S1      
317GND              VIA   -    MD0080PA00X+120512Y+120610X0160Y         S0      
327GND              PEX2  -R40        A01X+120512Y+120236X0180Y         S1      
317GND              VIA   -    MD0080PA00X+120512Y+120236X0160Y         S0      
327GND              PEX2  -T40        A01X+120512Y+119862X0180Y         S1      
317GND              VIA   -    MD0080PA00X+120512Y+119862X0160Y         S0      
317GND              VIA   -    MD0080PA00X+109291Y+121732X0160Y         S0      
317GND              VIA   -    MD0080PA00X+109291Y+121358X0160Y         S0      
317GND              VIA   -    MD0080PA00X+109291Y+120984X0160Y         S0      
317GND              VIA   -    MD0080PA00X+109291Y+120610X0160Y         S0      
317GND              VIA   -    MD0080PA00X+109291Y+120236X0160Y         S0      
317GND              VIA   -    MD0080PA00X+109291Y+119862X0160Y         S0      
317GND              VIA   -    MD0080PA00X+109291Y+119488X0160Y         S0      
317GND              VIA   -    MD0080PA00X+109291Y+119114X0160Y         S0      
317GND              VIA   -    MD0080PA00X+109291Y+118740X0160Y         S0      
317GND              VIA   -    MD0080PA00X+108917Y+110886X0160Y         S0      
317GND              VIA   -    MD0080PA00X+109291Y+110886X0160Y         S0      
317GND              VIA   -    MD0080PA00X+109665Y+110886X0160Y         S0      
317GND              VIA   -    MD0080PA00X+110039Y+110886X0160Y         S0      
317GND              VIA   -    MD0080PA00X+110413Y+110886X0160Y         S0      
317GND              VIA   -    MD0080PA00X+110787Y+110886X0160Y         S0      
317GND              VIA   -    MD0080PA00X+111161Y+110886X0160Y         S0      
317GND              VIA   -    MD0080PA00X+111535Y+110886X0160Y         S0      
317GND              VIA   -    MD0080PA00X+111909Y+110886X0160Y         S0      
317GND              VIA   -    MD0080PA00X+112283Y+110886X0160Y         S0      
317GND              VIA   -    MD0080PA00X+112657Y+110886X0160Y         S0      
317GND              VIA   -    MD0080PA00X+113031Y+110886X0160Y         S0      
317GND              VIA   -    MD0080PA00X+113405Y+110886X0160Y         S0      
317GND              VIA   -    MD0080PA00X+113780Y+110886X0160Y         S0      
317GND              VIA   -    MD0080PA00X+114154Y+110886X0160Y         S0      
317GND              VIA   -    MD0080PA00X+114528Y+110886X0160Y         S0      
317GND              VIA   -    MD0080PA00X+114902Y+110886X0160Y         S0      
317GND              VIA   -    MD0080PA00X+115276Y+110886X0160Y         S0      
317GND              VIA   -    MD0080PA00X+115650Y+110886X0160Y         S0      
317GND              VIA   -    MD0080PA00X+116024Y+110886X0160Y         S0      
317GND              VIA   -    MD0080PA00X+116398Y+110886X0160Y         S0      
317GND              VIA   -    MD0080PA00X+116772Y+110886X0160Y         S0      
317GND              VIA   -    MD0080PA00X+117146Y+110886X0160Y         S0      
317GND              VIA   -    MD0080PA00X+117520Y+110886X0160Y         S0      
317GND              VIA   -    MD0080PA00X+117894Y+110886X0160Y         S0      
317GND              VIA   -    MD0080PA00X+118268Y+110886X0160Y         S0      
317GND              VIA   -    MD0080PA00X+118642Y+110886X0160Y         S0      
317GND              VIA   -    MD0080PA00X+119016Y+110886X0160Y         S0      
317GND              VIA   -    MD0080PA00X+119390Y+110886X0160Y         S0      
317GND              VIA   -    MD0080PA00X+119764Y+110886X0160Y         S0      
317GND              VIA   -    MD0080PA00X+120138Y+110886X0160Y         S0      
317GND              VIA   -    MD0080PA00X+120512Y+110886X0160Y         S0      
317GND              VIA   -    MD0080PA00X+120512Y+111634X0160Y         S0      
317GND              VIA   -    MD0080PA00X+120512Y+112008X0160Y         S0      
317GND              VIA   -    MD0080PA00X+120512Y+112382X0160Y         S0      
317GND              VIA   -    MD0080PA00X+120512Y+112756X0160Y         S0      
317GND              VIA   -    MD0080PA00X+120512Y+113130X0160Y         S0      
317GND              VIA   -    MD0080PA00X+120512Y+113504X0160Y         S0      
327GND              PEX1  -AA7        A01X+062461Y+117992X0180Y         S1      
317GND              VIA   -    MD0080PA00X+063583Y+121732X0160Y         S0      
317GND              VIA   -    MD0080PA00X+063583Y+121358X0160Y         S0      
317GND              VIA   -    MD0080PA00X+063583Y+120984X0160Y         S0      
317GND              VIA   -    MD0080PA00X+063583Y+120610X0160Y         S0      
317GND              VIA   -    MD0080PA00X+063583Y+120236X0160Y         S0      
317GND              VIA   -    MD0080PA00X+063583Y+119862X0160Y         S0      
317GND              VIA   -    MD0080PA00X+063583Y+119488X0160Y         S0      
317GND              VIA   -    MD0080PA00X+063583Y+119114X0160Y         S0      
317GND              VIA   -    MD0080PA00X+063583Y+118740X0160Y         S0      
317GND              VIA   -    MD0080PA00X+062461Y+118366X0160Y         S0      
317GND              VIA   -    MD0080PA00X+063209Y+110886X0160Y         S0      
317GND              VIA   -    MD0080PA00X+063957Y+110886X0160Y         S0      
317GND              VIA   -    MD0080PA00X+063583Y+110886X0160Y         S0      
317GND              VIA   -    MD0080PA00X+064331Y+110886X0160Y         S0      
317GND              VIA   -    MD0080PA00X+064705Y+110886X0160Y         S0      
317GND              VIA   -    MD0080PA00X+065079Y+110886X0160Y         S0      
317GND              VIA   -    MD0080PA00X+065453Y+110886X0160Y         S0      
317GND              VIA   -    MD0080PA00X+065827Y+110886X0160Y         S0      
317GND              VIA   -    MD0080PA00X+066201Y+110886X0160Y         S0      
317GND              VIA   -    MD0080PA00X+066575Y+110886X0160Y         S0      
317GND              VIA   -    MD0080PA00X+066949Y+110886X0160Y         S0      
317GND              VIA   -    MD0080PA00X+067323Y+110886X0160Y         S0      
317GND              VIA   -    MD0080PA00X+067697Y+110886X0160Y         S0      
317GND              VIA   -    MD0080PA00X+068071Y+110886X0160Y         S0      
317GND              VIA   -    MD0080PA00X+068445Y+110886X0160Y         S0      
317GND              VIA   -    MD0080PA00X+068819Y+110886X0160Y         S0      
317GND              VIA   -    MD0080PA00X+069193Y+110886X0160Y         S0      
317GND              VIA   -    MD0080PA00X+069567Y+110886X0160Y         S0      
317GND              VIA   -    MD0080PA00X+069941Y+110886X0160Y         S0      
317GND              VIA   -    MD0080PA00X+070315Y+110886X0160Y         S0      
317GND              VIA   -    MD0080PA00X+070689Y+110886X0160Y         S0      
317GND              VIA   -    MD0080PA00X+071063Y+110886X0160Y         S0      
317GND              VIA   -    MD0080PA00X+071437Y+110886X0160Y         S0      
317GND              VIA   -    MD0080PA00X+071811Y+110886X0160Y         S0      
317GND              VIA   -    MD0080PA00X+072185Y+110886X0160Y         S0      
317GND              VIA   -    MD0080PA00X+072559Y+110886X0160Y         S0      
317GND              VIA   -    MD0080PA00X+072933Y+110886X0160Y         S0      
317GND              VIA   -    MD0080PA00X+073307Y+110886X0160Y         S0      
317GND              VIA   -    MD0080PA00X+073681Y+110886X0160Y         S0      
317GND              VIA   -    MD0080PA00X+074055Y+110886X0160Y         S0      
317GND              VIA   -    MD0080PA00X+074429Y+110886X0160Y         S0      
317GND              VIA   -    MD0080PA00X+074803Y+110886X0160Y         S0      
317GND              VIA   -    MD0080PA00X+074803Y+111260X0160Y         S0      
317GND              VIA   -    MD0080PA00X+074803Y+111634X0160Y         S0      
317GND              VIA   -    MD0080PA00X+074803Y+112008X0160Y         S0      
317GND              VIA   -    MD0080PA00X+074803Y+112382X0160Y         S0      
317GND              VIA   -    MD0080PA00X+074803Y+112756X0160Y         S0      
317GND              VIA   -    MD0080PA00X+074803Y+113130X0160Y         S0      
317GND              VIA   -    MD0080PA00X+074803Y+113504X0160Y         S0      
317GND              VIA   -    MD0080PA00X+074803Y+113878X0160Y         S0      
327GND              PEX0  -R12        A01X+018622Y+120236X0180Y         S1      
317GND              VIA   -    MD0080PA00X+019744Y+120984X0160Y         S0      
317GND              VIA   -    MD0080PA00X+018622Y+121358X0160Y         S0      
317GND              VIA   -    MD0080PA00X+018622Y+120984X0160Y         S0      
317GND              VIA   -    MD0080PA00X+018622Y+120610X0160Y         S0      
317GND              VIA   -    MD0080PA00X+018622Y+119862X0160Y         S0      
317GND              VIA   -    MD0080PA00X+018248Y+121732X0160Y         S0      
317GND              VIA   -    MD0080PA00X+018248Y+121358X0160Y         S0      
317GND              VIA   -    MD0080PA00X+018248Y+120984X0160Y         S0      
317GND              VIA   -    MD0080PA00X+018248Y+120610X0160Y         S0      
317GND              VIA   -    MD0080PA00X+018248Y+120236X0160Y         S0      
317GND              VIA   -    MD0080PA00X+018248Y+119862X0160Y         S0      
317GND              VIA   -    MD0080PA00X+018248Y+119114X0160Y         S0      
317GND              VIA   -    MD0080PA00X+018248Y+118740X0160Y         S0      
317GND              VIA   -    MD0080PA00X+029094Y+113878X0160Y         S0      
317GND              VIA   -    MD0080PA00X+029094Y+121732X0160Y         S0      
317GND              VIA   -    MD0080PA00X+029094Y+121358X0160Y         S0      
317GND              VIA   -    MD0080PA00X+029094Y+120984X0160Y         S0      
317GND              VIA   -    MD0080PA00X+029094Y+120610X0160Y         S0      
317GND              VIA   -    MD0080PA00X+029094Y+120236X0160Y         S0      
317GND              VIA   -    MD0080PA00X+029094Y+119862X0160Y         S0      
317GND              VIA   -    MD0080PA00X+029094Y+119488X0160Y         S0      
317GND              VIA   -    MD0080PA00X+029094Y+113504X0160Y         S0      
317GND              VIA   -    MD0080PA00X+029094Y+113130X0160Y         S0      
317GND              VIA   -    MD0080PA00X+029094Y+112756X0160Y         S0      
317GND              VIA   -    MD0080PA00X+029094Y+112382X0160Y         S0      
317GND              VIA   -    MD0080PA00X+029094Y+112008X0160Y         S0      
317GND              VIA   -    MD0080PA00X+029094Y+111634X0160Y         S0      
317GND              VIA   -    MD0080PA00X+029094Y+111260X0160Y         S0      
317GND              VIA   -    MD0080PA00X+029468Y+110886X0160Y         S0      
317GND              VIA   -    MD0080PA00X+029094Y+110886X0160Y         S0      
317GND              VIA   -    MD0080PA00X+028720Y+110886X0160Y         S0      
317GND              VIA   -    MD0080PA00X+028346Y+110886X0160Y         S0      
317GND              VIA   -    MD0080PA00X+027972Y+110886X0160Y         S0      
317GND              VIA   -    MD0080PA00X+027598Y+110886X0160Y         S0      
317GND              VIA   -    MD0080PA00X+027224Y+110886X0160Y         S0      
317GND              VIA   -    MD0080PA00X+026850Y+110886X0160Y         S0      
317GND              VIA   -    MD0080PA00X+026476Y+110886X0160Y         S0      
317GND              VIA   -    MD0080PA00X+026102Y+110886X0160Y         S0      
317GND              VIA   -    MD0080PA00X+025728Y+110886X0160Y         S0      
317GND              VIA   -    MD0080PA00X+025354Y+110886X0160Y         S0      
317GND              VIA   -    MD0080PA00X+024980Y+110886X0160Y         S0      
317GND              VIA   -    MD0080PA00X+024606Y+110886X0160Y         S0      
317GND              VIA   -    MD0080PA00X+024232Y+110886X0160Y         S0      
317GND              VIA   -    MD0080PA00X+023858Y+110886X0160Y         S0      
317GND              VIA   -    MD0080PA00X+023484Y+110886X0160Y         S0      
317GND              VIA   -    MD0080PA00X+023110Y+110886X0160Y         S0      
317GND              VIA   -    MD0080PA00X+022736Y+110886X0160Y         S0      
317GND              VIA   -    MD0080PA00X+022362Y+110886X0160Y         S0      
317GND              VIA   -    MD0080PA00X+021988Y+110886X0160Y         S0      
317GND              VIA   -    MD0080PA00X+021614Y+110886X0160Y         S0      
317GND              VIA   -    MD0080PA00X+021240Y+110886X0160Y         S0      
317GND              VIA   -    MD0080PA00X+020866Y+110886X0160Y         S0      
317GND              VIA   -    MD0080PA00X+020492Y+110886X0160Y         S0      
317GND              VIA   -    MD0080PA00X+020118Y+110886X0160Y         S0      
317GND              VIA   -    MD0080PA00X+019744Y+110886X0160Y         S0      
317GND              VIA   -    MD0080PA00X+019370Y+110886X0160Y         S0      
317GND              VIA   -    MD0080PA00X+018996Y+110886X0160Y         S0      
317GND              VIA   -    MD0080PA00X+018622Y+110886X0160Y         S0      
317GND              VIA   -    MD0080PA00X+018248Y+110886X0160Y         S0      
327GND              R1256 -2          A18X+022395Y+121703X0198Y0197R270 S2      
317GND              VIA   -    MD0080PA00X+017874Y+121732X0160Y         S0      
327GND              PEX0  -K15        A01X+019744Y+122106X0180Y         S1      
317GND              VIA   -    MD0080PA00X+019744Y+122106X0160Y         S0      
327GND              PEX0  -K16        A01X+020118Y+122106X0180Y         S1      
317GND              VIA   -    MD0080PA00X+020118Y+122106X0160Y         S0      
327GND              PEX0  -K17        A01X+020492Y+122106X0180Y         S1      
317GND              VIA   -    MD0080PA00X+020492Y+122106X0160Y         S0      
327GND              PEX0  -K18        A01X+020866Y+122106X0180Y         S1      
317GND              VIA   -    MD0080PA00X+020866Y+122106X0160Y         S0      
327GND              PEX0  -K19        A01X+021240Y+122106X0180Y         S1      
317GND              VIA   -    MD0080PA00X+021240Y+122106X0160Y         S0      
327GND              PEX0  -K20        A01X+021614Y+122106X0180Y         S1      
317GND              VIA   -    MD0080PA00X+021614Y+122106X0160Y         S0      
327GND              PEX0  -K21        A01X+021988Y+122106X0180Y         S1      
317GND              VIA   -    MD0080PA00X+021988Y+122106X0160Y         S0      
327GND              PEX0  -K22        A01X+022362Y+122106X0180Y         S1      
317GND              VIA   -    MD0080PA00X+022362Y+122106X0160Y         S0      
327GND              PEX0  -L21        A01X+021988Y+121732X0180Y         S1      
317GND              VIA   -    MD0080PA00X+021988Y+121732X0160Y         S0      
327GND              PEX0  -K23        A01X+022736Y+122106X0180Y         S1      
317GND              VIA   -    MD0080PA00X+022736Y+122106X0160Y         S0      
327GND              PEX0  -K24        A01X+023110Y+122106X0180Y         S1      
317GND              VIA   -    MD0080PA00X+023110Y+122106X0160Y         S0      
327GND              PEX0  -K34        A01X+026850Y+122106X0180Y         S1      
317GND              VIA   -    MD0080PA00X+026850Y+122106X0160Y         S0      
327GND              PEX0  -K35        A01X+027224Y+122106X0180Y         S1      
317GND              VIA   -    MD0080PA00X+027224Y+122106X0160Y         S0      
327GND              PEX0  -K36        A01X+027598Y+122106X0180Y         S1      
317GND              VIA   -    MD0080PA00X+027598Y+122106X0160Y         S0      
327GND              PEX0  -K37        A01X+027972Y+122106X0180Y         S1      
317GND              VIA   -    MD0080PA00X+027972Y+122106X0160Y         S0      
327GND              PEX0  -K38        A01X+028346Y+122106X0180Y         S1      
317GND              VIA   -    MD0080PA00X+028346Y+122106X0160Y         S0      
327GND              PEX0  -K39        A01X+028720Y+122106X0180Y         S1      
317GND              VIA   -    MD0080PA00X+028720Y+122106X0160Y         S0      
327GND              PEX0  -K40        A01X+029094Y+122106X0180Y         S1      
317GND              VIA   -    MD0080PA00X+029094Y+122106X0160Y         S0      
317GND              VIA   -    MD0080PA00X+019370Y+122106X0160Y         S0      
317GND              VIA   -    MD0080PA00X+018996Y+122106X0160Y         S0      
317GND              VIA   -    MD0080PA00X+018622Y+122106X0160Y         S0      
317GND              VIA   -    MD0080PA00X+018248Y+122106X0160Y         S0      
317GND              VIA   -    MD0080PA00X+017874Y+122106X0160Y         S0      
317GND              VIA   -    MD0080PA00X+017874Y+121358X0160Y         S0      
317GND              VIA   -    MD0080PA00X+017874Y+120984X0160Y         S0      
317GND              VIA   -    MD0080PA00X+017874Y+120236X0160Y         S0      
317GND              VIA   -    MD0080PA00X+017874Y+120610X0160Y         S0      
317GND              VIA   -    MD0080PA00X+017874Y+119862X0160Y         S0      
317GND              VIA   -    MD0080PA00X+017874Y+119488X0160Y         S0      
317GND              VIA   -    MD0080PA00X+017874Y+119114X0160Y         S0      
317GND              VIA   -    MD0080PA00X+017874Y+118740X0160Y         S0      
317GND              VIA   -    MD0080PA00X+016752Y+118366X0160Y         S0      
317GND              VIA   -    MD0080PA00X+016378Y+118366X0160Y         S0      
317GND              VIA   -    MD0080PA00X+016004Y+118366X0160Y         S0      
327GND              PEX2  -AY41       A01X+120886Y+110886X0180Y         S1      
317GND              VIA   -    MD0080PA00X+120886Y+110886X0160Y         S0      
327GND              PEX2  -AW42       A01X+121260Y+111260X0180Y         S1      
327GND              PEX1  -AW42       A01X+075551Y+111260X0180Y         S1      
317GND              VIA   -    MD0080PA00X+060965Y+125846X0160Y         S0      
317GND              VIA   -    MD0080PA00X+061713Y+125846X0160Y         S0      
317GND              VIA   -    MD0080PA00X+062461Y+125846X0160Y         S0      
317GND              VIA   -    MD0080PA00X+063209Y+125846X0160Y         S0      
317GND              VIA   -    MD0080PA00X+063957Y+125846X0160Y         S0      
317GND              VIA   -    MD0080PA00X+064705Y+125846X0160Y         S0      
317GND              VIA   -    MD0080PA00X+065453Y+125846X0160Y         S0      
317GND              VIA   -    MD0080PA00X+066949Y+125846X0160Y         S0      
317GND              VIA   -    MD0080PA00X+066201Y+125846X0160Y         S0      
317GND              VIA   -    MD0080PA00X+067697Y+125846X0160Y         S0      
317GND              VIA   -    MD0080PA00X+068445Y+125846X0160Y         S0      
317GND              VIA   -    MD0080PA00X+069193Y+125846X0160Y         S0      
317GND              VIA   -    MD0080PA00X+069941Y+125846X0160Y         S0      
317GND              VIA   -    MD0080PA00X+070689Y+125846X0160Y         S0      
317GND              VIA   -    MD0080PA00X+071437Y+125846X0160Y         S0      
317GND              VIA   -    MD0080PA00X+072185Y+125846X0160Y         S0      
317GND              VIA   -    MD0080PA00X+072933Y+125846X0160Y         S0      
317GND              VIA   -    MD0080PA00X+073681Y+125846X0160Y         S0      
317GND              VIA   -    MD0080PA00X+074429Y+125846X0160Y         S0      
317GND              VIA   -    MD0080PA00X+075177Y+125846X0160Y         S0      
317GND              VIA   -    MD0080PA00X+075925Y+125846X0160Y         S0      
317GND              VIA   -    MD0080PA00X+076673Y+125846X0160Y         S0      
317GND              VIA   -    MD0080PA00X+077421Y+125846X0160Y         S0      
317GND              VIA   -    MD0080PA00X+078543Y+119862X0160Y         S0      
317GND              VIA   -    MD0080PA00X+078543Y+120610X0160Y         S0      
317GND              VIA   -    MD0080PA00X+078543Y+121358X0160Y         S0      
317GND              VIA   -    MD0080PA00X+078543Y+122106X0160Y         S0      
317GND              VIA   -    MD0080PA00X+078543Y+122854X0160Y         S0      
317GND              VIA   -    MD0080PA00X+078543Y+123976X0160Y         S0      
317GND              VIA   -    MD0080PA00X+078543Y+124724X0160Y         S0      
317GND              VIA   -    MD0080PA00X+059842Y+119114X0160Y         S0      
317GND              VIA   -    MD0080PA00X+059842Y+119862X0160Y         S0      
317GND              VIA   -    MD0080PA00X+059842Y+120610X0160Y         S0      
317GND              VIA   -    MD0080PA00X+059842Y+121358X0160Y         S0      
317GND              VIA   -    MD0080PA00X+059842Y+122106X0160Y         S0      
317GND              VIA   -    MD0080PA00X+059842Y+122854X0160Y    R090 S0      
317GND              VIA   -    MD0080PA00X+059842Y+124724X0160Y    R090 S0      
317GND              VIA   -    MD0080PA00X+059842Y+123976X0160Y    R090 S0      
317GND              VIA   -    MD0080PA00X+063208Y+107146X0160Y         S0      
317GND              VIA   -    MD0080PA00X+063957Y+107146X0160Y         S0      
317GND              VIA   -    MD0080PA00X+064705Y+107146X0160Y         S0      
317GND              VIA   -    MD0080PA00X+065453Y+107146X0160Y         S0      
317GND              VIA   -    MD0080PA00X+066201Y+107146X0160Y         S0      
317GND              VIA   -    MD0080PA00X+066949Y+107146X0160Y         S0      
317GND              VIA   -    MD0080PA00X+067697Y+107146X0160Y         S0      
317GND              VIA   -    MD0080PA00X+068445Y+107146X0160Y         S0      
317GND              VIA   -    MD0080PA00X+069193Y+107145X0160Y         S0      
317GND              VIA   -    MD0080PA00X+069941Y+107146X0160Y         S0      
317GND              VIA   -    MD0080PA00X+070689Y+107146X0160Y         S0      
317GND              VIA   -    MD0080PA00X+071437Y+107146X0160Y         S0      
317GND              VIA   -    MD0080PA00X+072185Y+107146X0160Y         S0      
317GND              VIA   -    MD0080PA00X+072933Y+107146X0160Y         S0      
317GND              VIA   -    MD0080PA00X+073681Y+107146X0160Y         S0      
317GND              VIA   -    MD0080PA00X+074429Y+107146X0160Y         S0      
317GND              VIA   -    MD0080PA00X+075177Y+107146X0160Y         S0      
317GND              VIA   -    MD0080PA00X+075925Y+107146X0160Y         S0      
317GND              VIA   -    MD0080PA00X+076673Y+107146X0160Y         S0      
317GND              VIA   -    MD0080PA00X+077421Y+107146X0160Y         S0      
317GND              VIA   -    MD0080PA00X+078543Y+108268X0160Y         S0      
317GND              VIA   -    MD0080PA00X+078543Y+109016X0160Y         S0      
317GND              VIA   -    MD0080PA00X+078543Y+110138X0160Y         S0      
317GND              VIA   -    MD0080PA00X+078543Y+110886X0160Y         S0      
317GND              VIA   -    MD0080PA00X+078543Y+111634X0160Y         S0      
317GND              VIA   -    MD0080PA00X+078543Y+112382X0160Y         S0      
317GND              VIA   -    MD0080PA00X+078543Y+113130X0160Y         S0      
317GND              VIA   -    MD0080PA00X+106673Y+125846X0160Y         S0      
317GND              VIA   -    MD0080PA00X+107421Y+125846X0160Y         S0      
317GND              VIA   -    MD0080PA00X+108169Y+125846X0160Y         S0      
317GND              VIA   -    MD0080PA00X+108917Y+125846X0160Y         S0      
317GND              VIA   -    MD0080PA00X+109665Y+125846X0160Y         S0      
317GND              VIA   -    MD0080PA00X+110413Y+125846X0160Y         S0      
317GND              VIA   -    MD0080PA00X+111161Y+125846X0160Y         S0      
317GND              VIA   -    MD0080PA00X+112657Y+125846X0160Y         S0      
317GND              VIA   -    MD0080PA00X+111909Y+125846X0160Y         S0      
317GND              VIA   -    MD0080PA00X+113406Y+125846X0160Y         S0      
317GND              VIA   -    MD0080PA00X+114154Y+125846X0160Y         S0      
317GND              VIA   -    MD0080PA00X+114902Y+125846X0160Y         S0      
317GND              VIA   -    MD0080PA00X+115650Y+125846X0160Y         S0      
317GND              VIA   -    MD0080PA00X+116398Y+125846X0160Y         S0      
317GND              VIA   -    MD0080PA00X+117146Y+125846X0160Y         S0      
317GND              VIA   -    MD0080PA00X+117894Y+125846X0160Y         S0      
317GND              VIA   -    MD0080PA00X+118642Y+125846X0160Y         S0      
317GND              VIA   -    MD0080PA00X+119390Y+125846X0160Y         S0      
317GND              VIA   -    MD0080PA00X+120138Y+125846X0160Y         S0      
317GND              VIA   -    MD0080PA00X+120886Y+125846X0160Y         S0      
317GND              VIA   -    MD0080PA00X+121634Y+125846X0160Y         S0      
317GND              VIA   -    MD0080PA00X+122382Y+125846X0160Y         S0      
317GND              VIA   -    MD0080PA00X+123130Y+125846X0160Y         S0      
317GND              VIA   -    MD0080PA00X+124252Y+119862X0160Y         S0      
317GND              VIA   -    MD0080PA00X+124252Y+120610X0160Y         S0      
317GND              VIA   -    MD0080PA00X+124252Y+121358X0160Y         S0      
317GND              VIA   -    MD0080PA00X+124252Y+122106X0160Y         S0      
317GND              VIA   -    MD0080PA00X+124252Y+122854X0160Y         S0      
317GND              VIA   -    MD0080PA00X+124252Y+123976X0160Y         S0      
317GND              VIA   -    MD0080PA00X+124252Y+124724X0160Y         S0      
317GND              VIA   -    MD0080PA00X+105551Y+119114X0160Y         S0      
317GND              VIA   -    MD0080PA00X+105551Y+119862X0160Y         S0      
317GND              VIA   -    MD0080PA00X+105551Y+120610X0160Y         S0      
317GND              VIA   -    MD0080PA00X+105551Y+121358X0160Y         S0      
317GND              VIA   -    MD0080PA00X+105551Y+122106X0160Y         S0      
317GND              VIA   -    MD0080PA00X+105551Y+122854X0160Y    R090 S0      
317GND              VIA   -    MD0080PA00X+105551Y+124724X0160Y    R090 S0      
317GND              VIA   -    MD0080PA00X+105551Y+123976X0160Y    R090 S0      
317GND              VIA   -    MD0080PA00X+108917Y+107146X0160Y         S0      
317GND              VIA   -    MD0080PA00X+109665Y+107146X0160Y         S0      
317GND              VIA   -    MD0080PA00X+110413Y+107146X0160Y         S0      
317GND              VIA   -    MD0080PA00X+111161Y+107146X0160Y         S0      
317GND              VIA   -    MD0080PA00X+111909Y+107146X0160Y         S0      
317GND              VIA   -    MD0080PA00X+112657Y+107146X0160Y         S0      
317GND              VIA   -    MD0080PA00X+113405Y+107146X0160Y         S0      
317GND              VIA   -    MD0080PA00X+114153Y+107146X0160Y         S0      
317GND              VIA   -    MD0080PA00X+114901Y+107145X0160Y         S0      
317GND              VIA   -    MD0080PA00X+115649Y+107146X0160Y         S0      
317GND              VIA   -    MD0080PA00X+116398Y+107146X0160Y         S0      
317GND              VIA   -    MD0080PA00X+117146Y+107146X0160Y         S0      
317GND              VIA   -    MD0080PA00X+117894Y+107146X0160Y         S0      
317GND              VIA   -    MD0080PA00X+118642Y+107146X0160Y         S0      
317GND              VIA   -    MD0080PA00X+119390Y+107146X0160Y         S0      
317GND              VIA   -    MD0080PA00X+120138Y+107146X0160Y         S0      
317GND              VIA   -    MD0080PA00X+120886Y+107146X0160Y         S0      
317GND              VIA   -    MD0080PA00X+121634Y+107146X0160Y         S0      
317GND              VIA   -    MD0080PA00X+122382Y+107146X0160Y         S0      
317GND              VIA   -    MD0080PA00X+123130Y+107146X0160Y         S0      
317GND              VIA   -    MD0080PA00X+124252Y+108268X0160Y         S0      
317GND              VIA   -    MD0080PA00X+124252Y+109016X0160Y         S0      
317GND              VIA   -    MD0080PA00X+124252Y+110138X0160Y         S0      
317GND              VIA   -    MD0080PA00X+124252Y+110886X0160Y         S0      
317GND              VIA   -    MD0080PA00X+124252Y+111634X0160Y         S0      
317GND              VIA   -    MD0080PA00X+124252Y+112382X0160Y         S0      
317GND              VIA   -    MD0080PA00X+124252Y+113130X0160Y         S0      
317GND              VIA   -    MD0080PA00X+152382Y+125846X0160Y         S0      
317GND              VIA   -    MD0080PA00X+153130Y+125846X0160Y         S0      
317GND              VIA   -    MD0080PA00X+153878Y+125846X0160Y         S0      
317GND              VIA   -    MD0080PA00X+154626Y+125846X0160Y         S0      
317GND              VIA   -    MD0080PA00X+155374Y+125846X0160Y         S0      
317GND              VIA   -    MD0080PA00X+156122Y+125846X0160Y         S0      
317GND              VIA   -    MD0080PA00X+156870Y+125846X0160Y         S0      
317GND              VIA   -    MD0080PA00X+158366Y+125846X0160Y         S0      
317GND              VIA   -    MD0080PA00X+157618Y+125846X0160Y         S0      
317GND              VIA   -    MD0080PA00X+159114Y+125846X0160Y         S0      
317GND              VIA   -    MD0080PA00X+159862Y+125846X0160Y         S0      
317GND              VIA   -    MD0080PA00X+160610Y+125846X0160Y         S0      
317GND              VIA   -    MD0080PA00X+161358Y+125846X0160Y         S0      
317GND              VIA   -    MD0080PA00X+162106Y+125846X0160Y         S0      
317GND              VIA   -    MD0080PA00X+162854Y+125846X0160Y         S0      
317GND              VIA   -    MD0080PA00X+163602Y+125846X0160Y         S0      
317GND              VIA   -    MD0080PA00X+164350Y+125846X0160Y         S0      
317GND              VIA   -    MD0080PA00X+165098Y+125846X0160Y         S0      
317GND              VIA   -    MD0080PA00X+165846Y+125846X0160Y         S0      
317GND              VIA   -    MD0080PA00X+166594Y+125846X0160Y         S0      
317GND              VIA   -    MD0080PA00X+167342Y+125846X0160Y         S0      
317GND              VIA   -    MD0080PA00X+168090Y+125846X0160Y         S0      
317GND              VIA   -    MD0080PA00X+168838Y+125846X0160Y         S0      
317GND              VIA   -    MD0080PA00X+169961Y+119862X0160Y         S0      
317GND              VIA   -    MD0080PA00X+169961Y+120610X0160Y         S0      
317GND              VIA   -    MD0080PA00X+169961Y+121358X0160Y         S0      
317GND              VIA   -    MD0080PA00X+169961Y+122106X0160Y         S0      
317GND              VIA   -    MD0080PA00X+169961Y+122854X0160Y         S0      
317GND              VIA   -    MD0080PA00X+169961Y+123976X0160Y         S0      
317GND              VIA   -    MD0080PA00X+169961Y+124724X0160Y         S0      
317GND              VIA   -    MD0080PA00X+151260Y+119114X0160Y         S0      
317GND              VIA   -    MD0080PA00X+151260Y+119862X0160Y         S0      
317GND              VIA   -    MD0080PA00X+151260Y+120610X0160Y         S0      
317GND              VIA   -    MD0080PA00X+151260Y+121358X0160Y         S0      
317GND              VIA   -    MD0080PA00X+151260Y+122106X0160Y         S0      
317GND              VIA   -    MD0080PA00X+151260Y+122854X0160Y    R090 S0      
317GND              VIA   -    MD0080PA00X+151260Y+124724X0160Y    R090 S0      
317GND              VIA   -    MD0080PA00X+151260Y+123976X0160Y    R090 S0      
317GND              VIA   -    MD0080PA00X+154626Y+107146X0160Y         S0      
317GND              VIA   -    MD0080PA00X+155374Y+107146X0160Y         S0      
317GND              VIA   -    MD0080PA00X+156122Y+107146X0160Y         S0      
317GND              VIA   -    MD0080PA00X+156870Y+107146X0160Y         S0      
317GND              VIA   -    MD0080PA00X+157618Y+107146X0160Y         S0      
317GND              VIA   -    MD0080PA00X+158366Y+107146X0160Y         S0      
317GND              VIA   -    MD0080PA00X+159114Y+107146X0160Y         S0      
317GND              VIA   -    MD0080PA00X+159862Y+107146X0160Y         S0      
317GND              VIA   -    MD0080PA00X+160610Y+107145X0160Y         S0      
317GND              VIA   -    MD0080PA00X+161358Y+107146X0160Y         S0      
317GND              VIA   -    MD0080PA00X+162106Y+107146X0160Y         S0      
317GND              VIA   -    MD0080PA00X+162854Y+107146X0160Y         S0      
317GND              VIA   -    MD0080PA00X+163602Y+107146X0160Y         S0      
317GND              VIA   -    MD0080PA00X+164350Y+107146X0160Y         S0      
317GND              VIA   -    MD0080PA00X+165098Y+107146X0160Y         S0      
317GND              VIA   -    MD0080PA00X+165846Y+107146X0160Y         S0      
317GND              VIA   -    MD0080PA00X+166594Y+107146X0160Y         S0      
317GND              VIA   -    MD0080PA00X+167342Y+107146X0160Y         S0      
317GND              VIA   -    MD0080PA00X+168090Y+107146X0160Y         S0      
317GND              VIA   -    MD0080PA00X+168838Y+107146X0160Y         S0      
317GND              VIA   -    MD0080PA00X+169961Y+108268X0160Y         S0      
317GND              VIA   -    MD0080PA00X+169961Y+109016X0160Y         S0      
317GND              VIA   -    MD0080PA00X+169961Y+110138X0160Y         S0      
317GND              VIA   -    MD0080PA00X+169961Y+110886X0160Y         S0      
317GND              VIA   -    MD0080PA00X+169961Y+111634X0160Y         S0      
317GND              VIA   -    MD0080PA00X+169961Y+112382X0160Y         S0      
317GND              VIA   -    MD0080PA00X+169961Y+113130X0160Y         S0      
317GND              VIA   -    MD0080PA00X+032835Y+122854X0160Y         S0      
317GND              VIA   -    MD0080PA00X+023858Y+122106X0160Y         S0      
317GND              VIA   -    MD0080PA00X+023484Y+122106X0160Y         S0      
327GND              PEX0  -BF7        A01X+016752Y+108642X0180Y         S1      
317GND              VIA   -    MD0080PA00X+016565Y+108455X0160Y    R180 S0      
317GND              VIA   -    MD0080PA00X+077234Y+118927X0160Y         S0      
317GND              VIA   -    MD0080PA00X+076486Y+118927X0160Y         S0      
327GND              R1323 -2          A18X+068104Y+121703X0198Y0197R270 S2      
327GND              PEX2  -U49        A01X+123878Y+119488X0180Y         S1      
327GND              PEX2  -U48        A01X+123504Y+119488X0180Y         S1      
327GND              PEX1  -AM46       A01X+077047Y+113878X0180Y         S1      
317GND              VIA   -    MD0080PA00X+077047Y+113878X0160Y    R090 S0      
317GND              VIA   -    MD0080PA00X+015630Y+117992X0160Y         S0      
317GND              VIA   -    MD0080PA00X+164724Y+122106X0160Y         S0      
317GND              VIA   -    MD0080PA00X+164350Y+122106X0160Y         S0      
317GND              VIA   -    MD0080PA00X+163976Y+122106X0160Y         S0      
317GND              VIA   -    MD0080PA00X+163602Y+122106X0160Y         S0      
317GND              VIA   -    MD0080PA00X+160236Y+122106X0160Y         S0      
317GND              VIA   -    MD0080PA00X+159488Y+122106X0160Y         S0      
317GND              VIA   -    MD0080PA00X+060965Y+119862X0160Y         S0      
317GND              VIA   -    MD0080PA00X+060965Y+120610X0160Y         S0      
317GND              VIA   -    MD0080PA00X+060216Y+123228X0160Y         S0      
317GND              VIA   -    MD0080PA00X+060216Y+123602X0160Y         S0      
317GND              VIA   -    MD0080PA00X+060216Y+122480X0160Y         S0      
317GND              VIA   -    MD0080PA00X+060216Y+120984X0160Y         S0      
317GND              VIA   -    MD0080PA00X+060590Y+120984X0160Y         S0      
317GND              VIA   -    MD0080PA00X+060216Y+121732X0160Y         S0      
317GND              VIA   -    MD0080PA00X+060590Y+121732X0160Y         S0      
317GND              VIA   -    MD0080PA00X+060590Y+119488X0160Y         S0      
317GND              VIA   -    MD0080PA00X+060216Y+119488X0160Y         S0      
317GND              VIA   -    MD0080PA00X+060590Y+120236X0160Y         S0      
317GND              VIA   -    MD0080PA00X+060216Y+120236X0160Y         S0      
317GND              VIA   -    MD0080PA00X+060590Y+118740X0160Y         S0      
317GND              VIA   -    MD0080PA00X+060216Y+118740X0160Y         S0      
317GND              VIA   -    MD0080PA00X+060216Y+118366X0160Y         S0      
317GND              VIA   -    MD0080PA00X+060590Y+118366X0160Y         S0      
317GND              VIA   -    MD0080PA00X+074055Y+125098X0160Y    R180 S0      
317GND              VIA   -    MD0080PA00X+074055Y+125472X0160Y    R180 S0      
317GND              VIA   -    MD0080PA00X+074429Y+124724X0160Y    R180 S0      
317GND              VIA   -    MD0080PA00X+074803Y+125098X0160Y    R180 S0      
317GND              VIA   -    MD0080PA00X+074803Y+125472X0160Y    R180 S0      
317GND              VIA   -    MD0080PA00X+074055Y+123976X0160Y         S0      
317GND              VIA   -    MD0080PA00X+074429Y+123976X0160Y    R180 S0      
317GND              VIA   -    MD0080PA00X+074429Y+124350X0160Y    R180 S0      
317GND              VIA   -    MD0080PA00X+074803Y+123976X0160Y         S0      
317GND              VIA   -    MD0080PA00X+074055Y+123228X0160Y         S0      
317GND              VIA   -    MD0080PA00X+074429Y+122854X0160Y         S0      
317GND              VIA   -    MD0080PA00X+074055Y+123602X0160Y         S0      
317GND              VIA   -    MD0080PA00X+074803Y+123228X0160Y         S0      
317GND              VIA   -    MD0080PA00X+074803Y+123602X0160Y         S0      
317GND              VIA   -    MD0080PA00X+072185Y+124724X0160Y    R180 S0      
317GND              VIA   -    MD0080PA00X+072559Y+125098X0160Y    R180 S0      
317GND              VIA   -    MD0080PA00X+072559Y+125472X0160Y    R180 S0      
317GND              VIA   -    MD0080PA00X+073307Y+125472X0160Y    R180 S0      
317GND              VIA   -    MD0080PA00X+073307Y+125098X0160Y    R180 S0      
317GND              VIA   -    MD0080PA00X+072933Y+124724X0160Y    R180 S0      
317GND              VIA   -    MD0080PA00X+073681Y+124724X0160Y    R180 S0      
317GND              VIA   -    MD0080PA00X+072185Y+123976X0160Y    R270 S0      
317GND              VIA   -    MD0080PA00X+072933Y+123976X0160Y    R180 S0      
317GND              VIA   -    MD0080PA00X+072559Y+123976X0160Y         S0      
317GND              VIA   -    MD0080PA00X+072185Y+124350X0160Y    R180 S0      
317GND              VIA   -    MD0080PA00X+072933Y+124350X0160Y    R180 S0      
317GND              VIA   -    MD0080PA00X+073307Y+123976X0160Y    R270 S0      
317GND              VIA   -    MD0080PA00X+073681Y+123976X0160Y    R270 S0      
317GND              VIA   -    MD0080PA00X+073681Y+124350X0160Y    R180 S0      
317GND              VIA   -    MD0080PA00X+072185Y+122854X0160Y         S0      
317GND              VIA   -    MD0080PA00X+072185Y+122480X0160Y         S0      
317GND              VIA   -    MD0080PA00X+072559Y+123228X0160Y         S0      
317GND              VIA   -    MD0080PA00X+072559Y+123602X0160Y         S0      
317GND              VIA   -    MD0080PA00X+073307Y+123228X0160Y         S0      
317GND              VIA   -    MD0080PA00X+073307Y+123602X0160Y         S0      
317GND              VIA   -    MD0080PA00X+072933Y+122854X0160Y         S0      
317GND              VIA   -    MD0080PA00X+072933Y+122480X0160Y         S0      
317GND              VIA   -    MD0080PA00X+073681Y+122854X0160Y         S0      
317GND              VIA   -    MD0080PA00X+073681Y+122480X0160Y         S0      
317GND              VIA   -    MD0080PA00X+071811Y+125472X0160Y    R180 S0      
317GND              VIA   -    MD0080PA00X+070689Y+123976X0160Y    R180 S0      
317GND              VIA   -    MD0080PA00X+070689Y+124350X0160Y    R270 S0      
317GND              VIA   -    MD0080PA00X+070689Y+124724X0160Y    R180 S0      
317GND              VIA   -    MD0080PA00X+071063Y+123976X0160Y    R180 S0      
317GND              VIA   -    MD0080PA00X+071063Y+125098X0160Y    R180 S0      
317GND              VIA   -    MD0080PA00X+071063Y+125472X0160Y    R180 S0      
317GND              VIA   -    MD0080PA00X+071437Y+124724X0160Y    R180 S0      
317GND              VIA   -    MD0080PA00X+071437Y+124350X0160Y    R270 S0      
317GND              VIA   -    MD0080PA00X+071811Y+123976X0160Y    R180 S0      
317GND              VIA   -    MD0080PA00X+071811Y+125098X0160Y    R180 S0      
317GND              VIA   -    MD0080PA00X+071437Y+123976X0160Y         S0      
317GND              VIA   -    MD0080PA00X+070689Y+122854X0160Y         S0      
317GND              VIA   -    MD0080PA00X+070689Y+122480X0160Y         S0      
317GND              VIA   -    MD0080PA00X+071437Y+122854X0160Y         S0      
317GND              VIA   -    MD0080PA00X+071437Y+122480X0160Y         S0      
317GND              VIA   -    MD0080PA00X+071063Y+123228X0160Y         S0      
317GND              VIA   -    MD0080PA00X+071811Y+123228X0160Y         S0      
317GND              VIA   -    MD0080PA00X+071811Y+123602X0160Y         S0      
317GND              VIA   -    MD0080PA00X+071063Y+123602X0160Y         S0      
317GND              VIA   -    MD0080PA00X+069567Y+125472X0160Y    R180 S0      
317GND              VIA   -    MD0080PA00X+069567Y+125098X0160Y    R180 S0      
317GND              VIA   -    MD0080PA00X+069193Y+124724X0160Y    R180 S0      
317GND              VIA   -    MD0080PA00X+069193Y+124350X0160Y    R270 S0      
317GND              VIA   -    MD0080PA00X+069193Y+123976X0160Y    R270 S0      
317GND              VIA   -    MD0080PA00X+069567Y+123976X0160Y         S0      
317GND              VIA   -    MD0080PA00X+070315Y+123976X0160Y         S0      
317GND              VIA   -    MD0080PA00X+069941Y+123976X0160Y    R270 S0      
317GND              VIA   -    MD0080PA00X+069941Y+124350X0160Y    R180 S0      
317GND              VIA   -    MD0080PA00X+069941Y+124724X0160Y    R180 S0      
317GND              VIA   -    MD0080PA00X+070315Y+125098X0160Y    R180 S0      
317GND              VIA   -    MD0080PA00X+070315Y+125472X0160Y    R180 S0      
317GND              VIA   -    MD0080PA00X+069567Y+123228X0160Y         S0      
317GND              VIA   -    MD0080PA00X+069567Y+123602X0160Y         S0      
317GND              VIA   -    MD0080PA00X+069941Y+122854X0160Y         S0      
317GND              VIA   -    MD0080PA00X+069941Y+122480X0160Y         S0      
317GND              VIA   -    MD0080PA00X+070315Y+123228X0160Y         S0      
317GND              VIA   -    MD0080PA00X+070315Y+123602X0160Y         S0      
317GND              VIA   -    MD0080PA00X+069193Y+122854X0160Y         S0      
317GND              VIA   -    MD0080PA00X+069193Y+122480X0160Y         S0      
317GND              VIA   -    MD0080PA00X+068819Y+123976X0160Y         S0      
317GND              VIA   -    MD0080PA00X+068445Y+123976X0160Y    R270 S0      
317GND              VIA   -    MD0080PA00X+068445Y+124350X0160Y         S0      
317GND              VIA   -    MD0080PA00X+068445Y+124724X0160Y    R270 S0      
317GND              VIA   -    MD0080PA00X+068819Y+125098X0160Y    R270 S0      
317GND              VIA   -    MD0080PA00X+068819Y+125472X0160Y    R270 S0      
317GND              VIA   -    MD0080PA00X+067323Y+125098X0160Y    R270 S0      
317GND              VIA   -    MD0080PA00X+067323Y+125472X0160Y    R270 S0      
317GND              VIA   -    MD0080PA00X+067697Y+124724X0160Y    R270 S0      
317GND              VIA   -    MD0080PA00X+067697Y+124350X0160Y         S0      
317GND              VIA   -    MD0080PA00X+068071Y+125098X0160Y    R270 S0      
317GND              VIA   -    MD0080PA00X+068071Y+125472X0160Y    R270 S0      
317GND              VIA   -    MD0080PA00X+068071Y+123976X0160Y         S0      
317GND              VIA   -    MD0080PA00X+067697Y+123976X0160Y    R270 S0      
317GND              VIA   -    MD0080PA00X+067323Y+123976X0160Y         S0      
317GND              VIA   -    MD0080PA00X+068819Y+123228X0160Y         S0      
317GND              VIA   -    MD0080PA00X+068819Y+123602X0160Y         S0      
317GND              VIA   -    MD0080PA00X+068445Y+122854X0160Y    R090 S0      
317GND              VIA   -    MD0080PA00X+068445Y+122480X0160Y         S0      
317GND              VIA   -    MD0080PA00X+068071Y+123228X0160Y         S0      
317GND              VIA   -    MD0080PA00X+068071Y+123602X0160Y         S0      
317GND              VIA   -    MD0080PA00X+067697Y+122854X0160Y    R090 S0      
317GND              VIA   -    MD0080PA00X+067697Y+122480X0160Y         S0      
317GND              VIA   -    MD0080PA00X+067323Y+123228X0160Y         S0      
317GND              VIA   -    MD0080PA00X+067323Y+123602X0160Y         S0      
317GND              VIA   -    MD0080PA00X+065827Y+125098X0160Y    R270 S0      
317GND              VIA   -    MD0080PA00X+065827Y+125472X0160Y    R270 S0      
317GND              VIA   -    MD0080PA00X+066201Y+124724X0160Y    R270 S0      
317GND              VIA   -    MD0080PA00X+066201Y+124350X0160Y         S0      
317GND              VIA   -    MD0080PA00X+066949Y+124350X0160Y         S0      
317GND              VIA   -    MD0080PA00X+066949Y+124724X0160Y    R270 S0      
317GND              VIA   -    MD0080PA00X+066575Y+125472X0160Y    R270 S0      
317GND              VIA   -    MD0080PA00X+066575Y+125098X0160Y    R270 S0      
317GND              VIA   -    MD0080PA00X+066575Y+123976X0160Y         S0      
317GND              VIA   -    MD0080PA00X+066949Y+123976X0160Y    R270 S0      
317GND              VIA   -    MD0080PA00X+065827Y+123976X0160Y    R270 S0      
317GND              VIA   -    MD0080PA00X+066201Y+123976X0160Y    R270 S0      
317GND              VIA   -    MD0080PA00X+066949Y+122480X0160Y         S0      
317GND              VIA   -    MD0080PA00X+066949Y+122854X0160Y    R090 S0      
317GND              VIA   -    MD0080PA00X+066575Y+123228X0160Y         S0      
317GND              VIA   -    MD0080PA00X+066575Y+123602X0160Y         S0      
317GND              VIA   -    MD0080PA00X+066201Y+122480X0160Y         S0      
317GND              VIA   -    MD0080PA00X+066201Y+122854X0160Y    R090 S0      
317GND              VIA   -    MD0080PA00X+065827Y+123228X0160Y         S0      
317GND              VIA   -    MD0080PA00X+065827Y+123602X0160Y         S0      
317GND              VIA   -    MD0080PA00X+064331Y+125098X0160Y    R270 S0      
317GND              VIA   -    MD0080PA00X+064331Y+125472X0160Y    R270 S0      
317GND              VIA   -    MD0080PA00X+064705Y+124724X0160Y    R270 S0      
317GND              VIA   -    MD0080PA00X+065079Y+125098X0160Y    R270 S0      
317GND              VIA   -    MD0080PA00X+065079Y+125472X0160Y    R270 S0      
317GND              VIA   -    MD0080PA00X+065453Y+124724X0160Y    R270 S0      
317GND              VIA   -    MD0080PA00X+065453Y+124350X0160Y         S0      
317GND              VIA   -    MD0080PA00X+064331Y+123976X0160Y         S0      
317GND              VIA   -    MD0080PA00X+064705Y+123976X0160Y    R270 S0      
317GND              VIA   -    MD0080PA00X+065079Y+123976X0160Y         S0      
317GND              VIA   -    MD0080PA00X+065453Y+123976X0160Y         S0      
317GND              VIA   -    MD0080PA00X+064705Y+124350X0160Y         S0      
317GND              VIA   -    MD0080PA00X+065453Y+122854X0160Y    R090 S0      
317GND              VIA   -    MD0080PA00X+065453Y+122480X0160Y         S0      
317GND              VIA   -    MD0080PA00X+065079Y+123228X0160Y         S0      
317GND              VIA   -    MD0080PA00X+064705Y+122480X0160Y         S0      
317GND              VIA   -    MD0080PA00X+064705Y+122854X0160Y    R090 S0      
317GND              VIA   -    MD0080PA00X+065079Y+123602X0160Y         S0      
317GND              VIA   -    MD0080PA00X+064331Y+123228X0160Y         S0      
317GND              VIA   -    MD0080PA00X+064331Y+123602X0160Y         S0      
317GND              VIA   -    MD0080PA00X+062461Y+124724X0160Y    R270 S0      
317GND              VIA   -    MD0080PA00X+062835Y+125472X0160Y    R270 S0      
317GND              VIA   -    MD0080PA00X+063583Y+125098X0160Y    R270 S0      
317GND              VIA   -    MD0080PA00X+063583Y+125472X0160Y    R270 S0      
317GND              VIA   -    MD0080PA00X+063957Y+124724X0160Y    R270 S0      
317GND              VIA   -    MD0080PA00X+062461Y+123976X0160Y         S0      
317GND              VIA   -    MD0080PA00X+062461Y+124350X0160Y         S0      
317GND              VIA   -    MD0080PA00X+062835Y+125098X0160Y         S0      
317GND              VIA   -    MD0080PA00X+062835Y+123976X0160Y         S0      
317GND              VIA   -    MD0080PA00X+063209Y+123976X0160Y         S0      
317GND              VIA   -    MD0080PA00X+063583Y+123976X0160Y    R270 S0      
317GND              VIA   -    MD0080PA00X+063957Y+123976X0160Y    R270 S0      
317GND              VIA   -    MD0080PA00X+063957Y+124350X0160Y         S0      
317GND              VIA   -    MD0080PA00X+063209Y+124350X0160Y    R270 S0      
317GND              VIA   -    MD0080PA00X+063209Y+124724X0160Y         S0      
317GND              VIA   -    MD0080PA00X+063957Y+122854X0160Y    R090 S0      
317GND              VIA   -    MD0080PA00X+063957Y+122480X0160Y         S0      
317GND              VIA   -    MD0080PA00X+063583Y+123228X0160Y         S0      
317GND              VIA   -    MD0080PA00X+063583Y+123602X0160Y         S0      
317GND              VIA   -    MD0080PA00X+062835Y+123228X0160Y         S0      
317GND              VIA   -    MD0080PA00X+061339Y+123602X0160Y         S0      
317GND              VIA   -    MD0080PA00X+061339Y+123228X0160Y         S0      
317GND              VIA   -    MD0080PA00X+060965Y+122854X0160Y         S0      
317GND              VIA   -    MD0080PA00X+060965Y+122480X0160Y         S0      
317GND              VIA   -    MD0080PA00X+061713Y+122480X0160Y         S0      
317GND              VIA   -    MD0080PA00X+061713Y+122854X0160Y    R090 S0      
317GND              VIA   -    MD0080PA00X+062087Y+123228X0160Y         S0      
317GND              VIA   -    MD0080PA00X+062087Y+123602X0160Y         S0      
317GND              VIA   -    MD0080PA00X+060590Y+125098X0160Y    R270 S0      
317GND              VIA   -    MD0080PA00X+060590Y+125472X0160Y    R270 S0      
317GND              VIA   -    MD0080PA00X+060590Y+124350X0160Y    R270 S0      
317GND              VIA   -    MD0080PA00X+060590Y+123602X0160Y         S0      
317GND              VIA   -    MD0080PA00X+060590Y+123228X0160Y         S0      
317GND              VIA   -    MD0080PA00X+060590Y+122480X0160Y         S0      
317GND              VIA   -    MD0080PA00X+065827Y+107894X0160Y    R270 S0      
317GND              VIA   -    MD0080PA00X+077795Y+111260X0160Y    R180 S0      
317GND              VIA   -    MD0080PA00X+077421Y+111634X0160Y    R090 S0      
317GND              VIA   -    MD0080PA00X+107421Y+118366X0160Y         S0      
317GND              VIA   -    MD0080PA00X+166220Y+122106X0160Y         S0      
317GND              VIA   -    MD0080PA00X+068819Y+122106X0160Y         S0      
317GND              VIA   -    MD0080PA00X+068445Y+122106X0160Y         S0      
317GND              VIA   -    MD0080PA00X+068071Y+122106X0160Y         S0      
317GND              VIA   -    MD0080PA00X+067697Y+122106X0160Y         S0      
317GND              VIA   -    MD0080PA00X+067323Y+122106X0160Y         S0      
317GND              VIA   -    MD0080PA00X+066949Y+122106X0160Y         S0      
317GND              VIA   -    MD0080PA00X+066575Y+122106X0160Y         S0      
317GND              VIA   -    MD0080PA00X+066201Y+122106X0160Y         S0      
317GND              VIA   -    MD0080PA00X+065827Y+122106X0160Y         S0      
317GND              VIA   -    MD0080PA00X+065453Y+122106X0160Y         S0      
317GND              VIA   -    MD0080PA00X+065079Y+122106X0160Y         S0      
317GND              VIA   -    MD0080PA00X+064331Y+122106X0160Y         S0      
317GND              VIA   -    MD0080PA00X+064705Y+122106X0160Y         S0      
317GND              VIA   -    MD0080PA00X+063957Y+122106X0160Y         S0      
317GND              VIA   -    MD0080PA00X+063583Y+122106X0160Y         S0      
317GND              VIA   -    MD0080PA00X+108543Y+118740X0160Y         S0      
317GND              VIA   -    MD0080PA00X+108917Y+118740X0160Y         S0      
317GND              VIA   -    MD0080PA00X+108543Y+118366X0160Y         S0      
317GND              VIA   -    MD0080PA00X+108169Y+118366X0160Y         S0      
317GND              VIA   -    MD0080PA00X+107795Y+118366X0160Y         S0      
317GND              VIA   -    MD0080PA00X+165098Y+122106X0160Y         S0      
317GND              VIA   -    MD0080PA00X+154626Y+110512X0160Y         S0      
317GND              VIA   -    MD0080PA00X+168090Y+123976X0160Y         S0      
317GND              VIA   -    MD0080PA00X+167716Y+123976X0160Y    R270 S0      
317GND              VIA   -    MD0080PA00X+167342Y+123976X0160Y    R180 S0      
317GND              VIA   -    MD0080PA00X+166968Y+123976X0160Y         S0      
317GND              VIA   -    MD0080PA00X+168090Y+124350X0160Y    R180 S0      
317GND              VIA   -    MD0080PA00X+168090Y+124724X0160Y    R180 S0      
317GND              VIA   -    MD0080PA00X+167716Y+125472X0160Y    R180 S0      
317GND              VIA   -    MD0080PA00X+167716Y+125098X0160Y    R180 S0      
317GND              VIA   -    MD0080PA00X+167342Y+124350X0160Y    R180 S0      
317GND              VIA   -    MD0080PA00X+167342Y+124724X0160Y    R180 S0      
317GND              VIA   -    MD0080PA00X+166968Y+125472X0160Y    R180 S0      
317GND              VIA   -    MD0080PA00X+166968Y+125098X0160Y    R180 S0      
317GND              VIA   -    MD0080PA00X+166594Y+122854X0160Y         S0      
317GND              VIA   -    MD0080PA00X+166594Y+122480X0160Y         S0      
317GND              VIA   -    MD0080PA00X+167716Y+123602X0160Y         S0      
317GND              VIA   -    MD0080PA00X+167716Y+123228X0160Y         S0      
317GND              VIA   -    MD0080PA00X+168090Y+122854X0160Y         S0      
317GND              VIA   -    MD0080PA00X+168090Y+122480X0160Y         S0      
317GND              VIA   -    MD0080PA00X+166968Y+123602X0160Y         S0      
317GND              VIA   -    MD0080PA00X+166968Y+123228X0160Y         S0      
317GND              VIA   -    MD0080PA00X+167342Y+122854X0160Y         S0      
317GND              VIA   -    MD0080PA00X+167342Y+122480X0160Y         S0      
317GND              VIA   -    MD0080PA00X+165098Y+124350X0160Y    R180 S0      
317GND              VIA   -    MD0080PA00X+165098Y+123976X0160Y    R270 S0      
317GND              VIA   -    MD0080PA00X+165098Y+124724X0160Y    R180 S0      
317GND              VIA   -    MD0080PA00X+166220Y+123976X0160Y         S0      
317GND              VIA   -    MD0080PA00X+165846Y+124350X0160Y    R180 S0      
317GND              VIA   -    MD0080PA00X+165846Y+123976X0160Y    R180 S0      
317GND              VIA   -    MD0080PA00X+165472Y+123976X0160Y         S0      
317GND              VIA   -    MD0080PA00X+166220Y+125472X0160Y    R180 S0      
317GND              VIA   -    MD0080PA00X+166220Y+125098X0160Y    R180 S0      
317GND              VIA   -    MD0080PA00X+165846Y+124724X0160Y    R180 S0      
317GND              VIA   -    MD0080PA00X+165472Y+125472X0160Y    R180 S0      
317GND              VIA   -    MD0080PA00X+165472Y+125098X0160Y    R180 S0      
317GND              VIA   -    MD0080PA00X+165098Y+122480X0160Y         S0      
317GND              VIA   -    MD0080PA00X+165098Y+122854X0160Y         S0      
317GND              VIA   -    MD0080PA00X+166220Y+123602X0160Y         S0      
317GND              VIA   -    MD0080PA00X+166220Y+123228X0160Y         S0      
317GND              VIA   -    MD0080PA00X+165846Y+122480X0160Y         S0      
317GND              VIA   -    MD0080PA00X+165472Y+123602X0160Y         S0      
317GND              VIA   -    MD0080PA00X+165846Y+122854X0160Y         S0      
317GND              VIA   -    MD0080PA00X+165472Y+123228X0160Y         S0      
317GND              VIA   -    MD0080PA00X+164724Y+123976X0160Y    R270 S0      
317GND              VIA   -    MD0080PA00X+164350Y+124350X0160Y    R180 S0      
317GND              VIA   -    MD0080PA00X+163602Y+124350X0160Y    R180 S0      
317GND              VIA   -    MD0080PA00X+163976Y+123976X0160Y         S0      
317GND              VIA   -    MD0080PA00X+164350Y+123976X0160Y    R180 S0      
317GND              VIA   -    MD0080PA00X+163602Y+123976X0160Y    R270 S0      
317GND              VIA   -    MD0080PA00X+164350Y+124724X0160Y    R180 S0      
317GND              VIA   -    MD0080PA00X+164724Y+125098X0160Y    R180 S0      
317GND              VIA   -    MD0080PA00X+164724Y+125472X0160Y    R180 S0      
317GND              VIA   -    MD0080PA00X+163976Y+125472X0160Y    R180 S0      
317GND              VIA   -    MD0080PA00X+163976Y+125098X0160Y    R180 S0      
317GND              VIA   -    MD0080PA00X+163602Y+124724X0160Y    R180 S0      
317GND              VIA   -    MD0080PA00X+164350Y+122480X0160Y         S0      
317GND              VIA   -    MD0080PA00X+164350Y+122854X0160Y         S0      
317GND              VIA   -    MD0080PA00X+164724Y+123602X0160Y         S0      
317GND              VIA   -    MD0080PA00X+164724Y+123228X0160Y         S0      
317GND              VIA   -    MD0080PA00X+163976Y+123602X0160Y         S0      
317GND              VIA   -    MD0080PA00X+163976Y+123228X0160Y         S0      
317GND              VIA   -    MD0080PA00X+163602Y+122480X0160Y         S0      
317GND              VIA   -    MD0080PA00X+163602Y+122854X0160Y         S0      
317GND              VIA   -    MD0080PA00X+161732Y+125472X0160Y    R180 S0      
317GND              VIA   -    MD0080PA00X+161732Y+125098X0160Y    R180 S0      
317GND              VIA   -    MD0080PA00X+161732Y+123976X0160Y         S0      
317GND              VIA   -    MD0080PA00X+162854Y+123976X0160Y         S0      
317GND              VIA   -    MD0080PA00X+163228Y+125098X0160Y    R180 S0      
317GND              VIA   -    MD0080PA00X+163228Y+123976X0160Y    R180 S0      
317GND              VIA   -    MD0080PA00X+162854Y+124350X0160Y    R270 S0      
317GND              VIA   -    MD0080PA00X+162854Y+124724X0160Y    R180 S0      
317GND              VIA   -    MD0080PA00X+162480Y+125472X0160Y    R180 S0      
317GND              VIA   -    MD0080PA00X+162480Y+125098X0160Y    R180 S0      
317GND              VIA   -    MD0080PA00X+162480Y+123976X0160Y    R180 S0      
317GND              VIA   -    MD0080PA00X+162106Y+124724X0160Y    R180 S0      
317GND              VIA   -    MD0080PA00X+162106Y+124350X0160Y    R270 S0      
317GND              VIA   -    MD0080PA00X+162106Y+123976X0160Y    R180 S0      
317GND              VIA   -    MD0080PA00X+163228Y+125472X0160Y    R180 S0      
317GND              VIA   -    MD0080PA00X+161732Y+123602X0160Y         S0      
317GND              VIA   -    MD0080PA00X+161732Y+123228X0160Y         S0      
317GND              VIA   -    MD0080PA00X+162480Y+123602X0160Y         S0      
317GND              VIA   -    MD0080PA00X+163228Y+123602X0160Y         S0      
317GND              VIA   -    MD0080PA00X+163228Y+123228X0160Y         S0      
317GND              VIA   -    MD0080PA00X+162480Y+123228X0160Y         S0      
317GND              VIA   -    MD0080PA00X+162854Y+122480X0160Y         S0      
317GND              VIA   -    MD0080PA00X+162854Y+122854X0160Y         S0      
317GND              VIA   -    MD0080PA00X+162106Y+122480X0160Y         S0      
317GND              VIA   -    MD0080PA00X+162106Y+122854X0160Y         S0      
317GND              VIA   -    MD0080PA00X+160236Y+125472X0160Y    R270 S0      
317GND              VIA   -    MD0080PA00X+160236Y+125098X0160Y    R270 S0      
317GND              VIA   -    MD0080PA00X+160236Y+123976X0160Y         S0      
317GND              VIA   -    MD0080PA00X+161358Y+124724X0160Y    R180 S0      
317GND              VIA   -    MD0080PA00X+161358Y+124350X0160Y    R180 S0      
317GND              VIA   -    MD0080PA00X+161358Y+123976X0160Y    R270 S0      
317GND              VIA   -    MD0080PA00X+160984Y+123976X0160Y         S0      
317GND              VIA   -    MD0080PA00X+160610Y+123976X0160Y    R270 S0      
317GND              VIA   -    MD0080PA00X+160610Y+124350X0160Y    R270 S0      
317GND              VIA   -    MD0080PA00X+160610Y+124724X0160Y    R180 S0      
317GND              VIA   -    MD0080PA00X+160984Y+125098X0160Y    R180 S0      
317GND              VIA   -    MD0080PA00X+160984Y+125472X0160Y    R180 S0      
317GND              VIA   -    MD0080PA00X+160236Y+123602X0160Y         S0      
317GND              VIA   -    MD0080PA00X+160236Y+123228X0160Y         S0      
317GND              VIA   -    MD0080PA00X+160610Y+122480X0160Y         S0      
317GND              VIA   -    MD0080PA00X+160610Y+122854X0160Y         S0      
317GND              VIA   -    MD0080PA00X+161358Y+122480X0160Y         S0      
317GND              VIA   -    MD0080PA00X+161358Y+122854X0160Y         S0      
317GND              VIA   -    MD0080PA00X+160984Y+123602X0160Y         S0      
317GND              VIA   -    MD0080PA00X+160984Y+123228X0160Y         S0      
317GND              VIA   -    MD0080PA00X+158740Y+123976X0160Y         S0      
317GND              VIA   -    MD0080PA00X+159114Y+123976X0160Y    R270 S0      
317GND              VIA   -    MD0080PA00X+159488Y+123976X0160Y         S0      
317GND              VIA   -    MD0080PA00X+159488Y+125472X0160Y    R270 S0      
317GND              VIA   -    MD0080PA00X+159488Y+125098X0160Y    R270 S0      
317GND              VIA   -    MD0080PA00X+159114Y+124350X0160Y         S0      
317GND              VIA   -    MD0080PA00X+159114Y+124724X0160Y    R270 S0      
317GND              VIA   -    MD0080PA00X+158740Y+125472X0160Y    R270 S0      
317GND              VIA   -    MD0080PA00X+158740Y+125098X0160Y    R270 S0      
317GND              VIA   -    MD0080PA00X+159862Y+124724X0160Y    R270 S0      
317GND              VIA   -    MD0080PA00X+159862Y+124350X0160Y         S0      
317GND              VIA   -    MD0080PA00X+159862Y+123976X0160Y    R270 S0      
317GND              VIA   -    MD0080PA00X+158740Y+123602X0160Y         S0      
317GND              VIA   -    MD0080PA00X+158740Y+123228X0160Y         S0      
317GND              VIA   -    MD0080PA00X+159114Y+122480X0160Y         S0      
317GND              VIA   -    MD0080PA00X+159114Y+122854X0160Y    R090 S0      
317GND              VIA   -    MD0080PA00X+159488Y+123602X0160Y         S0      
317GND              VIA   -    MD0080PA00X+159488Y+123228X0160Y         S0      
317GND              VIA   -    MD0080PA00X+159862Y+122480X0160Y         S0      
317GND              VIA   -    MD0080PA00X+159862Y+122854X0160Y    R090 S0      
317GND              VIA   -    MD0080PA00X+156870Y+123976X0160Y         S0      
317GND              VIA   -    MD0080PA00X+156870Y+124350X0160Y         S0      
317GND              VIA   -    MD0080PA00X+156870Y+124724X0160Y    R270 S0      
317GND              VIA   -    MD0080PA00X+157618Y+123976X0160Y    R270 S0      
317GND              VIA   -    MD0080PA00X+157244Y+123976X0160Y    R270 S0      
317GND              VIA   -    MD0080PA00X+158366Y+123976X0160Y    R270 S0      
317GND              VIA   -    MD0080PA00X+157992Y+123976X0160Y         S0      
317GND              VIA   -    MD0080PA00X+157992Y+125098X0160Y    R270 S0      
317GND              VIA   -    MD0080PA00X+157992Y+125472X0160Y    R270 S0      
317GND              VIA   -    MD0080PA00X+158366Y+124724X0160Y    R270 S0      
317GND              VIA   -    MD0080PA00X+158366Y+124350X0160Y         S0      
317GND              VIA   -    MD0080PA00X+157618Y+124350X0160Y         S0      
317GND              VIA   -    MD0080PA00X+157618Y+124724X0160Y    R270 S0      
317GND              VIA   -    MD0080PA00X+157244Y+125472X0160Y    R270 S0      
317GND              VIA   -    MD0080PA00X+157244Y+125098X0160Y    R270 S0      
317GND              VIA   -    MD0080PA00X+156870Y+122480X0160Y         S0      
317GND              VIA   -    MD0080PA00X+156870Y+122854X0160Y    R090 S0      
317GND              VIA   -    MD0080PA00X+157244Y+123602X0160Y         S0      
317GND              VIA   -    MD0080PA00X+157244Y+123228X0160Y         S0      
317GND              VIA   -    MD0080PA00X+157618Y+122854X0160Y    R090 S0      
317GND              VIA   -    MD0080PA00X+157618Y+122480X0160Y         S0      
317GND              VIA   -    MD0080PA00X+157992Y+123602X0160Y         S0      
317GND              VIA   -    MD0080PA00X+157992Y+123228X0160Y         S0      
317GND              VIA   -    MD0080PA00X+158366Y+122854X0160Y    R090 S0      
317GND              VIA   -    MD0080PA00X+158366Y+122480X0160Y         S0      
317GND              VIA   -    MD0080PA00X+155374Y+124350X0160Y         S0      
317GND              VIA   -    MD0080PA00X+155374Y+123976X0160Y    R270 S0      
317GND              VIA   -    MD0080PA00X+155374Y+124724X0160Y    R270 S0      
317GND              VIA   -    MD0080PA00X+156122Y+124350X0160Y         S0      
317GND              VIA   -    MD0080PA00X+156496Y+123976X0160Y         S0      
317GND              VIA   -    MD0080PA00X+156122Y+123976X0160Y    R270 S0      
317GND              VIA   -    MD0080PA00X+155748Y+123976X0160Y         S0      
317GND              VIA   -    MD0080PA00X+156496Y+125472X0160Y    R270 S0      
317GND              VIA   -    MD0080PA00X+156496Y+125098X0160Y    R270 S0      
317GND              VIA   -    MD0080PA00X+156122Y+124724X0160Y    R270 S0      
317GND              VIA   -    MD0080PA00X+155748Y+125472X0160Y    R270 S0      
317GND              VIA   -    MD0080PA00X+155748Y+125098X0160Y    R270 S0      
317GND              VIA   -    MD0080PA00X+155374Y+122480X0160Y         S0      
317GND              VIA   -    MD0080PA00X+155374Y+122854X0160Y    R090 S0      
317GND              VIA   -    MD0080PA00X+155748Y+123602X0160Y         S0      
317GND              VIA   -    MD0080PA00X+155748Y+123228X0160Y         S0      
317GND              VIA   -    MD0080PA00X+156496Y+123602X0160Y         S0      
317GND              VIA   -    MD0080PA00X+156122Y+122854X0160Y    R090 S0      
317GND              VIA   -    MD0080PA00X+156122Y+122480X0160Y         S0      
317GND              VIA   -    MD0080PA00X+156496Y+123228X0160Y         S0      
317GND              VIA   -    MD0080PA00X+155000Y+123976X0160Y    R270 S0      
317GND              VIA   -    MD0080PA00X+155000Y+125472X0160Y    R270 S0      
317GND              VIA   -    MD0080PA00X+155000Y+125098X0160Y    R270 S0      
317GND              VIA   -    MD0080PA00X+155000Y+123602X0160Y         S0      
317GND              VIA   -    MD0080PA00X+155000Y+123228X0160Y         S0      
317GND              VIA   -    MD0080PA00X+154626Y+124724X0160Y         S0      
317GND              VIA   -    MD0080PA00X+154626Y+124350X0160Y    R270 S0      
317GND              VIA   -    MD0080PA00X+154626Y+123976X0160Y         S0      
317GND              VIA   -    MD0080PA00X+154252Y+123976X0160Y         S0      
317GND              VIA   -    MD0080PA00X+154252Y+125098X0160Y         S0      
317GND              VIA   -    MD0080PA00X+153878Y+124350X0160Y         S0      
317GND              VIA   -    MD0080PA00X+153878Y+123976X0160Y         S0      
317GND              VIA   -    MD0080PA00X+154252Y+125472X0160Y    R270 S0      
317GND              VIA   -    MD0080PA00X+153878Y+124724X0160Y    R270 S0      
317GND              VIA   -    MD0080PA00X+154626Y+122854X0160Y    R090 S0      
317GND              VIA   -    MD0080PA00X+154626Y+122480X0160Y         S0      
317GND              VIA   -    MD0080PA00X+153878Y+122480X0160Y         S0      
317GND              VIA   -    MD0080PA00X+153878Y+122854X0160Y    R090 S0      
317GND              VIA   -    MD0080PA00X+154252Y+123602X0160Y         S0      
317GND              VIA   -    MD0080PA00X+154252Y+123228X0160Y         S0      
317GND              VIA   -    MD0080PA00X+154252Y+121732X0160Y         S0      
317GND              VIA   -    MD0080PA00X+154252Y+122106X0160Y         S0      
317GND              VIA   -    MD0080PA00X+153878Y+122106X0160Y    R270 S0      
317GND              VIA   -    MD0080PA00X+154626Y+122106X0160Y         S0      
317GND              VIA   -    MD0080PA00X+154626Y+121732X0160Y         S0      
317GND              VIA   -    MD0080PA00X+152008Y+124350X0160Y    R270 S0      
317GND              VIA   -    MD0080PA00X+152008Y+125472X0160Y    R270 S0      
317GND              VIA   -    MD0080PA00X+152008Y+125098X0160Y    R270 S0      
317GND              VIA   -    MD0080PA00X+153130Y+124350X0160Y         S0      
317GND              VIA   -    MD0080PA00X+153130Y+123976X0160Y         S0      
317GND              VIA   -    MD0080PA00X+153504Y+123976X0160Y         S0      
317GND              VIA   -    MD0080PA00X+152756Y+123976X0160Y    R270 S0      
317GND              VIA   -    MD0080PA00X+152382Y+124350X0160Y         S0      
317GND              VIA   -    MD0080PA00X+152382Y+123976X0160Y         S0      
317GND              VIA   -    MD0080PA00X+153504Y+125472X0160Y    R270 S0      
317GND              VIA   -    MD0080PA00X+153504Y+125098X0160Y    R270 S0      
317GND              VIA   -    MD0080PA00X+153130Y+124724X0160Y    R270 S0      
317GND              VIA   -    MD0080PA00X+152382Y+124724X0160Y    R270 S0      
317GND              VIA   -    MD0080PA00X+152756Y+125472X0160Y    R270 S0      
317GND              VIA   -    MD0080PA00X+152756Y+125098X0160Y    R270 S0      
317GND              VIA   -    MD0080PA00X+152008Y+122480X0160Y         S0      
317GND              VIA   -    MD0080PA00X+152008Y+123228X0160Y         S0      
317GND              VIA   -    MD0080PA00X+152008Y+123602X0160Y         S0      
317GND              VIA   -    MD0080PA00X+153504Y+123602X0160Y         S0      
317GND              VIA   -    MD0080PA00X+153504Y+123228X0160Y         S0      
317GND              VIA   -    MD0080PA00X+153130Y+122854X0160Y    R090 S0      
317GND              VIA   -    MD0080PA00X+153130Y+122480X0160Y         S0      
317GND              VIA   -    MD0080PA00X+152382Y+122480X0160Y         S0      
317GND              VIA   -    MD0080PA00X+152382Y+122854X0160Y         S0      
317GND              VIA   -    MD0080PA00X+152756Y+123228X0160Y         S0      
317GND              VIA   -    MD0080PA00X+152756Y+123602X0160Y         S0      
317GND              VIA   -    MD0080PA00X+165846Y+122106X0160Y         S0      
317GND              VIA   -    MD0080PA00X+169587Y+122480X0160Y    R090 S0      
317GND              VIA   -    MD0080PA00X+166594Y+123976X0160Y    R270 S0      
317GND              VIA   -    MD0080PA00X+166594Y+124350X0160Y    R180 S0      
317GND              VIA   -    MD0080PA00X+166594Y+124724X0160Y    R180 S0      
317GND              VIA   -    MD0080PA00X+169213Y+125472X0160Y    R180 S0      
317GND              VIA   -    MD0080PA00X+168838Y+123976X0160Y    R180 S0      
317GND              VIA   -    MD0080PA00X+168464Y+123976X0160Y    R270 S0      
317GND              VIA   -    MD0080PA00X+169587Y+124350X0160Y    R090 S0      
317GND              VIA   -    MD0080PA00X+169213Y+124350X0160Y    R270 S0      
317GND              VIA   -    MD0080PA00X+168838Y+124350X0160Y    R180 S0      
317GND              VIA   -    MD0080PA00X+168838Y+124724X0160Y    R180 S0      
317GND              VIA   -    MD0080PA00X+169213Y+125098X0160Y    R180 S0      
317GND              VIA   -    MD0080PA00X+169587Y+125098X0160Y         S0      
317GND              VIA   -    MD0080PA00X+168464Y+125472X0160Y    R180 S0      
317GND              VIA   -    MD0080PA00X+168464Y+125098X0160Y    R180 S0      
317GND              VIA   -    MD0080PA00X+169587Y+123602X0160Y    R090 S0      
317GND              VIA   -    MD0080PA00X+169213Y+123602X0160Y    R090 S0      
317GND              VIA   -    MD0080PA00X+169213Y+123228X0160Y         S0      
317GND              VIA   -    MD0080PA00X+169587Y+123228X0160Y    R090 S0      
317GND              VIA   -    MD0080PA00X+168464Y+123228X0160Y         S0      
317GND              VIA   -    MD0080PA00X+168464Y+123602X0160Y         S0      
317GND              VIA   -    MD0080PA00X+168838Y+122854X0160Y         S0      
317GND              VIA   -    MD0080PA00X+168838Y+122480X0160Y         S0      
317GND              VIA   -    MD0080PA00X+169213Y+122480X0160Y    R090 S0      
317GND              VIA   -    MD0080PA00X+167342Y+119862X0160Y    R090 S0      
317GND              VIA   -    MD0080PA00X+167716Y+119862X0160Y         S0      
317GND              VIA   -    MD0080PA00X+168090Y+119862X0160Y         S0      
317GND              VIA   -    MD0080PA00X+168090Y+120236X0160Y         S0      
317GND              VIA   -    MD0080PA00X+166968Y+120236X0160Y         S0      
317GND              VIA   -    MD0080PA00X+167342Y+120610X0160Y    R090 S0      
317GND              VIA   -    MD0080PA00X+167716Y+120610X0160Y    R090 S0      
317GND              VIA   -    MD0080PA00X+168090Y+120610X0160Y         S0      
317GND              VIA   -    MD0080PA00X+168464Y+119862X0160Y    R090 S0      
317GND              VIA   -    MD0080PA00X+168838Y+119862X0160Y    R270 S0      
317GND              VIA   -    MD0080PA00X+168464Y+120610X0160Y    R090 S0      
317GND              VIA   -    MD0080PA00X+168838Y+120610X0160Y    R270 S0      
317GND              VIA   -    MD0080PA00X+169213Y+120236X0160Y         S0      
317GND              VIA   -    MD0080PA00X+169587Y+120236X0160Y         S0      
317GND              VIA   -    MD0080PA00X+166594Y+120984X0160Y    R090 S0      
317GND              VIA   -    MD0080PA00X+166594Y+121732X0160Y         S0      
317GND              VIA   -    MD0080PA00X+166594Y+122106X0160Y         S0      
317GND              VIA   -    MD0080PA00X+166968Y+120984X0160Y         S0      
317GND              VIA   -    MD0080PA00X+168090Y+120984X0160Y         S0      
317GND              VIA   -    MD0080PA00X+168090Y+121358X0160Y         S0      
317GND              VIA   -    MD0080PA00X+167716Y+121358X0160Y         S0      
317GND              VIA   -    MD0080PA00X+167342Y+121358X0160Y    R090 S0      
317GND              VIA   -    MD0080PA00X+166968Y+121732X0160Y    R090 S0      
317GND              VIA   -    MD0080PA00X+166968Y+122106X0160Y    R090 S0      
317GND              VIA   -    MD0080PA00X+167342Y+122106X0160Y         S0      
317GND              VIA   -    MD0080PA00X+167716Y+122106X0160Y         S0      
317GND              VIA   -    MD0080PA00X+168090Y+121732X0160Y         S0      
317GND              VIA   -    MD0080PA00X+168090Y+122106X0160Y         S0      
317GND              VIA   -    MD0080PA00X+166594Y+120236X0160Y    R090 S0      
317GND              VIA   -    MD0080PA00X+061339Y+120610X0160Y         S0      
317GND              VIA   -    MD0080PA00X+060965Y+118366X0160Y         S0      
317GND              VIA   -    MD0080PA00X+155000Y+107520X0160Y    R270 S0      
317GND              VIA   -    MD0080PA00X+168464Y+121358X0160Y    R090 S0      
317GND              VIA   -    MD0080PA00X+168838Y+121358X0160Y    R270 S0      
317GND              VIA   -    MD0080PA00X+169213Y+120984X0160Y         S0      
317GND              VIA   -    MD0080PA00X+169587Y+120984X0160Y    R090 S0      
317GND              VIA   -    MD0080PA00X+168464Y+122106X0160Y         S0      
317GND              VIA   -    MD0080PA00X+168838Y+122106X0160Y    R090 S0      
317GND              VIA   -    MD0080PA00X+169213Y+121732X0160Y    R090 S0      
317GND              VIA   -    MD0080PA00X+169587Y+121732X0160Y    R090 S0      
317GND              VIA   -    MD0080PA00X+155748Y+107520X0160Y    R270 S0      
317GND              VIA   -    MD0080PA00X+156496Y+107520X0160Y    R270 S0      
317GND              VIA   -    MD0080PA00X+154626Y+110138X0160Y         S0      
317GND              VIA   -    MD0080PA00X+155000Y+109764X0160Y         S0      
317GND              VIA   -    MD0080PA00X+155000Y+109390X0160Y         S0      
317GND              VIA   -    MD0080PA00X+155000Y+109016X0160Y         S0      
317GND              VIA   -    MD0080PA00X+154626Y+109016X0160Y         S0      
317GND              VIA   -    MD0080PA00X+155000Y+107894X0160Y    R270 S0      
317GND              VIA   -    MD0080PA00X+154626Y+108642X0160Y    R270 S0      
317GND              VIA   -    MD0080PA00X+154626Y+108268X0160Y    R270 S0      
317GND              VIA   -    MD0080PA00X+163228Y+109016X0160Y         S0      
317GND              VIA   -    MD0080PA00X+162480Y+109016X0160Y         S0      
317GND              VIA   -    MD0080PA00X+162854Y+109016X0160Y         S0      
317GND              VIA   -    MD0080PA00X+162854Y+108642X0160Y         S0      
317GND              VIA   -    MD0080PA00X+162854Y+108268X0160Y    R180 S0      
317GND              VIA   -    MD0080PA00X+163228Y+107894X0160Y         S0      
317GND              VIA   -    MD0080PA00X+162106Y+109016X0160Y         S0      
317GND              VIA   -    MD0080PA00X+162106Y+108642X0160Y         S0      
317GND              VIA   -    MD0080PA00X+162106Y+108268X0160Y    R180 S0      
317GND              VIA   -    MD0080PA00X+162480Y+107894X0160Y         S0      
317GND              VIA   -    MD0080PA00X+161732Y+107520X0160Y         S0      
317GND              VIA   -    MD0080PA00X+163228Y+107520X0160Y         S0      
317GND              VIA   -    MD0080PA00X+162480Y+107520X0160Y         S0      
317GND              VIA   -    MD0080PA00X+160236Y+109764X0160Y         S0      
317GND              VIA   -    MD0080PA00X+160236Y+109390X0160Y         S0      
317GND              VIA   -    MD0080PA00X+161358Y+110138X0160Y         S0      
317GND              VIA   -    MD0080PA00X+160984Y+109764X0160Y    R180 S0      
317GND              VIA   -    MD0080PA00X+160984Y+109390X0160Y         S0      
317GND              VIA   -    MD0080PA00X+160610Y+110138X0160Y         S0      
317GND              VIA   -    MD0080PA00X+160236Y+107894X0160Y    R270 S0      
317GND              VIA   -    MD0080PA00X+160236Y+109016X0160Y         S0      
317GND              VIA   -    MD0080PA00X+161358Y+108268X0160Y    R180 S0      
317GND              VIA   -    MD0080PA00X+160984Y+107894X0160Y    R180 S0      
317GND              VIA   -    MD0080PA00X+160610Y+109016X0160Y         S0      
317GND              VIA   -    MD0080PA00X+161358Y+108642X0160Y         S0      
317GND              VIA   -    MD0080PA00X+161358Y+109016X0160Y         S0      
317GND              VIA   -    MD0080PA00X+160984Y+109016X0160Y         S0      
317GND              VIA   -    MD0080PA00X+160610Y+108642X0160Y         S0      
317GND              VIA   -    MD0080PA00X+160610Y+108268X0160Y         S0      
317GND              VIA   -    MD0080PA00X+160236Y+107520X0160Y    R270 S0      
317GND              VIA   -    MD0080PA00X+160984Y+107520X0160Y         S0      
317GND              VIA   -    MD0080PA00X+159862Y+110138X0160Y         S0      
317GND              VIA   -    MD0080PA00X+159114Y+110138X0160Y         S0      
317GND              VIA   -    MD0080PA00X+159488Y+109764X0160Y         S0      
317GND              VIA   -    MD0080PA00X+159488Y+109390X0160Y         S0      
317GND              VIA   -    MD0080PA00X+158740Y+109390X0160Y         S0      
317GND              VIA   -    MD0080PA00X+158740Y+109764X0160Y         S0      
317GND              VIA   -    MD0080PA00X+159862Y+109016X0160Y         S0      
317GND              VIA   -    MD0080PA00X+159862Y+108642X0160Y    R270 S0      
317GND              VIA   -    MD0080PA00X+159862Y+108268X0160Y    R270 S0      
317GND              VIA   -    MD0080PA00X+159488Y+107894X0160Y    R270 S0      
317GND              VIA   -    MD0080PA00X+159488Y+109016X0160Y         S0      
317GND              VIA   -    MD0080PA00X+159114Y+109016X0160Y         S0      
317GND              VIA   -    MD0080PA00X+159114Y+108642X0160Y    R270 S0      
317GND              VIA   -    MD0080PA00X+159114Y+108268X0160Y    R270 S0      
317GND              VIA   -    MD0080PA00X+158740Y+107894X0160Y    R270 S0      
317GND              VIA   -    MD0080PA00X+158740Y+109016X0160Y         S0      
317GND              VIA   -    MD0080PA00X+159488Y+107520X0160Y    R270 S0      
317GND              VIA   -    MD0080PA00X+158740Y+107520X0160Y    R270 S0      
317GND              VIA   -    MD0080PA00X+156870Y+110138X0160Y         S0      
317GND              VIA   -    MD0080PA00X+158366Y+110138X0160Y         S0      
317GND              VIA   -    MD0080PA00X+157618Y+110138X0160Y         S0      
317GND              VIA   -    MD0080PA00X+157244Y+109764X0160Y         S0      
317GND              VIA   -    MD0080PA00X+157992Y+109764X0160Y         S0      
317GND              VIA   -    MD0080PA00X+157244Y+109390X0160Y         S0      
317GND              VIA   -    MD0080PA00X+157992Y+109390X0160Y         S0      
317GND              VIA   -    MD0080PA00X+156870Y+109016X0160Y         S0      
317GND              VIA   -    MD0080PA00X+156870Y+108642X0160Y    R270 S0      
317GND              VIA   -    MD0080PA00X+156870Y+108268X0160Y    R270 S0      
317GND              VIA   -    MD0080PA00X+157992Y+107894X0160Y    R270 S0      
317GND              VIA   -    MD0080PA00X+158366Y+108268X0160Y    R270 S0      
317GND              VIA   -    MD0080PA00X+158366Y+108642X0160Y    R270 S0      
317GND              VIA   -    MD0080PA00X+158366Y+109016X0160Y         S0      
317GND              VIA   -    MD0080PA00X+157992Y+109016X0160Y         S0      
317GND              VIA   -    MD0080PA00X+157618Y+109016X0160Y         S0      
317GND              VIA   -    MD0080PA00X+157618Y+108642X0160Y    R270 S0      
317GND              VIA   -    MD0080PA00X+157618Y+108268X0160Y    R270 S0      
317GND              VIA   -    MD0080PA00X+157244Y+107894X0160Y    R270 S0      
317GND              VIA   -    MD0080PA00X+157244Y+109016X0160Y         S0      
317GND              VIA   -    MD0080PA00X+157992Y+107520X0160Y    R270 S0      
317GND              VIA   -    MD0080PA00X+157244Y+107520X0160Y    R270 S0      
317GND              VIA   -    MD0080PA00X+155374Y+110138X0160Y         S0      
317GND              VIA   -    MD0080PA00X+155748Y+109390X0160Y         S0      
317GND              VIA   -    MD0080PA00X+155748Y+109764X0160Y         S0      
317GND              VIA   -    MD0080PA00X+156122Y+110138X0160Y         S0      
317GND              VIA   -    MD0080PA00X+156496Y+109764X0160Y         S0      
317GND              VIA   -    MD0080PA00X+156496Y+109390X0160Y         S0      
317GND              VIA   -    MD0080PA00X+155374Y+109016X0160Y         S0      
317GND              VIA   -    MD0080PA00X+155374Y+108642X0160Y    R270 S0      
317GND              VIA   -    MD0080PA00X+155374Y+108268X0160Y    R270 S0      
317GND              VIA   -    MD0080PA00X+155748Y+109016X0160Y         S0      
317GND              VIA   -    MD0080PA00X+155748Y+107894X0160Y    R270 S0      
317GND              VIA   -    MD0080PA00X+156496Y+107894X0160Y    R270 S0      
317GND              VIA   -    MD0080PA00X+156496Y+109016X0160Y         S0      
317GND              VIA   -    MD0080PA00X+156122Y+108268X0160Y    R270 S0      
317GND              VIA   -    MD0080PA00X+156122Y+109016X0160Y         S0      
317GND              VIA   -    MD0080PA00X+156122Y+108642X0160Y    R270 S0      
317GND              VIA   -    MD0080PA00X+107047Y+118366X0160Y         S0      
317GND              VIA   -    MD0080PA00X+106673Y+118366X0160Y         S0      
317GND              VIA   -    MD0080PA00X+106299Y+118366X0160Y         S0      
317GND              VIA   -    MD0080PA00X+105925Y+118366X0160Y         S0      
317GND              VIA   -    MD0080PA00X+114902Y+122106X0160Y         S0      
317GND              VIA   -    MD0080PA00X+108917Y+110512X0160Y         S0      
317GND              VIA   -    MD0080PA00X+151634Y+118366X0160Y         S0      
317GND              VIA   -    MD0080PA00X+165472Y+122106X0160Y         S0      
317GND              VIA   -    MD0080PA00X+152008Y+118366X0160Y         S0      
317GND              VIA   -    MD0080PA00X+152382Y+118366X0160Y         S0      
317GND              VIA   -    MD0080PA00X+152756Y+118366X0160Y         S0      
317GND              VIA   -    MD0080PA00X+153130Y+118366X0160Y         S0      
317GND              VIA   -    MD0080PA00X+153504Y+118366X0160Y         S0      
317GND              VIA   -    MD0080PA00X+153878Y+118366X0160Y         S0      
317GND              VIA   -    MD0080PA00X+154252Y+118366X0160Y         S0      
317GND              VIA   -    MD0080PA00X+154252Y+118740X0160Y         S0      
317GND              VIA   -    MD0080PA00X+154626Y+118740X0160Y         S0      
317GND              VIA   -    MD0080PA00X+158366Y+122106X0160Y         S0      
317GND              VIA   -    MD0080PA00X+157992Y+122106X0160Y         S0      
317GND              VIA   -    MD0080PA00X+157618Y+122106X0160Y         S0      
317GND              VIA   -    MD0080PA00X+157244Y+122106X0160Y         S0      
317GND              VIA   -    MD0080PA00X+156870Y+122106X0160Y         S0      
317GND              VIA   -    MD0080PA00X+120886Y+113504X0160Y    R090 S0      
317GND              VIA   -    MD0080PA00X+121260Y+113504X0160Y    R270 S0      
317GND              VIA   -    MD0080PA00X+123878Y+113504X0160Y    R180 S0      
317GND              VIA   -    MD0080PA00X+123504Y+113504X0160Y    R180 S0      
317GND              VIA   -    MD0080PA00X+122382Y+113504X0160Y    R090 S0      
317GND              VIA   -    MD0080PA00X+122756Y+113130X0160Y    R090 S0      
317GND              VIA   -    MD0080PA00X+123130Y+113130X0160Y    R270 S0      
317GND              VIA   -    MD0080PA00X+123504Y+112756X0160Y    R180 S0      
317GND              VIA   -    MD0080PA00X+123878Y+112756X0160Y    R180 S0      
317GND              VIA   -    MD0080PA00X+123878Y+112008X0160Y    R180 S0      
317GND              VIA   -    MD0080PA00X+123504Y+112008X0160Y    R180 S0      
317GND              VIA   -    MD0080PA00X+123130Y+112382X0160Y    R090 S0      
317GND              VIA   -    MD0080PA00X+122756Y+112382X0160Y    R090 S0      
317GND              VIA   -    MD0080PA00X+123878Y+111260X0160Y    R180 S0      
317GND              VIA   -    MD0080PA00X+123504Y+111260X0160Y    R180 S0      
317GND              VIA   -    MD0080PA00X+123130Y+111634X0160Y    R090 S0      
317GND              VIA   -    MD0080PA00X+122756Y+111634X0160Y    R090 S0      
317GND              VIA   -    MD0080PA00X+123130Y+110886X0160Y    R180 S0      
317GND              VIA   -    MD0080PA00X+122756Y+110886X0160Y         S0      
317GND              VIA   -    MD0080PA00X+123878Y+110512X0160Y    R180 S0      
317GND              VIA   -    MD0080PA00X+123504Y+110512X0160Y    R180 S0      
317GND              VIA   -    MD0080PA00X+122008Y+113130X0160Y    R090 S0      
317GND              VIA   -    MD0080PA00X+122382Y+113130X0160Y    R270 S0      
317GND              VIA   -    MD0080PA00X+122382Y+112756X0160Y    R090 S0      
317GND              VIA   -    MD0080PA00X+120886Y+112756X0160Y    R090 S0      
317GND              VIA   -    MD0080PA00X+121634Y+113130X0160Y         S0      
317GND              VIA   -    MD0080PA00X+121260Y+112756X0160Y    R270 S0      
317GND              VIA   -    MD0080PA00X+122382Y+112008X0160Y    R090 S0      
317GND              VIA   -    MD0080PA00X+122008Y+112382X0160Y    R090 S0      
317GND              VIA   -    MD0080PA00X+122382Y+112382X0160Y    R270 S0      
317GND              VIA   -    MD0080PA00X+122382Y+111260X0160Y    R090 S0      
317GND              VIA   -    MD0080PA00X+122008Y+111634X0160Y    R090 S0      
317GND              VIA   -    MD0080PA00X+122382Y+111634X0160Y    R270 S0      
317GND              VIA   -    MD0080PA00X+122382Y+110886X0160Y    R270 S0      
317GND              VIA   -    MD0080PA00X+122008Y+110886X0160Y         S0      
317GND              VIA   -    MD0080PA00X+120886Y+112008X0160Y         S0      
317GND              VIA   -    MD0080PA00X+120886Y+111260X0160Y         S0      
317GND              VIA   -    MD0080PA00X+121634Y+112382X0160Y         S0      
317GND              VIA   -    MD0080PA00X+121260Y+112008X0160Y    R090 S0      
317GND              VIA   -    MD0080PA00X+121634Y+111634X0160Y         S0      
317GND              VIA   -    MD0080PA00X+121634Y+110886X0160Y    R090 S0      
317GND              VIA   -    MD0080PA00X+121260Y+110886X0160Y         S0      
317GND              VIA   -    MD0080PA00X+123130Y+110512X0160Y    R270 S0      
317GND              VIA   -    MD0080PA00X+120886Y+110512X0160Y         S0      
317GND              VIA   -    MD0080PA00X+122382Y+110512X0160Y         S0      
317GND              VIA   -    MD0080PA00X+121634Y+110512X0160Y         S0      
317GND              VIA   -    MD0080PA00X+119390Y+110512X0160Y         S0      
317GND              VIA   -    MD0080PA00X+120138Y+110512X0160Y         S0      
317GND              VIA   -    MD0080PA00X+118642Y+110512X0160Y         S0      
317GND              VIA   -    MD0080PA00X+117894Y+110512X0160Y         S0      
317GND              VIA   -    MD0080PA00X+117146Y+110512X0160Y         S0      
317GND              VIA   -    MD0080PA00X+116398Y+110512X0160Y         S0      
317GND              VIA   -    MD0080PA00X+115650Y+110512X0160Y         S0      
317GND              VIA   -    MD0080PA00X+114902Y+110512X0160Y         S0      
317GND              VIA   -    MD0080PA00X+114154Y+110512X0160Y         S0      
317GND              VIA   -    MD0080PA00X+113405Y+110512X0160Y         S0      
317GND              VIA   -    MD0080PA00X+111161Y+110512X0160Y         S0      
317GND              VIA   -    MD0080PA00X+112657Y+110512X0160Y         S0      
317GND              VIA   -    MD0080PA00X+111909Y+110512X0160Y         S0      
317GND              VIA   -    MD0080PA00X+109665Y+110512X0160Y         S0      
317GND              VIA   -    MD0080PA00X+110413Y+110512X0160Y         S0      
317GND              VIA   -    MD0080PA00X+123504Y+109764X0160Y    R180 S0      
317GND              VIA   -    MD0080PA00X+123878Y+109764X0160Y    R180 S0      
317GND              VIA   -    MD0080PA00X+123878Y+109390X0160Y    R180 S0      
317GND              VIA   -    MD0080PA00X+123504Y+109390X0160Y    R180 S0      
317GND              VIA   -    MD0080PA00X+123130Y+110138X0160Y    R270 S0      
317GND              VIA   -    MD0080PA00X+122756Y+109764X0160Y    R180 S0      
317GND              VIA   -    MD0080PA00X+122756Y+109390X0160Y         S0      
317GND              VIA   -    MD0080PA00X+123878Y+107894X0160Y         S0      
317GND              VIA   -    MD0080PA00X+123130Y+109016X0160Y    R270 S0      
317GND              VIA   -    MD0080PA00X+122756Y+109016X0160Y         S0      
317GND              VIA   -    MD0080PA00X+123130Y+108642X0160Y    R180 S0      
317GND              VIA   -    MD0080PA00X+123504Y+108642X0160Y    R180 S0      
317GND              VIA   -    MD0080PA00X+123878Y+108642X0160Y    R180 S0      
317GND              VIA   -    MD0080PA00X+123130Y+108268X0160Y    R180 S0      
317GND              VIA   -    MD0080PA00X+122756Y+107894X0160Y         S0      
317GND              VIA   -    MD0080PA00X+123504Y+107894X0160Y         S0      
317GND              VIA   -    MD0080PA00X+123504Y+107520X0160Y         S0      
317GND              VIA   -    MD0080PA00X+122756Y+107520X0160Y         S0      
317GND              VIA   -    MD0080PA00X+120886Y+110138X0160Y    R270 S0      
317GND              VIA   -    MD0080PA00X+121634Y+110138X0160Y    R270 S0      
317GND              VIA   -    MD0080PA00X+122382Y+110138X0160Y    R270 S0      
317GND              VIA   -    MD0080PA00X+122008Y+109764X0160Y    R180 S0      
317GND              VIA   -    MD0080PA00X+121260Y+109764X0160Y    R180 S0      
317GND              VIA   -    MD0080PA00X+122008Y+109390X0160Y         S0      
317GND              VIA   -    MD0080PA00X+121260Y+109390X0160Y         S0      
317GND              VIA   -    MD0080PA00X+120886Y+109016X0160Y    R180 S0      
317GND              VIA   -    MD0080PA00X+120886Y+108642X0160Y    R180 S0      
317GND              VIA   -    MD0080PA00X+120886Y+108268X0160Y    R180 S0      
317GND              VIA   -    MD0080PA00X+122382Y+109016X0160Y    R270 S0      
317GND              VIA   -    MD0080PA00X+122008Y+109016X0160Y    R270 S0      
317GND              VIA   -    MD0080PA00X+121634Y+109016X0160Y    R270 S0      
317GND              VIA   -    MD0080PA00X+121260Y+109016X0160Y         S0      
317GND              VIA   -    MD0080PA00X+122382Y+108642X0160Y    R180 S0      
317GND              VIA   -    MD0080PA00X+121634Y+108642X0160Y    R180 S0      
317GND              VIA   -    MD0080PA00X+121634Y+108268X0160Y    R180 S0      
317GND              VIA   -    MD0080PA00X+122382Y+108268X0160Y    R180 S0      
317GND              VIA   -    MD0080PA00X+121260Y+107894X0160Y         S0      
317GND              VIA   -    MD0080PA00X+122008Y+107894X0160Y         S0      
317GND              VIA   -    MD0080PA00X+122008Y+107520X0160Y         S0      
317GND              VIA   -    MD0080PA00X+121260Y+107520X0160Y         S0      
317GND              VIA   -    MD0080PA00X+119390Y+110138X0160Y    R270 S0      
317GND              VIA   -    MD0080PA00X+120512Y+109764X0160Y    R180 S0      
317GND              VIA   -    MD0080PA00X+120512Y+109390X0160Y         S0      
317GND              VIA   -    MD0080PA00X+119764Y+109390X0160Y    R180 S0      
317GND              VIA   -    MD0080PA00X+120138Y+110138X0160Y         S0      
317GND              VIA   -    MD0080PA00X+119764Y+109764X0160Y    R270 S0      
317GND              VIA   -    MD0080PA00X+119390Y+109016X0160Y         S0      
317GND              VIA   -    MD0080PA00X+119390Y+108642X0160Y    R180 S0      
317GND              VIA   -    MD0080PA00X+119390Y+108268X0160Y    R180 S0      
317GND              VIA   -    MD0080PA00X+120512Y+109016X0160Y         S0      
317GND              VIA   -    MD0080PA00X+120512Y+107894X0160Y    R180 S0      
317GND              VIA   -    MD0080PA00X+120138Y+108268X0160Y    R180 S0      
317GND              VIA   -    MD0080PA00X+120138Y+108642X0160Y    R270 S0      
317GND              VIA   -    MD0080PA00X+120138Y+109016X0160Y         S0      
317GND              VIA   -    MD0080PA00X+119764Y+109016X0160Y         S0      
317GND              VIA   -    MD0080PA00X+119764Y+107894X0160Y         S0      
317GND              VIA   -    MD0080PA00X+120512Y+107520X0160Y         S0      
317GND              VIA   -    MD0080PA00X+119764Y+107520X0160Y         S0      
317GND              VIA   -    MD0080PA00X+119016Y+109764X0160Y    R180 S0      
317GND              VIA   -    MD0080PA00X+119016Y+109390X0160Y         S0      
317GND              VIA   -    MD0080PA00X+118268Y+109390X0160Y         S0      
317GND              VIA   -    MD0080PA00X+118268Y+109764X0160Y         S0      
317GND              VIA   -    MD0080PA00X+118642Y+110138X0160Y    R270 S0      
317GND              VIA   -    MD0080PA00X+117894Y+110138X0160Y    R270 S0      
317GND              VIA   -    MD0080PA00X+119016Y+109016X0160Y         S0      
317GND              VIA   -    MD0080PA00X+119016Y+107894X0160Y    R180 S0      
317GND              VIA   -    MD0080PA00X+118642Y+108268X0160Y         S0      
317GND              VIA   -    MD0080PA00X+118642Y+108642X0160Y         S0      
317GND              VIA   -    MD0080PA00X+118642Y+109016X0160Y         S0      
317GND              VIA   -    MD0080PA00X+118268Y+109016X0160Y         S0      
317GND              VIA   -    MD0080PA00X+117894Y+108642X0160Y         S0      
317GND              VIA   -    MD0080PA00X+117894Y+108268X0160Y    R180 S0      
317GND              VIA   -    MD0080PA00X+118268Y+107894X0160Y         S0      
317GND              VIA   -    MD0080PA00X+117894Y+109016X0160Y         S0      
317GND              VIA   -    MD0080PA00X+119016Y+107520X0160Y         S0      
317GND              VIA   -    MD0080PA00X+118268Y+107520X0160Y         S0      
317GND              VIA   -    MD0080PA00X+116024Y+109764X0160Y         S0      
317GND              VIA   -    MD0080PA00X+116024Y+109390X0160Y         S0      
317GND              VIA   -    MD0080PA00X+117520Y+109390X0160Y         S0      
317GND              VIA   -    MD0080PA00X+117520Y+109764X0160Y         S0      
317GND              VIA   -    MD0080PA00X+116772Y+109390X0160Y         S0      
317GND              VIA   -    MD0080PA00X+116772Y+109764X0160Y         S0      
317GND              VIA   -    MD0080PA00X+117146Y+110138X0160Y    R270 S0      
317GND              VIA   -    MD0080PA00X+116398Y+110138X0160Y    R180 S0      
317GND              VIA   -    MD0080PA00X+116024Y+109016X0160Y         S0      
317GND              VIA   -    MD0080PA00X+116024Y+107894X0160Y         S0      
317GND              VIA   -    MD0080PA00X+117520Y+109016X0160Y         S0      
317GND              VIA   -    MD0080PA00X+116772Y+109016X0160Y         S0      
317GND              VIA   -    MD0080PA00X+117146Y+109016X0160Y         S0      
317GND              VIA   -    MD0080PA00X+117146Y+108642X0160Y         S0      
317GND              VIA   -    MD0080PA00X+117146Y+108268X0160Y    R180 S0      
317GND              VIA   -    MD0080PA00X+117520Y+107894X0160Y         S0      
317GND              VIA   -    MD0080PA00X+116398Y+109016X0160Y         S0      
317GND              VIA   -    MD0080PA00X+116398Y+108642X0160Y         S0      
317GND              VIA   -    MD0080PA00X+116398Y+108268X0160Y    R180 S0      
317GND              VIA   -    MD0080PA00X+116772Y+107894X0160Y         S0      
317GND              VIA   -    MD0080PA00X+116024Y+107520X0160Y         S0      
317GND              VIA   -    MD0080PA00X+117520Y+107520X0160Y         S0      
317GND              VIA   -    MD0080PA00X+116772Y+107520X0160Y         S0      
317GND              VIA   -    MD0080PA00X+114528Y+109764X0160Y         S0      
317GND              VIA   -    MD0080PA00X+114528Y+109390X0160Y         S0      
317GND              VIA   -    MD0080PA00X+115650Y+110138X0160Y         S0      
317GND              VIA   -    MD0080PA00X+115276Y+109764X0160Y    R180 S0      
317GND              VIA   -    MD0080PA00X+115276Y+109390X0160Y         S0      
317GND              VIA   -    MD0080PA00X+114902Y+110138X0160Y         S0      
317GND              VIA   -    MD0080PA00X+114528Y+107894X0160Y    R270 S0      
317GND              VIA   -    MD0080PA00X+114528Y+109016X0160Y         S0      
317GND              VIA   -    MD0080PA00X+115650Y+108268X0160Y    R180 S0      
317GND              VIA   -    MD0080PA00X+115276Y+107894X0160Y    R180 S0      
317GND              VIA   -    MD0080PA00X+114902Y+109016X0160Y         S0      
317GND              VIA   -    MD0080PA00X+115650Y+108642X0160Y         S0      
317GND              VIA   -    MD0080PA00X+115650Y+109016X0160Y         S0      
317GND              VIA   -    MD0080PA00X+115276Y+109016X0160Y         S0      
317GND              VIA   -    MD0080PA00X+114902Y+108642X0160Y         S0      
317GND              VIA   -    MD0080PA00X+114902Y+108268X0160Y         S0      
317GND              VIA   -    MD0080PA00X+114528Y+107520X0160Y    R270 S0      
317GND              VIA   -    MD0080PA00X+115276Y+107520X0160Y         S0      
317GND              VIA   -    MD0080PA00X+114154Y+110138X0160Y         S0      
317GND              VIA   -    MD0080PA00X+113405Y+110138X0160Y         S0      
317GND              VIA   -    MD0080PA00X+113780Y+109764X0160Y         S0      
317GND              VIA   -    MD0080PA00X+113780Y+109390X0160Y         S0      
317GND              VIA   -    MD0080PA00X+113031Y+109390X0160Y         S0      
317GND              VIA   -    MD0080PA00X+113031Y+109764X0160Y         S0      
317GND              VIA   -    MD0080PA00X+114154Y+109016X0160Y         S0      
317GND              VIA   -    MD0080PA00X+114154Y+108642X0160Y    R270 S0      
317GND              VIA   -    MD0080PA00X+114154Y+108268X0160Y    R270 S0      
317GND              VIA   -    MD0080PA00X+113780Y+107894X0160Y    R270 S0      
317GND              VIA   -    MD0080PA00X+113780Y+109016X0160Y         S0      
317GND              VIA   -    MD0080PA00X+113405Y+109016X0160Y         S0      
317GND              VIA   -    MD0080PA00X+113405Y+108642X0160Y    R270 S0      
317GND              VIA   -    MD0080PA00X+113405Y+108268X0160Y    R270 S0      
317GND              VIA   -    MD0080PA00X+113031Y+107894X0160Y    R270 S0      
317GND              VIA   -    MD0080PA00X+113031Y+109016X0160Y         S0      
317GND              VIA   -    MD0080PA00X+113780Y+107520X0160Y    R270 S0      
317GND              VIA   -    MD0080PA00X+113031Y+107520X0160Y    R270 S0      
317GND              VIA   -    MD0080PA00X+111161Y+110138X0160Y         S0      
317GND              VIA   -    MD0080PA00X+112657Y+110138X0160Y         S0      
317GND              VIA   -    MD0080PA00X+111909Y+110138X0160Y         S0      
317GND              VIA   -    MD0080PA00X+111535Y+109764X0160Y         S0      
317GND              VIA   -    MD0080PA00X+112283Y+109764X0160Y         S0      
317GND              VIA   -    MD0080PA00X+111535Y+109390X0160Y         S0      
317GND              VIA   -    MD0080PA00X+112283Y+109390X0160Y         S0      
317GND              VIA   -    MD0080PA00X+111161Y+109016X0160Y         S0      
317GND              VIA   -    MD0080PA00X+111161Y+108642X0160Y    R270 S0      
317GND              VIA   -    MD0080PA00X+111161Y+108268X0160Y    R270 S0      
317GND              VIA   -    MD0080PA00X+112283Y+107894X0160Y    R270 S0      
317GND              VIA   -    MD0080PA00X+112657Y+108268X0160Y    R270 S0      
317GND              VIA   -    MD0080PA00X+112657Y+108642X0160Y    R270 S0      
317GND              VIA   -    MD0080PA00X+112657Y+109016X0160Y         S0      
317GND              VIA   -    MD0080PA00X+112283Y+109016X0160Y         S0      
317GND              VIA   -    MD0080PA00X+111909Y+109016X0160Y         S0      
317GND              VIA   -    MD0080PA00X+111909Y+108642X0160Y    R270 S0      
317GND              VIA   -    MD0080PA00X+111909Y+108268X0160Y    R270 S0      
317GND              VIA   -    MD0080PA00X+111535Y+107894X0160Y    R270 S0      
317GND              VIA   -    MD0080PA00X+111535Y+109016X0160Y         S0      
317GND              VIA   -    MD0080PA00X+112283Y+107520X0160Y    R270 S0      
317GND              VIA   -    MD0080PA00X+111535Y+107520X0160Y    R270 S0      
317GND              VIA   -    MD0080PA00X+109665Y+110138X0160Y         S0      
317GND              VIA   -    MD0080PA00X+110039Y+109390X0160Y         S0      
317GND              VIA   -    MD0080PA00X+110039Y+109764X0160Y         S0      
317GND              VIA   -    MD0080PA00X+110413Y+110138X0160Y         S0      
317GND              VIA   -    MD0080PA00X+110787Y+109764X0160Y         S0      
317GND              VIA   -    MD0080PA00X+110787Y+109390X0160Y         S0      
317GND              VIA   -    MD0080PA00X+109665Y+109016X0160Y         S0      
317GND              VIA   -    MD0080PA00X+109665Y+108642X0160Y    R270 S0      
317GND              VIA   -    MD0080PA00X+109665Y+108268X0160Y    R270 S0      
317GND              VIA   -    MD0080PA00X+110039Y+109016X0160Y         S0      
317GND              VIA   -    MD0080PA00X+110039Y+107894X0160Y    R270 S0      
317GND              VIA   -    MD0080PA00X+110787Y+107894X0160Y    R270 S0      
317GND              VIA   -    MD0080PA00X+110787Y+109016X0160Y         S0      
317GND              VIA   -    MD0080PA00X+110413Y+108268X0160Y    R270 S0      
317GND              VIA   -    MD0080PA00X+110413Y+109016X0160Y         S0      
317GND              VIA   -    MD0080PA00X+110413Y+108642X0160Y    R270 S0      
317GND              VIA   -    MD0080PA00X+110039Y+107520X0160Y    R270 S0      
317GND              VIA   -    MD0080PA00X+110787Y+107520X0160Y    R270 S0      
317GND              VIA   -    MD0080PA00X+108917Y+110138X0160Y         S0      
317GND              VIA   -    MD0080PA00X+109291Y+109764X0160Y         S0      
317GND              VIA   -    MD0080PA00X+109291Y+109390X0160Y         S0      
317GND              VIA   -    MD0080PA00X+109291Y+109016X0160Y         S0      
317GND              VIA   -    MD0080PA00X+108917Y+109016X0160Y         S0      
317GND              VIA   -    MD0080PA00X+109291Y+107894X0160Y    R270 S0      
317GND              VIA   -    MD0080PA00X+108917Y+108642X0160Y    R270 S0      
317GND              VIA   -    MD0080PA00X+108917Y+108268X0160Y    R270 S0      
317GND              VIA   -    MD0080PA00X+109291Y+107520X0160Y    R270 S0      
317GND              VIA   -    MD0080PA00X+122569Y+122293X0160Y         S0      
317GND              VIA   -    MD0080PA00X+122756Y+121358X0160Y    R090 S0      
317GND              VIA   -    MD0080PA00X+123130Y+121358X0160Y    R270 S0      
317GND              VIA   -    MD0080PA00X+123504Y+120984X0160Y         S0      
317GND              VIA   -    MD0080PA00X+123878Y+120984X0160Y    R090 S0      
317GND              VIA   -    MD0080PA00X+122756Y+122106X0160Y         S0      
317GND              VIA   -    MD0080PA00X+123130Y+122106X0160Y    R090 S0      
317GND              VIA   -    MD0080PA00X+123504Y+121732X0160Y    R090 S0      
317GND              VIA   -    MD0080PA00X+123878Y+121732X0160Y    R090 S0      
317GND              VIA   -    MD0080PA00X+122756Y+119862X0160Y    R090 S0      
317GND              VIA   -    MD0080PA00X+123130Y+119862X0160Y    R270 S0      
317GND              VIA   -    MD0080PA00X+122756Y+120610X0160Y    R090 S0      
317GND              VIA   -    MD0080PA00X+123130Y+120610X0160Y    R270 S0      
317GND              VIA   -    MD0080PA00X+123504Y+120236X0160Y         S0      
317GND              VIA   -    MD0080PA00X+123878Y+120236X0160Y         S0      
317GND              VIA   -    MD0080PA00X+120886Y+120984X0160Y    R090 S0      
317GND              VIA   -    MD0080PA00X+120886Y+121732X0160Y         S0      
317GND              VIA   -    MD0080PA00X+120886Y+122106X0160Y         S0      
317GND              VIA   -    MD0080PA00X+121260Y+120984X0160Y         S0      
317GND              VIA   -    MD0080PA00X+122382Y+120984X0160Y         S0      
317GND              VIA   -    MD0080PA00X+122382Y+121358X0160Y         S0      
317GND              VIA   -    MD0080PA00X+122008Y+121358X0160Y         S0      
317GND              VIA   -    MD0080PA00X+121634Y+121358X0160Y    R090 S0      
317GND              VIA   -    MD0080PA00X+121260Y+121732X0160Y    R090 S0      
317GND              VIA   -    MD0080PA00X+121260Y+122106X0160Y    R090 S0      
317GND              VIA   -    MD0080PA00X+121634Y+122106X0160Y         S0      
317GND              VIA   -    MD0080PA00X+122008Y+122106X0160Y         S0      
317GND              VIA   -    MD0080PA00X+122382Y+121732X0160Y         S0      
317GND              VIA   -    MD0080PA00X+122382Y+122106X0160Y         S0      
317GND              VIA   -    MD0080PA00X+120886Y+120236X0160Y    R090 S0      
317GND              VIA   -    MD0080PA00X+121634Y+119862X0160Y    R090 S0      
317GND              VIA   -    MD0080PA00X+122008Y+119862X0160Y         S0      
317GND              VIA   -    MD0080PA00X+122382Y+119862X0160Y         S0      
317GND              VIA   -    MD0080PA00X+122382Y+120236X0160Y         S0      
317GND              VIA   -    MD0080PA00X+121260Y+120236X0160Y         S0      
317GND              VIA   -    MD0080PA00X+121634Y+120610X0160Y    R090 S0      
317GND              VIA   -    MD0080PA00X+122008Y+120610X0160Y    R090 S0      
317GND              VIA   -    MD0080PA00X+122382Y+120610X0160Y         S0      
317GND              VIA   -    MD0080PA00X+123504Y+125472X0160Y    R180 S0      
317GND              VIA   -    MD0080PA00X+123130Y+123976X0160Y    R180 S0      
317GND              VIA   -    MD0080PA00X+122756Y+123976X0160Y    R270 S0      
317GND              VIA   -    MD0080PA00X+123878Y+124350X0160Y    R090 S0      
317GND              VIA   -    MD0080PA00X+123504Y+124350X0160Y    R270 S0      
317GND              VIA   -    MD0080PA00X+123130Y+124350X0160Y    R180 S0      
317GND              VIA   -    MD0080PA00X+123130Y+124724X0160Y    R180 S0      
317GND              VIA   -    MD0080PA00X+123504Y+125098X0160Y    R180 S0      
317GND              VIA   -    MD0080PA00X+123878Y+125098X0160Y         S0      
317GND              VIA   -    MD0080PA00X+122756Y+125472X0160Y    R180 S0      
317GND              VIA   -    MD0080PA00X+122756Y+125098X0160Y    R180 S0      
317GND              VIA   -    MD0080PA00X+123878Y+123602X0160Y    R090 S0      
317GND              VIA   -    MD0080PA00X+123504Y+123602X0160Y    R090 S0      
317GND              VIA   -    MD0080PA00X+123504Y+123228X0160Y         S0      
317GND              VIA   -    MD0080PA00X+123878Y+123228X0160Y    R090 S0      
317GND              VIA   -    MD0080PA00X+122756Y+123228X0160Y         S0      
317GND              VIA   -    MD0080PA00X+122756Y+123602X0160Y         S0      
317GND              VIA   -    MD0080PA00X+123130Y+122854X0160Y         S0      
317GND              VIA   -    MD0080PA00X+123130Y+122480X0160Y         S0      
317GND              VIA   -    MD0080PA00X+123504Y+122480X0160Y    R090 S0      
317GND              VIA   -    MD0080PA00X+123878Y+122480X0160Y    R090 S0      
317GND              VIA   -    MD0080PA00X+120886Y+123976X0160Y    R270 S0      
317GND              VIA   -    MD0080PA00X+120886Y+124350X0160Y    R180 S0      
317GND              VIA   -    MD0080PA00X+120886Y+124724X0160Y    R180 S0      
317GND              VIA   -    MD0080PA00X+122382Y+123976X0160Y         S0      
317GND              VIA   -    MD0080PA00X+122008Y+123976X0160Y    R270 S0      
317GND              VIA   -    MD0080PA00X+121634Y+123976X0160Y    R180 S0      
317GND              VIA   -    MD0080PA00X+121260Y+123976X0160Y         S0      
317GND              VIA   -    MD0080PA00X+122382Y+124350X0160Y    R180 S0      
317GND              VIA   -    MD0080PA00X+122382Y+124724X0160Y    R180 S0      
317GND              VIA   -    MD0080PA00X+122008Y+125472X0160Y    R180 S0      
317GND              VIA   -    MD0080PA00X+122008Y+125098X0160Y    R180 S0      
317GND              VIA   -    MD0080PA00X+121634Y+124350X0160Y    R180 S0      
317GND              VIA   -    MD0080PA00X+121634Y+124724X0160Y    R180 S0      
317GND              VIA   -    MD0080PA00X+121260Y+125472X0160Y    R180 S0      
317GND              VIA   -    MD0080PA00X+121260Y+125098X0160Y    R180 S0      
317GND              VIA   -    MD0080PA00X+120886Y+122854X0160Y         S0      
317GND              VIA   -    MD0080PA00X+120886Y+122480X0160Y         S0      
317GND              VIA   -    MD0080PA00X+122008Y+123602X0160Y         S0      
317GND              VIA   -    MD0080PA00X+122008Y+123228X0160Y         S0      
317GND              VIA   -    MD0080PA00X+122382Y+122854X0160Y         S0      
317GND              VIA   -    MD0080PA00X+122382Y+122480X0160Y         S0      
317GND              VIA   -    MD0080PA00X+121260Y+123602X0160Y         S0      
317GND              VIA   -    MD0080PA00X+121260Y+123228X0160Y         S0      
317GND              VIA   -    MD0080PA00X+121634Y+122854X0160Y         S0      
317GND              VIA   -    MD0080PA00X+121634Y+122480X0160Y         S0      
317GND              VIA   -    MD0080PA00X+119390Y+124350X0160Y    R180 S0      
317GND              VIA   -    MD0080PA00X+119390Y+123976X0160Y    R270 S0      
317GND              VIA   -    MD0080PA00X+119390Y+124724X0160Y    R180 S0      
317GND              VIA   -    MD0080PA00X+120512Y+123976X0160Y         S0      
317GND              VIA   -    MD0080PA00X+120138Y+124350X0160Y    R180 S0      
317GND              VIA   -    MD0080PA00X+120138Y+123976X0160Y    R180 S0      
317GND              VIA   -    MD0080PA00X+119764Y+123976X0160Y         S0      
317GND              VIA   -    MD0080PA00X+120512Y+125472X0160Y    R180 S0      
317GND              VIA   -    MD0080PA00X+120512Y+125098X0160Y    R180 S0      
317GND              VIA   -    MD0080PA00X+120138Y+124724X0160Y    R180 S0      
317GND              VIA   -    MD0080PA00X+119764Y+125472X0160Y    R180 S0      
317GND              VIA   -    MD0080PA00X+119764Y+125098X0160Y    R180 S0      
317GND              VIA   -    MD0080PA00X+119390Y+122480X0160Y         S0      
317GND              VIA   -    MD0080PA00X+119390Y+122854X0160Y         S0      
317GND              VIA   -    MD0080PA00X+120512Y+123602X0160Y         S0      
317GND              VIA   -    MD0080PA00X+120512Y+123228X0160Y         S0      
317GND              VIA   -    MD0080PA00X+120138Y+122480X0160Y         S0      
317GND              VIA   -    MD0080PA00X+119764Y+123602X0160Y         S0      
317GND              VIA   -    MD0080PA00X+120138Y+122854X0160Y         S0      
317GND              VIA   -    MD0080PA00X+119764Y+123228X0160Y         S0      
317GND              VIA   -    MD0080PA00X+119016Y+123976X0160Y    R270 S0      
317GND              VIA   -    MD0080PA00X+118642Y+124350X0160Y    R180 S0      
317GND              VIA   -    MD0080PA00X+117894Y+124350X0160Y    R180 S0      
317GND              VIA   -    MD0080PA00X+118268Y+123976X0160Y         S0      
317GND              VIA   -    MD0080PA00X+118642Y+123976X0160Y    R180 S0      
317GND              VIA   -    MD0080PA00X+117894Y+123976X0160Y    R270 S0      
317GND              VIA   -    MD0080PA00X+118642Y+124724X0160Y    R180 S0      
317GND              VIA   -    MD0080PA00X+119016Y+125098X0160Y    R180 S0      
317GND              VIA   -    MD0080PA00X+119016Y+125472X0160Y    R180 S0      
317GND              VIA   -    MD0080PA00X+118268Y+125472X0160Y    R180 S0      
317GND              VIA   -    MD0080PA00X+118268Y+125098X0160Y    R180 S0      
317GND              VIA   -    MD0080PA00X+117894Y+124724X0160Y    R180 S0      
317GND              VIA   -    MD0080PA00X+118642Y+122480X0160Y         S0      
317GND              VIA   -    MD0080PA00X+118642Y+122854X0160Y         S0      
317GND              VIA   -    MD0080PA00X+119016Y+123602X0160Y         S0      
317GND              VIA   -    MD0080PA00X+119016Y+123228X0160Y         S0      
317GND              VIA   -    MD0080PA00X+118268Y+123602X0160Y         S0      
317GND              VIA   -    MD0080PA00X+118268Y+123228X0160Y         S0      
317GND              VIA   -    MD0080PA00X+117894Y+122480X0160Y         S0      
317GND              VIA   -    MD0080PA00X+117894Y+122854X0160Y         S0      
317GND              VIA   -    MD0080PA00X+116024Y+125472X0160Y    R180 S0      
317GND              VIA   -    MD0080PA00X+116024Y+125098X0160Y    R180 S0      
317GND              VIA   -    MD0080PA00X+116024Y+123976X0160Y         S0      
317GND              VIA   -    MD0080PA00X+117146Y+123976X0160Y         S0      
317GND              VIA   -    MD0080PA00X+117520Y+125098X0160Y    R180 S0      
317GND              VIA   -    MD0080PA00X+117520Y+123976X0160Y    R180 S0      
317GND              VIA   -    MD0080PA00X+117146Y+124350X0160Y    R270 S0      
317GND              VIA   -    MD0080PA00X+117146Y+124724X0160Y    R180 S0      
317GND              VIA   -    MD0080PA00X+116772Y+125472X0160Y    R180 S0      
317GND              VIA   -    MD0080PA00X+116772Y+125098X0160Y    R180 S0      
317GND              VIA   -    MD0080PA00X+116772Y+123976X0160Y    R180 S0      
317GND              VIA   -    MD0080PA00X+116398Y+124724X0160Y    R180 S0      
317GND              VIA   -    MD0080PA00X+116398Y+124350X0160Y    R270 S0      
317GND              VIA   -    MD0080PA00X+116398Y+123976X0160Y    R180 S0      
317GND              VIA   -    MD0080PA00X+117520Y+125472X0160Y    R180 S0      
317GND              VIA   -    MD0080PA00X+116024Y+123602X0160Y         S0      
317GND              VIA   -    MD0080PA00X+116024Y+123228X0160Y         S0      
317GND              VIA   -    MD0080PA00X+116772Y+123602X0160Y         S0      
317GND              VIA   -    MD0080PA00X+117520Y+123602X0160Y         S0      
317GND              VIA   -    MD0080PA00X+117520Y+123228X0160Y         S0      
317GND              VIA   -    MD0080PA00X+116772Y+123228X0160Y         S0      
317GND              VIA   -    MD0080PA00X+117146Y+122480X0160Y         S0      
317GND              VIA   -    MD0080PA00X+117146Y+122854X0160Y         S0      
317GND              VIA   -    MD0080PA00X+116398Y+122480X0160Y         S0      
317GND              VIA   -    MD0080PA00X+116398Y+122854X0160Y         S0      
317GND              VIA   -    MD0080PA00X+114528Y+125472X0160Y    R270 S0      
317GND              VIA   -    MD0080PA00X+114528Y+125098X0160Y    R270 S0      
317GND              VIA   -    MD0080PA00X+114528Y+123976X0160Y         S0      
317GND              VIA   -    MD0080PA00X+115650Y+124724X0160Y    R180 S0      
317GND              VIA   -    MD0080PA00X+115650Y+124350X0160Y    R180 S0      
317GND              VIA   -    MD0080PA00X+115650Y+123976X0160Y    R270 S0      
317GND              VIA   -    MD0080PA00X+115276Y+123976X0160Y         S0      
317GND              VIA   -    MD0080PA00X+114902Y+123976X0160Y    R270 S0      
317GND              VIA   -    MD0080PA00X+114902Y+124350X0160Y    R270 S0      
317GND              VIA   -    MD0080PA00X+114902Y+124724X0160Y    R180 S0      
317GND              VIA   -    MD0080PA00X+115276Y+125098X0160Y    R180 S0      
317GND              VIA   -    MD0080PA00X+115276Y+125472X0160Y    R180 S0      
317GND              VIA   -    MD0080PA00X+114528Y+123602X0160Y         S0      
317GND              VIA   -    MD0080PA00X+114528Y+123228X0160Y         S0      
317GND              VIA   -    MD0080PA00X+114902Y+122480X0160Y         S0      
317GND              VIA   -    MD0080PA00X+114902Y+122854X0160Y         S0      
317GND              VIA   -    MD0080PA00X+115650Y+122480X0160Y         S0      
317GND              VIA   -    MD0080PA00X+115650Y+122854X0160Y         S0      
317GND              VIA   -    MD0080PA00X+115276Y+123602X0160Y         S0      
317GND              VIA   -    MD0080PA00X+115276Y+123228X0160Y         S0      
317GND              VIA   -    MD0080PA00X+113031Y+123976X0160Y         S0      
317GND              VIA   -    MD0080PA00X+113405Y+123976X0160Y    R270 S0      
317GND              VIA   -    MD0080PA00X+113780Y+123976X0160Y         S0      
317GND              VIA   -    MD0080PA00X+113780Y+125472X0160Y    R270 S0      
317GND              VIA   -    MD0080PA00X+113780Y+125098X0160Y    R270 S0      
317GND              VIA   -    MD0080PA00X+113405Y+124350X0160Y         S0      
317GND              VIA   -    MD0080PA00X+113405Y+124724X0160Y    R270 S0      
317GND              VIA   -    MD0080PA00X+113031Y+125472X0160Y    R270 S0      
317GND              VIA   -    MD0080PA00X+113031Y+125098X0160Y    R270 S0      
317GND              VIA   -    MD0080PA00X+114154Y+124724X0160Y    R270 S0      
317GND              VIA   -    MD0080PA00X+114154Y+124350X0160Y         S0      
317GND              VIA   -    MD0080PA00X+114154Y+123976X0160Y    R270 S0      
317GND              VIA   -    MD0080PA00X+113031Y+123602X0160Y         S0      
317GND              VIA   -    MD0080PA00X+113031Y+123228X0160Y         S0      
317GND              VIA   -    MD0080PA00X+113405Y+122480X0160Y         S0      
317GND              VIA   -    MD0080PA00X+113405Y+122854X0160Y    R090 S0      
317GND              VIA   -    MD0080PA00X+113780Y+123602X0160Y         S0      
317GND              VIA   -    MD0080PA00X+113780Y+123228X0160Y         S0      
317GND              VIA   -    MD0080PA00X+114154Y+122480X0160Y         S0      
317GND              VIA   -    MD0080PA00X+114154Y+122854X0160Y    R090 S0      
317GND              VIA   -    MD0080PA00X+111161Y+123976X0160Y         S0      
317GND              VIA   -    MD0080PA00X+111161Y+124350X0160Y         S0      
317GND              VIA   -    MD0080PA00X+111161Y+124724X0160Y    R270 S0      
317GND              VIA   -    MD0080PA00X+111909Y+123976X0160Y    R270 S0      
317GND              VIA   -    MD0080PA00X+111535Y+123976X0160Y    R270 S0      
317GND              VIA   -    MD0080PA00X+112657Y+123976X0160Y    R270 S0      
317GND              VIA   -    MD0080PA00X+112283Y+123976X0160Y         S0      
317GND              VIA   -    MD0080PA00X+112283Y+125098X0160Y    R270 S0      
317GND              VIA   -    MD0080PA00X+112283Y+125472X0160Y    R270 S0      
317GND              VIA   -    MD0080PA00X+112657Y+124724X0160Y    R270 S0      
317GND              VIA   -    MD0080PA00X+112657Y+124350X0160Y         S0      
317GND              VIA   -    MD0080PA00X+111909Y+124350X0160Y         S0      
317GND              VIA   -    MD0080PA00X+111909Y+124724X0160Y    R270 S0      
317GND              VIA   -    MD0080PA00X+111535Y+125472X0160Y    R270 S0      
317GND              VIA   -    MD0080PA00X+111535Y+125098X0160Y    R270 S0      
317GND              VIA   -    MD0080PA00X+111161Y+122480X0160Y         S0      
317GND              VIA   -    MD0080PA00X+111161Y+122854X0160Y    R090 S0      
317GND              VIA   -    MD0080PA00X+111535Y+123602X0160Y         S0      
317GND              VIA   -    MD0080PA00X+111535Y+123228X0160Y         S0      
317GND              VIA   -    MD0080PA00X+111909Y+122854X0160Y    R090 S0      
317GND              VIA   -    MD0080PA00X+111909Y+122480X0160Y         S0      
317GND              VIA   -    MD0080PA00X+112283Y+123602X0160Y         S0      
317GND              VIA   -    MD0080PA00X+112283Y+123228X0160Y         S0      
317GND              VIA   -    MD0080PA00X+112657Y+122854X0160Y    R090 S0      
317GND              VIA   -    MD0080PA00X+112657Y+122480X0160Y         S0      
317GND              VIA   -    MD0080PA00X+109665Y+124350X0160Y         S0      
317GND              VIA   -    MD0080PA00X+109665Y+123976X0160Y    R270 S0      
317GND              VIA   -    MD0080PA00X+109665Y+124724X0160Y    R270 S0      
317GND              VIA   -    MD0080PA00X+110413Y+124350X0160Y         S0      
317GND              VIA   -    MD0080PA00X+110787Y+123976X0160Y         S0      
317GND              VIA   -    MD0080PA00X+110413Y+123976X0160Y    R270 S0      
317GND              VIA   -    MD0080PA00X+110039Y+123976X0160Y         S0      
317GND              VIA   -    MD0080PA00X+110787Y+125472X0160Y    R270 S0      
317GND              VIA   -    MD0080PA00X+110787Y+125098X0160Y    R270 S0      
317GND              VIA   -    MD0080PA00X+110413Y+124724X0160Y    R270 S0      
317GND              VIA   -    MD0080PA00X+110039Y+125472X0160Y    R270 S0      
317GND              VIA   -    MD0080PA00X+110039Y+125098X0160Y    R270 S0      
317GND              VIA   -    MD0080PA00X+109665Y+122480X0160Y         S0      
317GND              VIA   -    MD0080PA00X+109665Y+122854X0160Y    R090 S0      
317GND              VIA   -    MD0080PA00X+110039Y+123602X0160Y         S0      
317GND              VIA   -    MD0080PA00X+110039Y+123228X0160Y         S0      
317GND              VIA   -    MD0080PA00X+110787Y+123602X0160Y         S0      
317GND              VIA   -    MD0080PA00X+110413Y+122854X0160Y    R090 S0      
317GND              VIA   -    MD0080PA00X+110413Y+122480X0160Y         S0      
317GND              VIA   -    MD0080PA00X+110787Y+123228X0160Y         S0      
317GND              VIA   -    MD0080PA00X+109291Y+123976X0160Y    R270 S0      
317GND              VIA   -    MD0080PA00X+109291Y+125472X0160Y    R270 S0      
317GND              VIA   -    MD0080PA00X+109291Y+125098X0160Y    R270 S0      
317GND              VIA   -    MD0080PA00X+109291Y+123602X0160Y         S0      
317GND              VIA   -    MD0080PA00X+109291Y+123228X0160Y         S0      
317GND              VIA   -    MD0080PA00X+108917Y+124724X0160Y         S0      
317GND              VIA   -    MD0080PA00X+108917Y+124350X0160Y    R270 S0      
317GND              VIA   -    MD0080PA00X+108917Y+123976X0160Y         S0      
317GND              VIA   -    MD0080PA00X+108543Y+123976X0160Y         S0      
317GND              VIA   -    MD0080PA00X+108543Y+125098X0160Y         S0      
317GND              VIA   -    MD0080PA00X+108169Y+124350X0160Y         S0      
317GND              VIA   -    MD0080PA00X+108169Y+123976X0160Y         S0      
317GND              VIA   -    MD0080PA00X+108543Y+125472X0160Y    R270 S0      
317GND              VIA   -    MD0080PA00X+108169Y+124724X0160Y    R270 S0      
317GND              VIA   -    MD0080PA00X+108917Y+122854X0160Y    R090 S0      
317GND              VIA   -    MD0080PA00X+108917Y+122480X0160Y         S0      
317GND              VIA   -    MD0080PA00X+108169Y+122480X0160Y         S0      
317GND              VIA   -    MD0080PA00X+108169Y+122854X0160Y    R090 S0      
317GND              VIA   -    MD0080PA00X+108543Y+123602X0160Y         S0      
317GND              VIA   -    MD0080PA00X+108543Y+123228X0160Y         S0      
317GND              VIA   -    MD0080PA00X+108543Y+121732X0160Y         S0      
317GND              VIA   -    MD0080PA00X+108543Y+122106X0160Y         S0      
317GND              VIA   -    MD0080PA00X+108169Y+122106X0160Y    R270 S0      
317GND              VIA   -    MD0080PA00X+108917Y+122106X0160Y         S0      
317GND              VIA   -    MD0080PA00X+108917Y+121732X0160Y         S0      
317GND              VIA   -    MD0080PA00X+106299Y+124350X0160Y    R270 S0      
317GND              VIA   -    MD0080PA00X+106299Y+125472X0160Y    R270 S0      
317GND              VIA   -    MD0080PA00X+106299Y+125098X0160Y    R270 S0      
317GND              VIA   -    MD0080PA00X+107421Y+124350X0160Y         S0      
317GND              VIA   -    MD0080PA00X+107421Y+123976X0160Y         S0      
317GND              VIA   -    MD0080PA00X+107795Y+123976X0160Y         S0      
317GND              VIA   -    MD0080PA00X+107047Y+123976X0160Y    R270 S0      
317GND              VIA   -    MD0080PA00X+106673Y+124350X0160Y         S0      
317GND              VIA   -    MD0080PA00X+106673Y+123976X0160Y         S0      
317GND              VIA   -    MD0080PA00X+107795Y+125472X0160Y    R270 S0      
317GND              VIA   -    MD0080PA00X+107795Y+125098X0160Y    R270 S0      
317GND              VIA   -    MD0080PA00X+107421Y+124724X0160Y    R270 S0      
317GND              VIA   -    MD0080PA00X+106673Y+124724X0160Y    R270 S0      
317GND              VIA   -    MD0080PA00X+107047Y+125472X0160Y    R270 S0      
317GND              VIA   -    MD0080PA00X+107047Y+125098X0160Y    R270 S0      
317GND              VIA   -    MD0080PA00X+106299Y+122480X0160Y         S0      
317GND              VIA   -    MD0080PA00X+106299Y+123228X0160Y         S0      
317GND              VIA   -    MD0080PA00X+106299Y+123602X0160Y         S0      
317GND              VIA   -    MD0080PA00X+107795Y+123602X0160Y         S0      
317GND              VIA   -    MD0080PA00X+107795Y+123228X0160Y         S0      
317GND              VIA   -    MD0080PA00X+107421Y+122854X0160Y    R090 S0      
317GND              VIA   -    MD0080PA00X+107421Y+122480X0160Y         S0      
317GND              VIA   -    MD0080PA00X+106673Y+122480X0160Y         S0      
317GND              VIA   -    MD0080PA00X+106673Y+122854X0160Y         S0      
317GND              VIA   -    MD0080PA00X+107047Y+123228X0160Y         S0      
317GND              VIA   -    MD0080PA00X+107047Y+123602X0160Y         S0      
317GND              VIA   -    MD0080PA00X+107047Y+122106X0160Y         S0      
317GND              VIA   -    MD0080PA00X+106673Y+122106X0160Y         S0      
317GND              VIA   -    MD0080PA00X+107795Y+122106X0160Y         S0      
317GND              VIA   -    MD0080PA00X+107421Y+122106X0160Y         S0      
317GND              VIA   -    MD0080PA00X+105925Y+125098X0160Y    R270 S0      
317GND              VIA   -    MD0080PA00X+105925Y+124350X0160Y    R270 S0      
317GND              VIA   -    MD0080PA00X+105925Y+122480X0160Y         S0      
317GND              VIA   -    MD0080PA00X+105925Y+123602X0160Y         S0      
317GND              VIA   -    MD0080PA00X+105925Y+123228X0160Y         S0      
317GND              VIA   -    MD0080PA00X+108917Y+120984X0160Y    R270 S0      
317GND              VIA   -    MD0080PA00X+108543Y+120984X0160Y         S0      
317GND              VIA   -    MD0080PA00X+108917Y+120236X0160Y         S0      
317GND              VIA   -    MD0080PA00X+108543Y+120236X0160Y         S0      
317GND              VIA   -    MD0080PA00X+108917Y+119488X0160Y         S0      
317GND              VIA   -    MD0080PA00X+108543Y+119488X0160Y         S0      
317GND              VIA   -    MD0080PA00X+108169Y+121358X0160Y    R090 S0      
317GND              VIA   -    MD0080PA00X+108169Y+119114X0160Y         S0      
317GND              VIA   -    MD0080PA00X+108169Y+120610X0160Y         S0      
317GND              VIA   -    MD0080PA00X+108169Y+119862X0160Y    R090 S0      
317GND              VIA   -    MD0080PA00X+106299Y+121732X0160Y         S0      
317GND              VIA   -    MD0080PA00X+106299Y+120984X0160Y         S0      
317GND              VIA   -    MD0080PA00X+106673Y+121358X0160Y         S0      
317GND              VIA   -    MD0080PA00X+107047Y+121358X0160Y         S0      
317GND              VIA   -    MD0080PA00X+107421Y+121358X0160Y    R180 S0      
317GND              VIA   -    MD0080PA00X+107421Y+120984X0160Y    R270 S0      
317GND              VIA   -    MD0080PA00X+107795Y+121358X0160Y    R180 S0      
317GND              VIA   -    MD0080PA00X+107421Y+121732X0160Y    R270 S0      
317GND              VIA   -    MD0080PA00X+106299Y+120236X0160Y         S0      
317GND              VIA   -    MD0080PA00X+106299Y+119488X0160Y         S0      
317GND              VIA   -    MD0080PA00X+107047Y+120610X0160Y         S0      
317GND              VIA   -    MD0080PA00X+106673Y+120610X0160Y         S0      
317GND              VIA   -    MD0080PA00X+106673Y+119862X0160Y         S0      
317GND              VIA   -    MD0080PA00X+107047Y+119862X0160Y         S0      
317GND              VIA   -    MD0080PA00X+106673Y+119114X0160Y         S0      
317GND              VIA   -    MD0080PA00X+107047Y+119114X0160Y         S0      
317GND              VIA   -    MD0080PA00X+107421Y+120236X0160Y    R270 S0      
317GND              VIA   -    MD0080PA00X+107795Y+120610X0160Y         S0      
317GND              VIA   -    MD0080PA00X+107421Y+120610X0160Y         S0      
317GND              VIA   -    MD0080PA00X+107421Y+119488X0160Y    R270 S0      
317GND              VIA   -    MD0080PA00X+107421Y+119862X0160Y         S0      
317GND              VIA   -    MD0080PA00X+107795Y+119862X0160Y         S0      
317GND              VIA   -    MD0080PA00X+107421Y+119114X0160Y         S0      
317GND              VIA   -    MD0080PA00X+107795Y+119114X0160Y         S0      
317GND              VIA   -    MD0080PA00X+106299Y+118740X0160Y         S0      
317GND              VIA   -    MD0080PA00X+107421Y+118740X0160Y         S0      
317GND              VIA   -    MD0080PA00X+105925Y+121732X0160Y         S0      
317GND              VIA   -    MD0080PA00X+105925Y+120984X0160Y         S0      
317GND              VIA   -    MD0080PA00X+105925Y+120236X0160Y         S0      
317GND              VIA   -    MD0080PA00X+105925Y+119488X0160Y         S0      
317GND              VIA   -    MD0080PA00X+105925Y+118740X0160Y         S0      
317GND              VIA   -    MD0080PA00X+166594Y+113504X0160Y    R090 S0      
317GND              VIA   -    MD0080PA00X+166968Y+113504X0160Y    R270 S0      
317GND              VIA   -    MD0080PA00X+169587Y+113504X0160Y    R180 S0      
317GND              VIA   -    MD0080PA00X+169213Y+113504X0160Y    R180 S0      
317GND              VIA   -    MD0080PA00X+168090Y+113504X0160Y    R090 S0      
317GND              VIA   -    MD0080PA00X+168464Y+113130X0160Y    R090 S0      
317GND              VIA   -    MD0080PA00X+168838Y+113130X0160Y    R270 S0      
317GND              VIA   -    MD0080PA00X+169213Y+112756X0160Y    R180 S0      
317GND              VIA   -    MD0080PA00X+169587Y+112756X0160Y    R180 S0      
317GND              VIA   -    MD0080PA00X+169587Y+112008X0160Y    R180 S0      
317GND              VIA   -    MD0080PA00X+169213Y+112008X0160Y    R180 S0      
317GND              VIA   -    MD0080PA00X+168838Y+112382X0160Y    R090 S0      
317GND              VIA   -    MD0080PA00X+168464Y+112382X0160Y    R090 S0      
317GND              VIA   -    MD0080PA00X+169587Y+111260X0160Y    R180 S0      
317GND              VIA   -    MD0080PA00X+169213Y+111260X0160Y    R180 S0      
317GND              VIA   -    MD0080PA00X+168838Y+111634X0160Y    R090 S0      
317GND              VIA   -    MD0080PA00X+168464Y+111634X0160Y    R090 S0      
317GND              VIA   -    MD0080PA00X+168838Y+110886X0160Y    R180 S0      
317GND              VIA   -    MD0080PA00X+168464Y+110886X0160Y         S0      
317GND              VIA   -    MD0080PA00X+169587Y+110512X0160Y    R180 S0      
317GND              VIA   -    MD0080PA00X+169213Y+110512X0160Y    R180 S0      
317GND              VIA   -    MD0080PA00X+167716Y+113130X0160Y    R090 S0      
317GND              VIA   -    MD0080PA00X+168090Y+113130X0160Y    R270 S0      
317GND              VIA   -    MD0080PA00X+168090Y+112756X0160Y    R090 S0      
317GND              VIA   -    MD0080PA00X+166594Y+112756X0160Y    R090 S0      
317GND              VIA   -    MD0080PA00X+167342Y+113130X0160Y         S0      
317GND              VIA   -    MD0080PA00X+166968Y+112756X0160Y    R270 S0      
317GND              VIA   -    MD0080PA00X+168090Y+112008X0160Y    R090 S0      
317GND              VIA   -    MD0080PA00X+167716Y+112382X0160Y    R090 S0      
317GND              VIA   -    MD0080PA00X+168090Y+112382X0160Y    R270 S0      
317GND              VIA   -    MD0080PA00X+168090Y+111260X0160Y    R090 S0      
317GND              VIA   -    MD0080PA00X+167716Y+111634X0160Y    R090 S0      
317GND              VIA   -    MD0080PA00X+168090Y+111634X0160Y    R270 S0      
317GND              VIA   -    MD0080PA00X+168090Y+110886X0160Y    R270 S0      
317GND              VIA   -    MD0080PA00X+167716Y+110886X0160Y         S0      
317GND              VIA   -    MD0080PA00X+166594Y+112008X0160Y         S0      
317GND              VIA   -    MD0080PA00X+166594Y+111260X0160Y         S0      
317GND              VIA   -    MD0080PA00X+167342Y+112382X0160Y         S0      
317GND              VIA   -    MD0080PA00X+166968Y+112008X0160Y    R090 S0      
317GND              VIA   -    MD0080PA00X+166968Y+111260X0160Y    R090 S0      
317GND              VIA   -    MD0080PA00X+167342Y+111634X0160Y         S0      
317GND              VIA   -    MD0080PA00X+167342Y+110886X0160Y    R090 S0      
317GND              VIA   -    MD0080PA00X+166968Y+110886X0160Y         S0      
317GND              VIA   -    MD0080PA00X+168839Y+110512X0160Y    R270 S0      
317GND              VIA   -    MD0080PA00X+166594Y+110512X0160Y         S0      
317GND              VIA   -    MD0080PA00X+168090Y+110512X0160Y         S0      
317GND              VIA   -    MD0080PA00X+167342Y+110512X0160Y         S0      
317GND              VIA   -    MD0080PA00X+165098Y+110512X0160Y         S0      
317GND              VIA   -    MD0080PA00X+165846Y+110512X0160Y         S0      
317GND              VIA   -    MD0080PA00X+164350Y+110512X0160Y         S0      
317GND              VIA   -    MD0080PA00X+163602Y+110512X0160Y         S0      
317GND              VIA   -    MD0080PA00X+069193Y+122106X0160Y         S0      
317GND              VIA   -    MD0080PA00X+077047Y+111634X0160Y    R090 S0      
317GND              VIA   -    MD0080PA00X+077421Y+110886X0160Y    R180 S0      
317GND              VIA   -    MD0080PA00X+077047Y+110886X0160Y         S0      
317GND              VIA   -    MD0080PA00X+078169Y+113504X0160Y    R180 S0      
317GND              VIA   -    MD0080PA00X+077795Y+113504X0160Y    R180 S0      
317GND              VIA   -    MD0080PA00X+077047Y+113130X0160Y    R090 S0      
317GND              VIA   -    MD0080PA00X+077421Y+113130X0160Y    R270 S0      
317GND              VIA   -    MD0080PA00X+077795Y+112756X0160Y    R180 S0      
317GND              VIA   -    MD0080PA00X+078169Y+112756X0160Y    R180 S0      
317GND              VIA   -    MD0080PA00X+075177Y+112008X0160Y         S0      
317GND              VIA   -    MD0080PA00X+075177Y+111260X0160Y         S0      
317GND              VIA   -    MD0080PA00X+075177Y+113504X0160Y    R090 S0      
317GND              VIA   -    MD0080PA00X+075177Y+112756X0160Y    R090 S0      
317GND              VIA   -    MD0080PA00X+075925Y+112382X0160Y         S0      
317GND              VIA   -    MD0080PA00X+075551Y+112008X0160Y    R090 S0      
317GND              VIA   -    MD0080PA00X+075925Y+111634X0160Y         S0      
317GND              VIA   -    MD0080PA00X+062087Y+118366X0160Y         S0      
317GND              VIA   -    MD0080PA00X+061339Y+117992X0160Y         S0      
317GND              VIA   -    MD0080PA00X+061713Y+118366X0160Y         S0      
317GND              VIA   -    MD0080PA00X+075177Y+110886X0160Y         S0      
317GND              VIA   -    MD0080PA00X+074803Y+119862X0160Y         S0      
317GND              VIA   -    MD0080PA00X+074803Y+120236X0160Y         S0      
317GND              VIA   -    MD0080PA00X+074803Y+120610X0160Y         S0      
317GND              VIA   -    MD0080PA00X+074803Y+120984X0160Y         S0      
317GND              VIA   -    MD0080PA00X+074803Y+121358X0160Y         S0      
327GND              PEX1  -M40        A01X+074803Y+121358X0180Y         S1      
317GND              VIA   -    MD0080PA00X+074803Y+121732X0160Y         S0      
317GND              VIA   -    MD0080PA00X+074429Y+122106X0160Y         S0      
317GND              VIA   -    MD0080PA00X+074803Y+122106X0160Y         S0      
317GND              VIA   -    MD0080PA00X+074055Y+122106X0160Y         S0      
317GND              VIA   -    MD0080PA00X+072933Y+122106X0160Y         S0      
317GND              VIA   -    MD0080PA00X+072559Y+122106X0160Y         S0      
317GND              VIA   -    MD0080PA00X+072185Y+122106X0160Y         S0      
317GND              VIA   -    MD0080PA00X+071811Y+122106X0160Y         S0      
317GND              VIA   -    MD0080PA00X+071437Y+122106X0160Y         S0      
317GND              VIA   -    MD0080PA00X+071063Y+122106X0160Y         S0      
317GND              VIA   -    MD0080PA00X+070689Y+122106X0160Y         S0      
317GND              VIA   -    MD0080PA00X+070315Y+122106X0160Y         S0      
317GND              VIA   -    MD0080PA00X+073681Y+122106X0160Y         S0      
317GND              VIA   -    MD0080PA00X+073307Y+122106X0160Y         S0      
317GND              VIA   -    MD0080PA00X+069941Y+122106X0160Y         S0      
317GND              VIA   -    MD0080PA00X+069567Y+122106X0160Y         S0      
317GND              VIA   -    MD0080PA00X+015069Y+117431X0160Y         S0      
317GND              VIA   -    MD0080PA00X+075551Y+113504X0160Y    R270 S0      
317GND              VIA   -    MD0080PA00X+075925Y+113130X0160Y         S0      
317GND              VIA   -    MD0080PA00X+075551Y+112756X0160Y    R270 S0      
317GND              VIA   -    MD0080PA00X+075925Y+110886X0160Y    R090 S0      
317GND              VIA   -    MD0080PA00X+075551Y+110886X0160Y         S0      
317GND              VIA   -    MD0080PA00X+075177Y+120236X0160Y    R090 S0      
317GND              VIA   -    MD0080PA00X+075177Y+120984X0160Y    R090 S0      
317GND              VIA   -    MD0080PA00X+075177Y+121732X0160Y         S0      
317GND              VIA   -    MD0080PA00X+075177Y+122106X0160Y         S0      
317GND              VIA   -    MD0080PA00X+075177Y+122854X0160Y         S0      
317GND              VIA   -    MD0080PA00X+075177Y+122480X0160Y         S0      
317GND              VIA   -    MD0080PA00X+075177Y+123976X0160Y    R270 S0      
317GND              VIA   -    MD0080PA00X+075177Y+124350X0160Y    R180 S0      
317GND              VIA   -    MD0080PA00X+075177Y+124724X0160Y    R180 S0      
317GND              VIA   -    MD0080PA00X+075925Y+119862X0160Y    R090 S0      
317GND              VIA   -    MD0080PA00X+076299Y+119862X0160Y         S0      
317GND              VIA   -    MD0080PA00X+076673Y+119862X0160Y         S0      
317GND              VIA   -    MD0080PA00X+076673Y+120236X0160Y         S0      
317GND              VIA   -    MD0080PA00X+032461Y+107894X0160Y         S0      
317GND              VIA   -    MD0080PA00X+075551Y+120236X0160Y         S0      
317GND              VIA   -    MD0080PA00X+015069Y+117805X0160Y         S0      
317GND              VIA   -    MD0080PA00X+015443Y+117431X0160Y         S0      
317GND              VIA   -    MD0080PA00X+075925Y+120610X0160Y    R090 S0      
317GND              VIA   -    MD0080PA00X+076299Y+120610X0160Y    R090 S0      
317GND              VIA   -    MD0080PA00X+076673Y+120610X0160Y         S0      
317GND              VIA   -    MD0080PA00X+075551Y+120984X0160Y         S0      
317GND              VIA   -    MD0080PA00X+076673Y+120984X0160Y         S0      
317GND              VIA   -    MD0080PA00X+076673Y+121358X0160Y         S0      
317GND              VIA   -    MD0080PA00X+076299Y+121358X0160Y         S0      
317GND              VIA   -    MD0080PA00X+075925Y+121358X0160Y    R090 S0      
317GND              VIA   -    MD0080PA00X+075551Y+121732X0160Y    R090 S0      
317GND              VIA   -    MD0080PA00X+075551Y+122106X0160Y    R090 S0      
317GND              VIA   -    MD0080PA00X+075925Y+122106X0160Y         S0      
317GND              VIA   -    MD0080PA00X+076299Y+122106X0160Y         S0      
317GND              VIA   -    MD0080PA00X+076673Y+121732X0160Y         S0      
317GND              VIA   -    MD0080PA00X+076673Y+122106X0160Y         S0      
317GND              VIA   -    MD0080PA00X+076299Y+123602X0160Y         S0      
317GND              VIA   -    MD0080PA00X+076299Y+123228X0160Y         S0      
317GND              VIA   -    MD0080PA00X+076673Y+122854X0160Y         S0      
317GND              VIA   -    MD0080PA00X+076673Y+122480X0160Y         S0      
317GND              VIA   -    MD0080PA00X+075551Y+123602X0160Y         S0      
317GND              VIA   -    MD0080PA00X+075551Y+123228X0160Y         S0      
317GND              VIA   -    MD0080PA00X+075925Y+122854X0160Y         S0      
317GND              VIA   -    MD0080PA00X+075925Y+122480X0160Y         S0      
317GND              VIA   -    MD0080PA00X+076673Y+123976X0160Y         S0      
317GND              VIA   -    MD0080PA00X+076299Y+123976X0160Y    R270 S0      
317GND              VIA   -    MD0080PA00X+075925Y+123976X0160Y    R180 S0      
317GND              VIA   -    MD0080PA00X+075551Y+123976X0160Y         S0      
317GND              VIA   -    MD0080PA00X+076673Y+124350X0160Y    R180 S0      
317GND              VIA   -    MD0080PA00X+076673Y+124724X0160Y    R180 S0      
317GND              VIA   -    MD0080PA00X+076299Y+125472X0160Y    R180 S0      
317GND              VIA   -    MD0080PA00X+076299Y+125098X0160Y    R180 S0      
317GND              VIA   -    MD0080PA00X+075925Y+124350X0160Y    R180 S0      
317GND              VIA   -    MD0080PA00X+075925Y+124724X0160Y    R180 S0      
317GND              VIA   -    MD0080PA00X+075551Y+125472X0160Y    R180 S0      
317GND              VIA   -    MD0080PA00X+075551Y+125098X0160Y    R180 S0      
317GND              VIA   -    MD0080PA00X+077047Y+119862X0160Y    R090 S0      
317GND              VIA   -    MD0080PA00X+077421Y+119862X0160Y    R270 S0      
317GND              VIA   -    MD0080PA00X+077047Y+120610X0160Y    R090 S0      
317GND              VIA   -    MD0080PA00X+077421Y+120610X0160Y    R270 S0      
317GND              VIA   -    MD0080PA00X+077795Y+120236X0160Y         S0      
317GND              VIA   -    MD0080PA00X+078169Y+120236X0160Y         S0      
317GND              VIA   -    MD0080PA00X+077047Y+121358X0160Y    R090 S0      
317GND              VIA   -    MD0080PA00X+077421Y+121358X0160Y    R270 S0      
317GND              VIA   -    MD0080PA00X+077795Y+120984X0160Y         S0      
317GND              VIA   -    MD0080PA00X+078169Y+120984X0160Y    R090 S0      
317GND              VIA   -    MD0080PA00X+077047Y+122106X0160Y         S0      
317GND              VIA   -    MD0080PA00X+077421Y+122106X0160Y    R090 S0      
317GND              VIA   -    MD0080PA00X+077795Y+121732X0160Y    R090 S0      
317GND              VIA   -    MD0080PA00X+078169Y+121732X0160Y    R090 S0      
317GND              VIA   -    MD0080PA00X+078169Y+123602X0160Y    R090 S0      
317GND              VIA   -    MD0080PA00X+077795Y+123602X0160Y    R090 S0      
317GND              VIA   -    MD0080PA00X+077795Y+123228X0160Y         S0      
317GND              VIA   -    MD0080PA00X+078169Y+123228X0160Y    R090 S0      
317GND              VIA   -    MD0080PA00X+077047Y+123228X0160Y         S0      
317GND              VIA   -    MD0080PA00X+077047Y+123602X0160Y         S0      
317GND              VIA   -    MD0080PA00X+077421Y+122854X0160Y         S0      
317GND              VIA   -    MD0080PA00X+077421Y+122480X0160Y         S0      
317GND              VIA   -    MD0080PA00X+077795Y+122480X0160Y    R090 S0      
317GND              VIA   -    MD0080PA00X+078169Y+122480X0160Y    R090 S0      
317GND              VIA   -    MD0080PA00X+077795Y+125472X0160Y    R180 S0      
317GND              VIA   -    MD0080PA00X+077421Y+123976X0160Y    R180 S0      
317GND              VIA   -    MD0080PA00X+077047Y+123976X0160Y    R270 S0      
317GND              VIA   -    MD0080PA00X+078169Y+124350X0160Y    R090 S0      
317GND              VIA   -    MD0080PA00X+077795Y+124350X0160Y    R270 S0      
317GND              VIA   -    MD0080PA00X+077421Y+124350X0160Y    R180 S0      
317GND              VIA   -    MD0080PA00X+077421Y+124724X0160Y    R180 S0      
317GND              VIA   -    MD0080PA00X+077795Y+125098X0160Y    R180 S0      
317GND              VIA   -    MD0080PA00X+078169Y+125098X0160Y         S0      
317GND              VIA   -    MD0080PA00X+077047Y+125472X0160Y    R180 S0      
317GND              VIA   -    MD0080PA00X+077047Y+125098X0160Y    R180 S0      
317GND              VIA   -    MD0080PA00X+015817Y+117431X0160Y         S0      
317GND              VIA   -    MD0080PA00X+014695Y+117431X0160Y         S0      
317GND              VIA   -    MD0080PA00X+032087Y+125472X0160Y    R180 S0      
317GND              VIA   -    MD0080PA00X+066575Y+109764X0160Y         S0      
317GND              VIA   -    MD0080PA00X+074803Y+107520X0160Y         S0      
317GND              VIA   -    MD0080PA00X+066949Y+110512X0160Y         S0      
317GND              VIA   -    MD0080PA00X+066949Y+110138X0160Y         S0      
317GND              VIA   -    MD0080PA00X+065827Y+109764X0160Y         S0      
317GND              VIA   -    MD0080PA00X+162480Y+122106X0160Y         S0      
317GND              VIA   -    MD0080PA00X+067323Y+109390X0160Y         S0      
317GND              VIA   -    MD0080PA00X+067323Y+109764X0160Y         S0      
317GND              VIA   -    MD0080PA00X+152756Y+122106X0160Y         S0      
317GND              VIA   -    MD0080PA00X+072185Y+108642X0160Y         S0      
317GND              VIA   -    MD0080PA00X+072559Y+107894X0160Y         S0      
317GND              VIA   -    MD0080PA00X+163228Y+122106X0160Y         S0      
317GND              VIA   -    MD0080PA00X+072185Y+109016X0160Y         S0      
317GND              VIA   -    MD0080PA00X+072559Y+109016X0160Y         S0      
317GND              VIA   -    MD0080PA00X+072933Y+109016X0160Y         S0      
317GND              VIA   -    MD0080PA00X+073307Y+107894X0160Y    R180 S0      
317GND              VIA   -    MD0080PA00X+073307Y+109016X0160Y         S0      
317GND              VIA   -    MD0080PA00X+073681Y+108268X0160Y    R180 S0      
317GND              VIA   -    MD0080PA00X+073681Y+109016X0160Y         S0      
317GND              VIA   -    MD0080PA00X+073307Y+107520X0160Y         S0      
317GND              VIA   -    MD0080PA00X+160984Y+122106X0160Y         S0      
317GND              VIA   -    MD0080PA00X+071063Y+107520X0160Y         S0      
317GND              VIA   -    MD0080PA00X+071811Y+107520X0160Y         S0      
317GND              VIA   -    MD0080PA00X+069193Y+110512X0160Y         S0      
317GND              VIA   -    MD0080PA00X+069567Y+109764X0160Y    R180 S0      
317GND              VIA   -    MD0080PA00X+070315Y+107520X0160Y         S0      
317GND              VIA   -    MD0080PA00X+067697Y+108642X0160Y    R270 S0      
317GND              VIA   -    MD0080PA00X+069567Y+107520X0160Y         S0      
317GND              VIA   -    MD0080PA00X+070315Y+109016X0160Y         S0      
317GND              VIA   -    MD0080PA00X+069941Y+108268X0160Y    R180 S0      
317GND              VIA   -    MD0080PA00X+070315Y+107894X0160Y         S0      
317GND              VIA   -    MD0080PA00X+069567Y+107894X0160Y    R180 S0      
317GND              VIA   -    MD0080PA00X+069193Y+109016X0160Y         S0      
317GND              VIA   -    MD0080PA00X+069941Y+108642X0160Y         S0      
317GND              VIA   -    MD0080PA00X+069941Y+109016X0160Y         S0      
317GND              VIA   -    MD0080PA00X+069567Y+109016X0160Y         S0      
317GND              VIA   -    MD0080PA00X+069193Y+108642X0160Y         S0      
317GND              VIA   -    MD0080PA00X+069193Y+108268X0160Y         S0      
317GND              VIA   -    MD0080PA00X+070315Y+109764X0160Y         S0      
317GND              VIA   -    MD0080PA00X+070315Y+109390X0160Y         S0      
317GND              VIA   -    MD0080PA00X+067697Y+108268X0160Y    R270 S0      
317GND              VIA   -    MD0080PA00X+069941Y+110138X0160Y         S0      
317GND              VIA   -    MD0080PA00X+068071Y+107894X0160Y    R270 S0      
317GND              VIA   -    MD0080PA00X+067323Y+107894X0160Y    R270 S0      
317GND              VIA   -    MD0080PA00X+067323Y+109016X0160Y         S0      
317GND              VIA   -    MD0080PA00X+071811Y+109016X0160Y         S0      
317GND              VIA   -    MD0080PA00X+071063Y+109016X0160Y         S0      
317GND              VIA   -    MD0080PA00X+071437Y+109016X0160Y         S0      
317GND              VIA   -    MD0080PA00X+071437Y+108642X0160Y         S0      
317GND              VIA   -    MD0080PA00X+071437Y+108268X0160Y    R180 S0      
317GND              VIA   -    MD0080PA00X+071811Y+107894X0160Y         S0      
317GND              VIA   -    MD0080PA00X+070689Y+109016X0160Y         S0      
317GND              VIA   -    MD0080PA00X+070689Y+108642X0160Y         S0      
317GND              VIA   -    MD0080PA00X+070689Y+108268X0160Y    R180 S0      
317GND              VIA   -    MD0080PA00X+071063Y+107894X0160Y         S0      
317GND              VIA   -    MD0080PA00X+071811Y+109390X0160Y         S0      
317GND              VIA   -    MD0080PA00X+071811Y+109764X0160Y         S0      
317GND              VIA   -    MD0080PA00X+071063Y+109390X0160Y         S0      
317GND              VIA   -    MD0080PA00X+071063Y+109764X0160Y         S0      
317GND              VIA   -    MD0080PA00X+071437Y+110138X0160Y    R270 S0      
317GND              VIA   -    MD0080PA00X+071437Y+110512X0160Y         S0      
317GND              VIA   -    MD0080PA00X+070689Y+110512X0160Y         S0      
317GND              VIA   -    MD0080PA00X+070689Y+110138X0160Y    R180 S0      
317GND              VIA   -    MD0080PA00X+060216Y+125098X0160Y    R270 S0      
317GND              VIA   -    MD0080PA00X+159862Y+122106X0160Y         S0      
317GND              VIA   -    MD0080PA00X+162854Y+122106X0160Y         S0      
317GND              VIA   -    MD0080PA00X+072559Y+107520X0160Y         S0      
317GND              VIA   -    MD0080PA00X+073681Y+108642X0160Y    R180 S0      
317GND              VIA   -    MD0080PA00X+072933Y+108268X0160Y         S0      
317GND              VIA   -    MD0080PA00X+072933Y+108642X0160Y         S0      
317GND              VIA   -    MD0080PA00X+072185Y+108268X0160Y    R180 S0      
317GND              VIA   -    MD0080PA00X+161358Y+122106X0160Y         S0      
317GND              VIA   -    MD0080PA00X+073681Y+110138X0160Y    R270 S0      
317GND              VIA   -    MD0080PA00X+073307Y+109764X0160Y    R180 S0      
317GND              VIA   -    MD0080PA00X+073681Y+110512X0160Y         S0      
317GND              VIA   -    MD0080PA00X+066201Y+109016X0160Y         S0      
317GND              VIA   -    MD0080PA00X+066201Y+108642X0160Y    R270 S0      
317GND              VIA   -    MD0080PA00X+066201Y+108268X0160Y    R270 S0      
317GND              VIA   -    MD0080PA00X+065827Y+109016X0160Y         S0      
317GND              VIA   -    MD0080PA00X+073307Y+109390X0160Y         S0      
317GND              VIA   -    MD0080PA00X+162106Y+122106X0160Y         S0      
317GND              VIA   -    MD0080PA00X+072933Y+110512X0160Y         S0      
317GND              VIA   -    MD0080PA00X+066201Y+110512X0160Y         S0      
317GND              VIA   -    MD0080PA00X+074055Y+107520X0160Y         S0      
317GND              VIA   -    MD0080PA00X+027972Y+122854X0160Y         S0      
317GND              VIA   -    MD0080PA00X+077421Y+112382X0160Y    R090 S0      
317GND              VIA   -    MD0080PA00X+076673Y+112756X0160Y    R090 S0      
317GND              VIA   -    MD0080PA00X+078169Y+112008X0160Y    R180 S0      
317GND              VIA   -    MD0080PA00X+066575Y+107520X0160Y    R270 S0      
317GND              VIA   -    MD0080PA00X+077795Y+112008X0160Y    R180 S0      
317GND              VIA   -    MD0080PA00X+065827Y+107520X0160Y    R270 S0      
317GND              VIA   -    MD0080PA00X+068071Y+109764X0160Y         S0      
317GND              VIA   -    MD0080PA00X+067697Y+110138X0160Y         S0      
317GND              VIA   -    MD0080PA00X+077047Y+112382X0160Y    R090 S0      
317GND              VIA   -    MD0080PA00X+078169Y+111260X0160Y    R180 S0      
317GND              VIA   -    MD0080PA00X+152382Y+122106X0160Y         S0      
317GND              VIA   -    MD0080PA00X+153504Y+122106X0160Y         S0      
317GND              VIA   -    MD0080PA00X+153130Y+122106X0160Y         S0      
317GND              VIA   -    MD0080PA00X+151634Y+125098X0160Y    R270 S0      
317GND              VIA   -    MD0080PA00X+151634Y+124350X0160Y    R270 S0      
317GND              VIA   -    MD0080PA00X+151634Y+122480X0160Y         S0      
317GND              VIA   -    MD0080PA00X+151634Y+123602X0160Y         S0      
317GND              VIA   -    MD0080PA00X+151634Y+123228X0160Y         S0      
317GND              VIA   -    MD0080PA00X+075551Y+109390X0160Y         S0      
317GND              VIA   -    MD0080PA00X+077795Y+108642X0160Y    R180 S0      
317GND              VIA   -    MD0080PA00X+078169Y+108642X0160Y    R180 S0      
317GND              VIA   -    MD0080PA00X+077047Y+109016X0160Y         S0      
317GND              VIA   -    MD0080PA00X+075551Y+107894X0160Y         S0      
317GND              VIA   -    MD0080PA00X+076673Y+108268X0160Y    R180 S0      
317GND              VIA   -    MD0080PA00X+076673Y+110138X0160Y    R270 S0      
317GND              VIA   -    MD0080PA00X+075925Y+110138X0160Y    R270 S0      
317GND              VIA   -    MD0080PA00X+067323Y+107520X0160Y    R270 S0      
317GND              VIA   -    MD0080PA00X+068819Y+107520X0160Y    R270 S0      
317GND              VIA   -    MD0080PA00X+068445Y+108642X0160Y    R270 S0      
317GND              VIA   -    MD0080PA00X+077047Y+107520X0160Y         S0      
317GND              VIA   -    MD0080PA00X+075551Y+109764X0160Y    R180 S0      
317GND              VIA   -    MD0080PA00X+063209Y+121732X0160Y         S0      
317GND              VIA   -    MD0080PA00X+063209Y+122106X0160Y         S0      
317GND              VIA   -    MD0080PA00X+062461Y+122106X0160Y    R270 S0      
317GND              VIA   -    MD0080PA00X+062835Y+122106X0160Y         S0      
317GND              VIA   -    MD0080PA00X+062835Y+121732X0160Y         S0      
317GND              VIA   -    MD0080PA00X+061713Y+121732X0160Y    R270 S0      
317GND              VIA   -    MD0080PA00X+061713Y+122106X0160Y         S0      
317GND              VIA   -    MD0080PA00X+062087Y+122106X0160Y         S0      
317GND              VIA   -    MD0080PA00X+062835Y+120984X0160Y         S0      
317GND              VIA   -    MD0080PA00X+063209Y+120984X0160Y    R270 S0      
317GND              VIA   -    MD0080PA00X+062461Y+121358X0160Y    R090 S0      
317GND              VIA   -    MD0080PA00X+062835Y+119488X0160Y         S0      
317GND              VIA   -    MD0080PA00X+063209Y+119488X0160Y         S0      
317GND              VIA   -    MD0080PA00X+062461Y+119862X0160Y    R090 S0      
317GND              VIA   -    MD0080PA00X+062461Y+120610X0160Y         S0      
317GND              VIA   -    MD0080PA00X+062835Y+120236X0160Y         S0      
317GND              VIA   -    MD0080PA00X+063209Y+120236X0160Y         S0      
317GND              VIA   -    MD0080PA00X+062461Y+119114X0160Y         S0      
317GND              VIA   -    MD0080PA00X+062835Y+118740X0160Y         S0      
317GND              VIA   -    MD0080PA00X+063209Y+118740X0160Y         S0      
317GND              VIA   -    MD0080PA00X+062087Y+121358X0160Y    R180 S0      
317GND              VIA   -    MD0080PA00X+061713Y+120984X0160Y    R270 S0      
317GND              VIA   -    MD0080PA00X+061713Y+121358X0160Y    R180 S0      
317GND              VIA   -    MD0080PA00X+062087Y+119114X0160Y         S0      
317GND              VIA   -    MD0080PA00X+061713Y+119114X0160Y         S0      
317GND              VIA   -    MD0080PA00X+062087Y+119862X0160Y         S0      
317GND              VIA   -    MD0080PA00X+061713Y+119862X0160Y         S0      
317GND              VIA   -    MD0080PA00X+061713Y+119488X0160Y    R270 S0      
317GND              VIA   -    MD0080PA00X+061713Y+120610X0160Y         S0      
317GND              VIA   -    MD0080PA00X+062087Y+120610X0160Y         S0      
317GND              VIA   -    MD0080PA00X+061713Y+120236X0160Y    R270 S0      
317GND              VIA   -    MD0080PA00X+061713Y+118740X0160Y         S0      
317GND              VIA   -    MD0080PA00X+061339Y+121358X0160Y         S0      
317GND              VIA   -    MD0080PA00X+060965Y+121358X0160Y         S0      
317GND              VIA   -    MD0080PA00X+060965Y+122106X0160Y         S0      
317GND              VIA   -    MD0080PA00X+061339Y+122106X0160Y         S0      
317GND              VIA   -    MD0080PA00X+061339Y+119114X0160Y         S0      
317GND              VIA   -    MD0080PA00X+060965Y+119114X0160Y         S0      
317GND              VIA   -    MD0080PA00X+061339Y+119862X0160Y         S0      
317GND              VIA   -    MD0080PA00X+062835Y+123602X0160Y         S0      
317GND              VIA   -    MD0080PA00X+062461Y+122854X0160Y    R090 S0      
317GND              VIA   -    MD0080PA00X+062461Y+122480X0160Y         S0      
317GND              VIA   -    MD0080PA00X+063209Y+122480X0160Y         S0      
317GND              VIA   -    MD0080PA00X+063209Y+122854X0160Y    R090 S0      
317GND              VIA   -    MD0080PA00X+061339Y+125098X0160Y    R270 S0      
317GND              VIA   -    MD0080PA00X+061339Y+125472X0160Y    R270 S0      
317GND              VIA   -    MD0080PA00X+060965Y+124724X0160Y    R270 S0      
317GND              VIA   -    MD0080PA00X+061713Y+124724X0160Y    R270 S0      
317GND              VIA   -    MD0080PA00X+062087Y+125098X0160Y    R270 S0      
317GND              VIA   -    MD0080PA00X+062087Y+125472X0160Y    R270 S0      
317GND              VIA   -    MD0080PA00X+060965Y+123976X0160Y         S0      
317GND              VIA   -    MD0080PA00X+060965Y+124350X0160Y         S0      
317GND              VIA   -    MD0080PA00X+061339Y+123976X0160Y    R270 S0      
317GND              VIA   -    MD0080PA00X+062087Y+123976X0160Y         S0      
317GND              VIA   -    MD0080PA00X+061713Y+123976X0160Y         S0      
317GND              VIA   -    MD0080PA00X+061713Y+124350X0160Y         S0      
317GND              VIA   -    MD0080PA00X+061339Y+118366X0160Y         S0      
317GND              VIA   -    MD0080PA00X+068445Y+108268X0160Y    R270 S0      
317GND              VIA   -    MD0080PA00X+072559Y+109390X0160Y         S0      
317GND              VIA   -    MD0080PA00X+154626Y+120984X0160Y    R270 S0      
317GND              VIA   -    MD0080PA00X+154252Y+120984X0160Y         S0      
317GND              VIA   -    MD0080PA00X+154626Y+120236X0160Y         S0      
317GND              VIA   -    MD0080PA00X+154252Y+120236X0160Y         S0      
317GND              VIA   -    MD0080PA00X+154626Y+119488X0160Y         S0      
317GND              VIA   -    MD0080PA00X+154252Y+119488X0160Y         S0      
317GND              VIA   -    MD0080PA00X+153878Y+121358X0160Y    R090 S0      
317GND              VIA   -    MD0080PA00X+153878Y+119114X0160Y         S0      
317GND              VIA   -    MD0080PA00X+153878Y+120610X0160Y         S0      
317GND              VIA   -    MD0080PA00X+153878Y+119862X0160Y    R090 S0      
317GND              VIA   -    MD0080PA00X+152008Y+121732X0160Y         S0      
317GND              VIA   -    MD0080PA00X+152008Y+120984X0160Y         S0      
317GND              VIA   -    MD0080PA00X+152382Y+121358X0160Y         S0      
317GND              VIA   -    MD0080PA00X+152756Y+121358X0160Y         S0      
317GND              VIA   -    MD0080PA00X+153130Y+121358X0160Y    R180 S0      
317GND              VIA   -    MD0080PA00X+153130Y+120984X0160Y    R270 S0      
317GND              VIA   -    MD0080PA00X+153504Y+121358X0160Y    R180 S0      
317GND              VIA   -    MD0080PA00X+153130Y+121732X0160Y    R270 S0      
317GND              VIA   -    MD0080PA00X+152008Y+120236X0160Y         S0      
317GND              VIA   -    MD0080PA00X+152008Y+119488X0160Y         S0      
317GND              VIA   -    MD0080PA00X+152756Y+120610X0160Y         S0      
317GND              VIA   -    MD0080PA00X+152382Y+120610X0160Y         S0      
317GND              VIA   -    MD0080PA00X+152382Y+119862X0160Y         S0      
317GND              VIA   -    MD0080PA00X+152756Y+119862X0160Y         S0      
317GND              VIA   -    MD0080PA00X+152382Y+119114X0160Y         S0      
317GND              VIA   -    MD0080PA00X+152756Y+119114X0160Y         S0      
317GND              VIA   -    MD0080PA00X+153130Y+120236X0160Y    R270 S0      
317GND              VIA   -    MD0080PA00X+153504Y+120610X0160Y         S0      
317GND              VIA   -    MD0080PA00X+153130Y+120610X0160Y         S0      
317GND              VIA   -    MD0080PA00X+153130Y+119488X0160Y    R270 S0      
317GND              VIA   -    MD0080PA00X+153130Y+119862X0160Y         S0      
317GND              VIA   -    MD0080PA00X+153504Y+119862X0160Y         S0      
317GND              VIA   -    MD0080PA00X+153130Y+119114X0160Y         S0      
317GND              VIA   -    MD0080PA00X+153504Y+119114X0160Y         S0      
317GND              VIA   -    MD0080PA00X+152008Y+118740X0160Y         S0      
317GND              VIA   -    MD0080PA00X+153130Y+118740X0160Y         S0      
317GND              VIA   -    MD0080PA00X+151634Y+121732X0160Y         S0      
317GND              VIA   -    MD0080PA00X+151634Y+120984X0160Y         S0      
317GND              VIA   -    MD0080PA00X+151634Y+120236X0160Y         S0      
317GND              VIA   -    MD0080PA00X+151634Y+119488X0160Y         S0      
317GND              VIA   -    MD0080PA00X+151634Y+118740X0160Y         S0      
317GND              VIA   -    MD0080PA00X+156496Y+122106X0160Y         S0      
317GND              VIA   -    MD0080PA00X+156122Y+122106X0160Y         S0      
317GND              VIA   -    MD0080PA00X+155748Y+122106X0160Y         S0      
317GND              VIA   -    MD0080PA00X+155374Y+122106X0160Y         S0      
317GND              VIA   -    MD0080PA00X+155000Y+122106X0160Y         S0      
317GND              VIA   -    MD0080PA00X+158740Y+122106X0160Y         S0      
317GND              VIA   -    MD0080PA00X+159114Y+122106X0160Y         S0      
317GND              VIA   -    MD0080PA00X+161358Y+110512X0160Y         S0      
317GND              VIA   -    MD0080PA00X+160610Y+110512X0160Y         S0      
317GND              VIA   -    MD0080PA00X+159862Y+110512X0160Y         S0      
317GND              VIA   -    MD0080PA00X+159114Y+110512X0160Y         S0      
317GND              VIA   -    MD0080PA00X+156870Y+110512X0160Y         S0      
317GND              VIA   -    MD0080PA00X+158366Y+110512X0160Y         S0      
317GND              VIA   -    MD0080PA00X+157618Y+110512X0160Y         S0      
317GND              VIA   -    MD0080PA00X+155374Y+110512X0160Y         S0      
317GND              VIA   -    MD0080PA00X+156122Y+110512X0160Y         S0      
317GND              VIA   -    MD0080PA00X+169213Y+109764X0160Y    R180 S0      
317GND              VIA   -    MD0080PA00X+169587Y+109764X0160Y    R180 S0      
317GND              VIA   -    MD0080PA00X+169587Y+109390X0160Y    R180 S0      
317GND              VIA   -    MD0080PA00X+169213Y+109390X0160Y    R180 S0      
317GND              VIA   -    MD0080PA00X+168838Y+110138X0160Y    R270 S0      
317GND              VIA   -    MD0080PA00X+168464Y+109764X0160Y    R180 S0      
317GND              VIA   -    MD0080PA00X+168464Y+109390X0160Y         S0      
317GND              VIA   -    MD0080PA00X+169587Y+107894X0160Y         S0      
317GND              VIA   -    MD0080PA00X+168838Y+109016X0160Y    R270 S0      
317GND              VIA   -    MD0080PA00X+168464Y+109016X0160Y         S0      
317GND              VIA   -    MD0080PA00X+168839Y+108642X0160Y    R180 S0      
317GND              VIA   -    MD0080PA00X+169213Y+108642X0160Y    R180 S0      
317GND              VIA   -    MD0080PA00X+169587Y+108642X0160Y    R180 S0      
317GND              VIA   -    MD0080PA00X+168838Y+108268X0160Y    R180 S0      
317GND              VIA   -    MD0080PA00X+168465Y+107894X0160Y         S0      
317GND              VIA   -    MD0080PA00X+169213Y+107894X0160Y         S0      
317GND              VIA   -    MD0080PA00X+169213Y+107520X0160Y         S0      
317GND              VIA   -    MD0080PA00X+168465Y+107520X0160Y         S0      
317GND              VIA   -    MD0080PA00X+166594Y+110138X0160Y    R270 S0      
317GND              VIA   -    MD0080PA00X+167342Y+110138X0160Y    R270 S0      
317GND              VIA   -    MD0080PA00X+168090Y+110138X0160Y    R270 S0      
317GND              VIA   -    MD0080PA00X+167716Y+109764X0160Y    R180 S0      
317GND              VIA   -    MD0080PA00X+166968Y+109764X0160Y    R180 S0      
317GND              VIA   -    MD0080PA00X+167716Y+109390X0160Y         S0      
317GND              VIA   -    MD0080PA00X+166968Y+109390X0160Y         S0      
317GND              VIA   -    MD0080PA00X+166594Y+109016X0160Y    R180 S0      
317GND              VIA   -    MD0080PA00X+166594Y+108642X0160Y    R180 S0      
317GND              VIA   -    MD0080PA00X+166594Y+108268X0160Y    R180 S0      
317GND              VIA   -    MD0080PA00X+168090Y+109016X0160Y    R270 S0      
317GND              VIA   -    MD0080PA00X+167716Y+109016X0160Y    R270 S0      
317GND              VIA   -    MD0080PA00X+167342Y+109016X0160Y    R270 S0      
317GND              VIA   -    MD0080PA00X+166968Y+109016X0160Y         S0      
317GND              VIA   -    MD0080PA00X+168090Y+108642X0160Y    R180 S0      
317GND              VIA   -    MD0080PA00X+167342Y+108642X0160Y    R180 S0      
317GND              VIA   -    MD0080PA00X+167342Y+108268X0160Y    R180 S0      
317GND              VIA   -    MD0080PA00X+168090Y+108268X0160Y    R180 S0      
317GND              VIA   -    MD0080PA00X+166969Y+107894X0160Y         S0      
317GND              VIA   -    MD0080PA00X+167717Y+107894X0160Y         S0      
317GND              VIA   -    MD0080PA00X+167717Y+107520X0160Y         S0      
317GND              VIA   -    MD0080PA00X+166968Y+107520X0160Y         S0      
317GND              VIA   -    MD0080PA00X+165098Y+110138X0160Y    R270 S0      
317GND              VIA   -    MD0080PA00X+166220Y+109764X0160Y    R180 S0      
317GND              VIA   -    MD0080PA00X+166220Y+109390X0160Y         S0      
317GND              VIA   -    MD0080PA00X+165472Y+109390X0160Y    R180 S0      
317GND              VIA   -    MD0080PA00X+165846Y+110138X0160Y         S0      
317GND              VIA   -    MD0080PA00X+162854Y+110512X0160Y         S0      
317GND              VIA   -    MD0080PA00X+162106Y+110512X0160Y         S0      
317GND              VIA   -    MD0080PA00X+063209Y+108642X0160Y    R270 S0      
317GND              VIA   -    MD0080PA00X+077421Y+108268X0160Y    R180 S0      
317GND              VIA   -    MD0080PA00X+076673Y+110512X0160Y         S0      
317GND              VIA   -    MD0080PA00X+076299Y+107894X0160Y         S0      
317GND              VIA   -    MD0080PA00X+068819Y+109016X0160Y         S0      
317GND              VIA   -    MD0080PA00X+068445Y+109016X0160Y         S0      
317GND              VIA   -    MD0080PA00X+075925Y+110512X0160Y         S0      
317GND              VIA   -    MD0080PA00X+076299Y+109390X0160Y         S0      
317GND              VIA   -    MD0080PA00X+063209Y+108268X0160Y    R270 S0      
317GND              VIA   -    MD0080PA00X+077421Y+108642X0160Y    R180 S0      
317GND              VIA   -    MD0080PA00X+068819Y+107894X0160Y    R270 S0      
317GND              VIA   -    MD0080PA00X+063583Y+109764X0160Y         S0      
317GND              VIA   -    MD0080PA00X+077047Y+107894X0160Y         S0      
317GND              VIA   -    MD0080PA00X+076299Y+109764X0160Y    R180 S0      
317GND              VIA   -    MD0080PA00X+068071Y+109390X0160Y         S0      
317GND              VIA   -    MD0080PA00X+060216Y+124350X0160Y    R270 S0      
317GND              VIA   -    MD0080PA00X+068071Y+107520X0160Y    R270 S0      
317GND              VIA   -    MD0080PA00X+063957Y+108268X0160Y    R270 S0      
317GND              VIA   -    MD0080PA00X+063957Y+108642X0160Y    R270 S0      
317GND              VIA   -    MD0080PA00X+063209Y+109016X0160Y         S0      
317GND              VIA   -    MD0080PA00X+078169Y+107894X0160Y         S0      
317GND              VIA   -    MD0080PA00X+064705Y+109016X0160Y         S0      
317GND              VIA   -    MD0080PA00X+076673Y+111260X0160Y    R090 S0      
317GND              VIA   -    MD0080PA00X+065079Y+109016X0160Y         S0      
317GND              VIA   -    MD0080PA00X+062835Y+107520X0160Y    R270 S0      
317GND              VIA   -    MD0080PA00X+065079Y+109390X0160Y         S0      
317GND              VIA   -    MD0080PA00X+076673Y+113504X0160Y    R090 S0      
317GND              VIA   -    MD0080PA00X+063583Y+107894X0160Y    R270 S0      
317GND              VIA   -    MD0080PA00X+077795Y+107894X0160Y         S0      
317GND              VIA   -    MD0080PA00X+078169Y+110512X0160Y    R180 S0      
317GND              VIA   -    MD0080PA00X+064331Y+109390X0160Y         S0      
317GND              VIA   -    MD0080PA00X+064331Y+107894X0160Y    R270 S0      
317GND              VIA   -    MD0080PA00X+064705Y+108642X0160Y    R270 S0      
317GND              VIA   -    MD0080PA00X+064705Y+108268X0160Y    R270 S0      
317GND              VIA   -    MD0080PA00X+077421Y+109016X0160Y    R270 S0      
317GND              VIA   -    MD0080PA00X+062835Y+109016X0160Y         S0      
317GND              VIA   -    MD0080PA00X+064331Y+109764X0160Y         S0      
317GND              VIA   -    MD0080PA00X+065079Y+109764X0160Y         S0      
317GND              VIA   -    MD0080PA00X+077795Y+109764X0160Y    R180 S0      
317GND              VIA   -    MD0080PA00X+078169Y+109764X0160Y    R180 S0      
317GND              VIA   -    MD0080PA00X+078169Y+109390X0160Y    R180 S0      
317GND              VIA   -    MD0080PA00X+065453Y+110138X0160Y         S0      
317GND              VIA   -    MD0080PA00X+065453Y+110512X0160Y         S0      
317GND              VIA   -    MD0080PA00X+064705Y+110138X0160Y         S0      
317GND              VIA   -    MD0080PA00X+064705Y+110512X0160Y         S0      
317GND              VIA   -    MD0080PA00X+077047Y+109390X0160Y         S0      
317GND              VIA   -    MD0080PA00X+062835Y+107894X0160Y    R270 S0      
317GND              VIA   -    MD0080PA00X+065079Y+107520X0160Y    R270 S0      
317GND              VIA   -    MD0080PA00X+065453Y+109016X0160Y         S0      
317GND              VIA   -    MD0080PA00X+065453Y+108642X0160Y    R270 S0      
317GND              VIA   -    MD0080PA00X+065453Y+108268X0160Y    R270 S0      
317GND              VIA   -    MD0080PA00X+063957Y+109016X0160Y         S0      
317GND              VIA   -    MD0080PA00X+063583Y+109016X0160Y         S0      
317GND              VIA   -    MD0080PA00X+076299Y+112382X0160Y    R090 S0      
317GND              VIA   -    MD0080PA00X+076673Y+112382X0160Y    R270 S0      
317GND              VIA   -    MD0080PA00X+076673Y+111634X0160Y    R270 S0      
317GND              VIA   -    MD0080PA00X+062835Y+109390X0160Y         S0      
317GND              VIA   -    MD0080PA00X+077795Y+107520X0160Y         S0      
317GND              VIA   -    MD0080PA00X+076673Y+110886X0160Y    R270 S0      
317GND              VIA   -    MD0080PA00X+076299Y+110886X0160Y         S0      
317GND              VIA   -    MD0080PA00X+064331Y+109016X0160Y         S0      
317GND              VIA   -    MD0080PA00X+077421Y+110512X0160Y    R270 S0      
317GND              VIA   -    MD0080PA00X+076673Y+113130X0160Y    R270 S0      
317GND              VIA   -    MD0080PA00X+076299Y+113130X0160Y    R090 S0      
317GND              VIA   -    MD0080PA00X+069193Y+110138X0160Y         S0      
317GND              VIA   -    MD0080PA00X+062835Y+109764X0160Y    R270 S0      
317GND              VIA   -    MD0080PA00X+077795Y+110512X0160Y    R180 S0      
317GND              VIA   -    MD0080PA00X+077421Y+110138X0160Y    R270 S0      
317GND              VIA   -    MD0080PA00X+065079Y+107894X0160Y    R270 S0      
317GND              VIA   -    MD0080PA00X+077795Y+109390X0160Y    R180 S0      
317GND              VIA   -    MD0080PA00X+072185Y+110512X0160Y         S0      
317GND              VIA   -    MD0080PA00X+076673Y+108642X0160Y    R180 S0      
317GND              VIA   -    MD0080PA00X+165472Y+109764X0160Y    R270 S0      
317GND              VIA   -    MD0080PA00X+163976Y+107894X0160Y         S0      
317GND              VIA   -    MD0080PA00X+063957Y+110512X0160Y         S0      
317GND              VIA   -    MD0080PA00X+077047Y+109764X0160Y    R180 S0      
317GND              VIA   -    MD0080PA00X+063583Y+107520X0160Y    R270 S0      
317GND              VIA   -    MD0080PA00X+076673Y+112008X0160Y    R090 S0      
317GND              VIA   -    MD0080PA00X+063209Y+110512X0160Y         S0      
317GND              VIA   -    MD0080PA00X+063209Y+110138X0160Y         S0      
317GND              VIA   -    MD0080PA00X+064331Y+107520X0160Y    R270 S0      
317GND              VIA   -    MD0080PA00X+063583Y+109390X0160Y         S0      
317GND              VIA   -    MD0080PA00X+063957Y+110138X0160Y         S0      
317GND              VIA   -    MD0080PA00X+076299Y+111634X0160Y    R090 S0      
317GND              VIA   -    MD0080PA00X+072185Y+110138X0160Y    R270 S0      
317GND              VIA   -    MD0080PA00X+069941Y+110512X0160Y         S0      
317GND              VIA   -    MD0080PA00X+066575Y+109016X0160Y         S0      
317GND              VIA   -    MD0080PA00X+072559Y+109764X0160Y         S0      
317GND              VIA   -    MD0080PA00X+075551Y+109016X0160Y         S0      
317GND              VIA   -    MD0080PA00X+020866Y+125472X0160Y    R270 S0      
317GND              VIA   -    MD0080PA00X+067697Y+109016X0160Y         S0      
317GND              VIA   -    MD0080PA00X+166220Y+107520X0160Y         S0      
317GND              VIA   -    MD0080PA00X+162106Y+110138X0160Y    R180 S0      
317GND              VIA   -    MD0080PA00X+162480Y+109764X0160Y         S0      
317GND              VIA   -    MD0080PA00X+107608Y+117431X0160Y         S0      
317GND              VIA   -    MD0080PA00X+107608Y+117805X0160Y         S0      
317GND              VIA   -    MD0080PA00X+107608Y+118179X0160Y         S0      
317GND              VIA   -    MD0080PA00X+107608Y+115935X0160Y         S0      
317GND              VIA   -    MD0080PA00X+107608Y+114439X0160Y         S0      
317GND              VIA   -    MD0080PA00X+107608Y+114813X0160Y         S0      
317GND              VIA   -    MD0080PA00X+107608Y+115187X0160Y         S0      
317GND              VIA   -    MD0080PA00X+107608Y+115561X0160Y         S0      
317GND              VIA   -    MD0080PA00X+107608Y+114065X0160Y         S0      
317GND              VIA   -    MD0080PA00X+107608Y+112569X0160Y    R270 S0      
317GND              VIA   -    MD0080PA00X+107608Y+112943X0160Y    R090 S0      
317GND              VIA   -    MD0080PA00X+107608Y+113317X0160Y    R270 S0      
317GND              VIA   -    MD0080PA00X+107608Y+111447X0160Y         S0      
317GND              VIA   -    MD0080PA00X+107608Y+109577X0160Y    R180 S0      
317GND              VIA   -    MD0080PA00X+107608Y+110699X0160Y         S0      
317GND              VIA   -    MD0080PA00X+107608Y+107707X0160Y    R180 S0      
317GND              VIA   -    MD0080PA00X+107608Y+108829X0160Y    R180 S0      
317GND              VIA   -    MD0080PA00X+107608Y+109203X0160Y    R180 S0      
317GND              VIA   -    MD0080PA00X+107608Y+107333X0160Y    R180 S0      
317GND              VIA   -    MD0080PA00X+108356Y+107333X0160Y    R270 S0      
317GND              VIA   -    MD0080PA00X+107982Y+109951X0160Y    R180 S0      
317GND              VIA   -    MD0080PA00X+107982Y+110325X0160Y    R180 S0      
317GND              VIA   -    MD0080PA00X+108356Y+110699X0160Y         S0      
317GND              VIA   -    MD0080PA00X+107982Y+110699X0160Y         S0      
317GND              VIA   -    MD0080PA00X+108730Y+110699X0160Y         S0      
317GND              VIA   -    MD0080PA00X+108356Y+109577X0160Y         S0      
317GND              VIA   -    MD0080PA00X+108356Y+109951X0160Y    R270 S0      
317GND              VIA   -    MD0080PA00X+107982Y+108081X0160Y    R180 S0      
317GND              VIA   -    MD0080PA00X+107982Y+108455X0160Y    R180 S0      
317GND              VIA   -    MD0080PA00X+107982Y+108829X0160Y    R180 S0      
317GND              VIA   -    MD0080PA00X+108356Y+107707X0160Y    R270 S0      
317GND              VIA   -    MD0080PA00X+108356Y+108829X0160Y    R180 S0      
317GND              VIA   -    MD0080PA00X+108356Y+109203X0160Y         S0      
317GND              VIA   -    MD0080PA00X+108730Y+114439X0160Y         S0      
317GND              VIA   -    MD0080PA00X+108356Y+114439X0160Y         S0      
317GND              VIA   -    MD0080PA00X+108730Y+114813X0160Y         S0      
317GND              VIA   -    MD0080PA00X+108730Y+115561X0160Y         S0      
317GND              VIA   -    MD0080PA00X+108730Y+115187X0160Y         S0      
317GND              VIA   -    MD0080PA00X+109104Y+112943X0160Y         S0      
317GND              VIA   -    MD0080PA00X+109104Y+113317X0160Y         S0      
317GND              VIA   -    MD0080PA00X+109104Y+113691X0160Y         S0      
317GND              VIA   -    MD0080PA00X+108730Y+114065X0160Y         S0      
317GND              VIA   -    MD0080PA00X+108356Y+114065X0160Y         S0      
317GND              VIA   -    MD0080PA00X+107982Y+114065X0160Y         S0      
317GND              VIA   -    MD0080PA00X+108730Y+112943X0160Y    R270 S0      
317GND              VIA   -    MD0080PA00X+108356Y+112943X0160Y    R270 S0      
317GND              VIA   -    MD0080PA00X+107982Y+112943X0160Y         S0      
317GND              VIA   -    MD0080PA00X+108730Y+113691X0160Y    R270 S0      
317GND              VIA   -    MD0080PA00X+108356Y+113691X0160Y    R270 S0      
317GND              VIA   -    MD0080PA00X+109104Y+114065X0160Y         S0      
317GND              VIA   -    MD0080PA00X+109104Y+112569X0160Y         S0      
317GND              VIA   -    MD0080PA00X+109104Y+111447X0160Y         S0      
317GND              VIA   -    MD0080PA00X+109104Y+111821X0160Y         S0      
317GND              VIA   -    MD0080PA00X+109104Y+112195X0160Y         S0      
317GND              VIA   -    MD0080PA00X+109104Y+111073X0160Y         S0      
317GND              VIA   -    MD0080PA00X+108730Y+111073X0160Y         S0      
317GND              VIA   -    MD0080PA00X+108356Y+111073X0160Y         S0      
317GND              VIA   -    MD0080PA00X+107982Y+111447X0160Y         S0      
317GND              VIA   -    MD0080PA00X+108730Y+111821X0160Y         S0      
317GND              VIA   -    MD0080PA00X+108356Y+111821X0160Y         S0      
317GND              VIA   -    MD0080PA00X+108356Y+112195X0160Y    R090 S0      
317GND              VIA   -    MD0080PA00X+108730Y+117431X0160Y         S0      
317GND              VIA   -    MD0080PA00X+108730Y+117805X0160Y         S0      
317GND              VIA   -    MD0080PA00X+108730Y+118179X0160Y         S0      
317GND              VIA   -    MD0080PA00X+108356Y+118179X0160Y         S0      
317GND              VIA   -    MD0080PA00X+108169Y+117992X0160Y         S0      
317GND              VIA   -    MD0080PA00X+107982Y+117805X0160Y    R180 S0      
317GND              VIA   -    MD0080PA00X+107982Y+117431X0160Y    R180 S0      
317GND              VIA   -    MD0080PA00X+109104Y+117057X0160Y         S0      
317GND              VIA   -    MD0080PA00X+107982Y+116683X0160Y    R180 S0      
317GND              VIA   -    MD0080PA00X+107982Y+117057X0160Y    R180 S0      
317GND              VIA   -    MD0080PA00X+108730Y+115935X0160Y         S0      
317GND              VIA   -    MD0080PA00X+108730Y+116683X0160Y         S0      
317GND              VIA   -    MD0080PA00X+108730Y+117057X0160Y         S0      
317GND              VIA   -    MD0080PA00X+109478Y+111447X0160Y         S0      
317GND              VIA   -    MD0080PA00X+110600Y+111821X0160Y         S0      
317GND              VIA   -    MD0080PA00X+110226Y+111821X0160Y         S0      
317GND              VIA   -    MD0080PA00X+109852Y+111821X0160Y         S0      
317GND              VIA   -    MD0080PA00X+109478Y+111821X0160Y         S0      
317GND              VIA   -    MD0080PA00X+110600Y+112195X0160Y         S0      
317GND              VIA   -    MD0080PA00X+110226Y+112195X0160Y         S0      
317GND              VIA   -    MD0080PA00X+109852Y+112195X0160Y         S0      
317GND              VIA   -    MD0080PA00X+109478Y+112195X0160Y         S0      
317GND              VIA   -    MD0080PA00X+109478Y+111073X0160Y         S0      
317GND              VIA   -    MD0080PA00X+110600Y+116683X0160Y         S0      
317GND              VIA   -    MD0080PA00X+109478Y+116683X0160Y         S0      
317GND              VIA   -    MD0080PA00X+110226Y+115935X0160Y         S0      
317GND              VIA   -    MD0080PA00X+109478Y+115935X0160Y         S0      
317GND              VIA   -    MD0080PA00X+109478Y+117057X0160Y    R270 S0      
317GND              VIA   -    MD0080PA00X+110226Y+117057X0160Y         S0      
317GND              VIA   -    MD0080PA00X+110600Y+115561X0160Y         S0      
317GND              VIA   -    MD0080PA00X+110600Y+114813X0160Y         S0      
317GND              VIA   -    MD0080PA00X+110226Y+114439X0160Y         S0      
317GND              VIA   -    MD0080PA00X+109478Y+114439X0160Y         S0      
317GND              VIA   -    MD0080PA00X+109478Y+114813X0160Y         S0      
317GND              VIA   -    MD0080PA00X+110226Y+115187X0160Y         S0      
317GND              VIA   -    MD0080PA00X+109478Y+115561X0160Y         S0      
317GND              VIA   -    MD0080PA00X+109478Y+115187X0160Y         S0      
317GND              VIA   -    MD0080PA00X+109478Y+114065X0160Y         S0      
317GND              VIA   -    MD0080PA00X+110600Y+112569X0160Y         S0      
317GND              VIA   -    MD0080PA00X+110226Y+112569X0160Y         S0      
317GND              VIA   -    MD0080PA00X+109852Y+112569X0160Y         S0      
317GND              VIA   -    MD0080PA00X+109478Y+112569X0160Y         S0      
317GND              VIA   -    MD0080PA00X+110226Y+112943X0160Y         S0      
317GND              VIA   -    MD0080PA00X+109852Y+112943X0160Y         S0      
317GND              VIA   -    MD0080PA00X+109478Y+112943X0160Y         S0      
317GND              VIA   -    MD0080PA00X+110226Y+113317X0160Y         S0      
317GND              VIA   -    MD0080PA00X+109852Y+113317X0160Y         S0      
317GND              VIA   -    MD0080PA00X+109478Y+113317X0160Y         S0      
317GND              VIA   -    MD0080PA00X+110226Y+113691X0160Y         S0      
317GND              VIA   -    MD0080PA00X+109478Y+113691X0160Y         S0      
317GND              VIA   -    MD0080PA00X+110226Y+114065X0160Y         S0      
317GND              VIA   -    MD0080PA00X+109852Y+114065X0160Y         S0      
317GND              VIA   -    MD0080PA00X+110226Y+119301X0160Y    R270 S0      
317GND              VIA   -    MD0080PA00X+110226Y+119675X0160Y         S0      
317GND              VIA   -    MD0080PA00X+110226Y+120049X0160Y         S0      
317GND              VIA   -    MD0080PA00X+109852Y+120049X0160Y         S0      
317GND              VIA   -    MD0080PA00X+109852Y+120423X0160Y         S0      
317GND              VIA   -    MD0080PA00X+110226Y+120423X0160Y         S0      
317GND              VIA   -    MD0080PA00X+110600Y+120423X0160Y         S0      
317GND              VIA   -    MD0080PA00X+110600Y+119675X0160Y         S0      
317GND              VIA   -    MD0080PA00X+110600Y+120049X0160Y         S0      
317GND              VIA   -    MD0080PA00X+109852Y+119301X0160Y         S0      
317GND              VIA   -    MD0080PA00X+109852Y+119675X0160Y         S0      
317GND              VIA   -    MD0080PA00X+110600Y+117431X0160Y         S0      
317GND              VIA   -    MD0080PA00X+110600Y+118179X0160Y         S0      
317GND              VIA   -    MD0080PA00X+109478Y+117805X0160Y         S0      
317GND              VIA   -    MD0080PA00X+109478Y+117431X0160Y         S0      
317GND              VIA   -    MD0080PA00X+110226Y+118553X0160Y         S0      
317GND              VIA   -    MD0080PA00X+109478Y+118179X0160Y         S0      
317GND              VIA   -    MD0080PA00X+110226Y+117805X0160Y    R270 S0      
317GND              VIA   -    MD0080PA00X+110600Y+121919X0160Y         S0      
317GND              VIA   -    MD0080PA00X+109852Y+121919X0160Y         S0      
317GND              VIA   -    MD0080PA00X+109852Y+121171X0160Y         S0      
317GND              VIA   -    MD0080PA00X+110226Y+121171X0160Y         S0      
317GND              VIA   -    MD0080PA00X+110600Y+121171X0160Y         S0      
317GND              VIA   -    MD0080PA00X+110600Y+120797X0160Y         S0      
317GND              VIA   -    MD0080PA00X+110226Y+120797X0160Y         S0      
317GND              VIA   -    MD0080PA00X+109852Y+120797X0160Y         S0      
317GND              VIA   -    MD0080PA00X+112470Y+114813X0160Y         S0      
317GND              VIA   -    MD0080PA00X+111722Y+114813X0160Y         S0      
317GND              VIA   -    MD0080PA00X+111348Y+114813X0160Y         S0      
317GND              VIA   -    MD0080PA00X+112096Y+114813X0160Y         S0      
317GND              VIA   -    MD0080PA00X+110974Y+113317X0160Y         S0      
317GND              VIA   -    MD0080PA00X+110974Y+112943X0160Y         S0      
317GND              VIA   -    MD0080PA00X+111348Y+114065X0160Y         S0      
317GND              VIA   -    MD0080PA00X+111722Y+114065X0160Y         S0      
317GND              VIA   -    MD0080PA00X+112096Y+114065X0160Y         S0      
317GND              VIA   -    MD0080PA00X+111348Y+112569X0160Y         S0      
317GND              VIA   -    MD0080PA00X+111722Y+112569X0160Y         S0      
317GND              VIA   -    MD0080PA00X+112096Y+112569X0160Y         S0      
317GND              VIA   -    MD0080PA00X+110974Y+112569X0160Y         S0      
317GND              VIA   -    MD0080PA00X+112096Y+113317X0160Y         S0      
317GND              VIA   -    MD0080PA00X+111722Y+113317X0160Y         S0      
317GND              VIA   -    MD0080PA00X+111348Y+113317X0160Y         S0      
317GND              VIA   -    MD0080PA00X+112470Y+113317X0160Y         S0      
317GND              VIA   -    MD0080PA00X+112470Y+114065X0160Y         S0      
317GND              VIA   -    MD0080PA00X+112470Y+112569X0160Y         S0      
317GND              VIA   -    MD0080PA00X+110974Y+113691X0160Y         S0      
317GND              VIA   -    MD0080PA00X+112096Y+112195X0160Y         S0      
317GND              VIA   -    MD0080PA00X+112470Y+111821X0160Y         S0      
317GND              VIA   -    MD0080PA00X+112470Y+112195X0160Y         S0      
317GND              VIA   -    MD0080PA00X+111348Y+111821X0160Y         S0      
317GND              VIA   -    MD0080PA00X+110974Y+111821X0160Y         S0      
317GND              VIA   -    MD0080PA00X+111348Y+112195X0160Y         S0      
317GND              VIA   -    MD0080PA00X+110974Y+112195X0160Y         S0      
317GND              VIA   -    MD0080PA00X+112096Y+111821X0160Y         S0      
317GND              VIA   -    MD0080PA00X+111722Y+111821X0160Y         S0      
317GND              VIA   -    MD0080PA00X+111722Y+112195X0160Y         S0      
317GND              VIA   -    MD0080PA00X+111348Y+117431X0160Y         S0      
317GND              VIA   -    MD0080PA00X+110974Y+118553X0160Y         S0      
317GND              VIA   -    MD0080PA00X+112096Y+117431X0160Y         S0      
317GND              VIA   -    MD0080PA00X+110974Y+117805X0160Y         S0      
317GND              VIA   -    MD0080PA00X+112470Y+118179X0160Y         S0      
317GND              VIA   -    MD0080PA00X+112470Y+118927X0160Y         S0      
317GND              VIA   -    MD0080PA00X+112096Y+118179X0160Y         S0      
317GND              VIA   -    MD0080PA00X+111722Y+118179X0160Y         S0      
317GND              VIA   -    MD0080PA00X+111348Y+118179X0160Y         S0      
317GND              VIA   -    MD0080PA00X+112096Y+118927X0160Y         S0      
317GND              VIA   -    MD0080PA00X+111722Y+118927X0160Y         S0      
317GND              VIA   -    MD0080PA00X+111348Y+118927X0160Y         S0      
317GND              VIA   -    MD0080PA00X+110974Y+118927X0160Y         S0      
317GND              VIA   -    MD0080PA00X+112470Y+115935X0160Y         S0      
317GND              VIA   -    MD0080PA00X+112470Y+117057X0160Y         S0      
317GND              VIA   -    MD0080PA00X+110974Y+115935X0160Y         S0      
317GND              VIA   -    MD0080PA00X+112096Y+116683X0160Y         S0      
317GND              VIA   -    MD0080PA00X+111722Y+115935X0160Y         S0      
317GND              VIA   -    MD0080PA00X+111348Y+116683X0160Y         S0      
317GND              VIA   -    MD0080PA00X+110974Y+117057X0160Y         S0      
317GND              VIA   -    MD0080PA00X+111722Y+117057X0160Y         S0      
317GND              VIA   -    MD0080PA00X+110974Y+115187X0160Y         S0      
317GND              VIA   -    MD0080PA00X+112096Y+115561X0160Y         S0      
317GND              VIA   -    MD0080PA00X+110974Y+114439X0160Y         S0      
317GND              VIA   -    MD0080PA00X+111348Y+115561X0160Y         S0      
317GND              VIA   -    MD0080PA00X+112470Y+120797X0160Y         S0      
317GND              VIA   -    MD0080PA00X+112470Y+121171X0160Y    R090 S0      
317GND              VIA   -    MD0080PA00X+110974Y+120797X0160Y         S0      
317GND              VIA   -    MD0080PA00X+110974Y+121171X0160Y         S0      
317GND              VIA   -    MD0080PA00X+112096Y+120797X0160Y         S0      
317GND              VIA   -    MD0080PA00X+111722Y+120797X0160Y         S0      
317GND              VIA   -    MD0080PA00X+111348Y+120797X0160Y         S0      
317GND              VIA   -    MD0080PA00X+112096Y+119675X0160Y         S0      
317GND              VIA   -    MD0080PA00X+111722Y+119675X0160Y         S0      
317GND              VIA   -    MD0080PA00X+111348Y+119675X0160Y         S0      
317GND              VIA   -    MD0080PA00X+110974Y+120049X0160Y         S0      
317GND              VIA   -    MD0080PA00X+110974Y+119675X0160Y         S0      
317GND              VIA   -    MD0080PA00X+110974Y+119301X0160Y         S0      
317GND              VIA   -    MD0080PA00X+110974Y+120423X0160Y         S0      
317GND              VIA   -    MD0080PA00X+111348Y+120423X0160Y         S0      
317GND              VIA   -    MD0080PA00X+111722Y+120423X0160Y         S0      
317GND              VIA   -    MD0080PA00X+112096Y+120423X0160Y         S0      
317GND              VIA   -    MD0080PA00X+112470Y+119675X0160Y         S0      
317GND              VIA   -    MD0080PA00X+112470Y+120423X0160Y         S0      
317GND              VIA   -    MD0080PA00X+113966Y+114065X0160Y         S0      
317GND              VIA   -    MD0080PA00X+113966Y+113317X0160Y         S0      
317GND              VIA   -    MD0080PA00X+113966Y+111821X0160Y         S0      
317GND              VIA   -    MD0080PA00X+112844Y+112195X0160Y         S0      
317GND              VIA   -    MD0080PA00X+113592Y+112195X0160Y         S0      
317GND              VIA   -    MD0080PA00X+113218Y+112195X0160Y         S0      
317GND              VIA   -    MD0080PA00X+113592Y+111821X0160Y         S0      
317GND              VIA   -    MD0080PA00X+113218Y+111821X0160Y         S0      
317GND              VIA   -    MD0080PA00X+112844Y+111821X0160Y         S0      
317GND              VIA   -    MD0080PA00X+113031Y+111260X0160Y         S0      
317GND              VIA   -    MD0080PA00X+112844Y+111447X0160Y    R180 S0      
317GND              VIA   -    MD0080PA00X+113966Y+112195X0160Y         S0      
317GND              VIA   -    MD0080PA00X+113966Y+118927X0160Y         S0      
317GND              VIA   -    MD0080PA00X+113966Y+118179X0160Y         S0      
317GND              VIA   -    MD0080PA00X+113218Y+115935X0160Y         S0      
317GND              VIA   -    MD0080PA00X+112844Y+116683X0160Y         S0      
317GND              VIA   -    MD0080PA00X+113592Y+116683X0160Y         S0      
317GND              VIA   -    MD0080PA00X+113218Y+117057X0160Y         S0      
317GND              VIA   -    MD0080PA00X+113966Y+115935X0160Y         S0      
317GND              VIA   -    MD0080PA00X+113966Y+117057X0160Y         S0      
317GND              VIA   -    MD0080PA00X+113592Y+115561X0160Y         S0      
317GND              VIA   -    MD0080PA00X+112844Y+115561X0160Y         S0      
317GND              VIA   -    MD0080PA00X+113966Y+114813X0160Y         S0      
317GND              VIA   -    MD0080PA00X+112844Y+114813X0160Y         S0      
317GND              VIA   -    MD0080PA00X+113218Y+114813X0160Y         S0      
317GND              VIA   -    MD0080PA00X+113592Y+114813X0160Y         S0      
317GND              VIA   -    MD0080PA00X+112844Y+113317X0160Y         S0      
317GND              VIA   -    MD0080PA00X+113218Y+113317X0160Y         S0      
317GND              VIA   -    MD0080PA00X+113592Y+113317X0160Y         S0      
317GND              VIA   -    MD0080PA00X+113592Y+112569X0160Y         S0      
317GND              VIA   -    MD0080PA00X+112844Y+112569X0160Y         S0      
317GND              VIA   -    MD0080PA00X+113218Y+112569X0160Y         S0      
317GND              VIA   -    MD0080PA00X+113592Y+114065X0160Y         S0      
317GND              VIA   -    MD0080PA00X+113218Y+114065X0160Y         S0      
317GND              VIA   -    MD0080PA00X+112844Y+114065X0160Y         S0      
317GND              VIA   -    MD0080PA00X+113966Y+112569X0160Y         S0      
317GND              VIA   -    MD0080PA00X+112844Y+120797X0160Y         S0      
317GND              VIA   -    MD0080PA00X+113218Y+120797X0160Y         S0      
317GND              VIA   -    MD0080PA00X+113592Y+120797X0160Y         S0      
317GND              VIA   -    MD0080PA00X+113405Y+121732X0160Y         S0      
317GND              VIA   -    MD0080PA00X+113218Y+121171X0160Y    R090 S0      
317GND              VIA   -    MD0080PA00X+113966Y+120797X0160Y         S0      
317GND              VIA   -    MD0080PA00X+113218Y+120423X0160Y         S0      
317GND              VIA   -    MD0080PA00X+112844Y+120423X0160Y         S0      
317GND              VIA   -    MD0080PA00X+112844Y+119675X0160Y         S0      
317GND              VIA   -    MD0080PA00X+113218Y+119675X0160Y         S0      
317GND              VIA   -    MD0080PA00X+113592Y+119675X0160Y         S0      
317GND              VIA   -    MD0080PA00X+113592Y+120423X0160Y         S0      
317GND              VIA   -    MD0080PA00X+113966Y+120423X0160Y         S0      
317GND              VIA   -    MD0080PA00X+113966Y+119675X0160Y         S0      
317GND              VIA   -    MD0080PA00X+113592Y+117431X0160Y         S0      
317GND              VIA   -    MD0080PA00X+112844Y+117431X0160Y         S0      
317GND              VIA   -    MD0080PA00X+112844Y+118927X0160Y         S0      
317GND              VIA   -    MD0080PA00X+113218Y+118927X0160Y         S0      
317GND              VIA   -    MD0080PA00X+113592Y+118927X0160Y         S0      
317GND              VIA   -    MD0080PA00X+112844Y+118179X0160Y         S0      
317GND              VIA   -    MD0080PA00X+113218Y+118179X0160Y         S0      
317GND              VIA   -    MD0080PA00X+113592Y+118179X0160Y         S0      
317GND              VIA   -    MD0080PA00X+115088Y+112569X0160Y         S0      
317GND              VIA   -    MD0080PA00X+115462Y+114065X0160Y         S0      
317GND              VIA   -    MD0080PA00X+115088Y+114065X0160Y         S0      
317GND              VIA   -    MD0080PA00X+114340Y+112569X0160Y         S0      
317GND              VIA   -    MD0080PA00X+114340Y+114065X0160Y         S0      
317GND              VIA   -    MD0080PA00X+114350Y+113268X0160Y         S0      
317GND              VIA   -    MD0080PA00X+115462Y+113317X0160Y         S0      
317GND              VIA   -    MD0080PA00X+115088Y+113346X0160Y         S0      
317GND              VIA   -    MD0080PA00X+115462Y+112569X0160Y         S0      
317GND              VIA   -    MD0080PA00X+115462Y+112195X0160Y         S0      
317GND              VIA   -    MD0080PA00X+114340Y+111447X0160Y         S0      
317GND              VIA   -    MD0080PA00X+114340Y+111821X0160Y         S0      
317GND              VIA   -    MD0080PA00X+114340Y+112195X0160Y         S0      
317GND              VIA   -    MD0080PA00X+115088Y+112195X0160Y         S0      
317GND              VIA   -    MD0080PA00X+115462Y+117431X0160Y         S0      
317GND              VIA   -    MD0080PA00X+114340Y+117431X0160Y         S0      
317GND              VIA   -    MD0080PA00X+114340Y+118927X0160Y         S0      
317GND              VIA   -    MD0080PA00X+115462Y+118927X0160Y         S0      
317GND              VIA   -    MD0080PA00X+115088Y+118927X0160Y         S0      
317GND              VIA   -    MD0080PA00X+115088Y+118179X0160Y         S0      
317GND              VIA   -    MD0080PA00X+115462Y+118179X0160Y         S0      
317GND              VIA   -    MD0080PA00X+114340Y+118179X0160Y         S0      
317GND              VIA   -    MD0080PA00X+115088Y+115935X0160Y         S0      
317GND              VIA   -    MD0080PA00X+114340Y+116683X0160Y         S0      
317GND              VIA   -    MD0080PA00X+115088Y+117057X0160Y         S0      
317GND              VIA   -    MD0080PA00X+115462Y+116683X0160Y         S0      
317GND              VIA   -    MD0080PA00X+115462Y+115561X0160Y         S0      
317GND              VIA   -    MD0080PA00X+114340Y+115561X0160Y         S0      
317GND              VIA   -    MD0080PA00X+115462Y+114813X0160Y         S0      
317GND              VIA   -    MD0080PA00X+115088Y+114813X0160Y         S0      
317GND              VIA   -    MD0080PA00X+114340Y+114813X0160Y         S0      
317GND              VIA   -    MD0080PA00X+114340Y+120797X0160Y         S0      
317GND              VIA   -    MD0080PA00X+115462Y+121171X0160Y         S0      
317GND              VIA   -    MD0080PA00X+115462Y+120797X0160Y         S0      
317GND              VIA   -    MD0080PA00X+115088Y+120797X0160Y         S0      
317GND              VIA   -    MD0080PA00X+114340Y+120423X0160Y         S0      
317GND              VIA   -    MD0080PA00X+114340Y+119675X0160Y         S0      
317GND              VIA   -    MD0080PA00X+115462Y+119675X0160Y         S0      
317GND              VIA   -    MD0080PA00X+115088Y+120423X0160Y         S0      
317GND              VIA   -    MD0080PA00X+115462Y+120423X0160Y         S0      
317GND              VIA   -    MD0080PA00X+115088Y+119675X0160Y         S0      
317GND              VIA   -    MD0080PA00X+117333Y+112195X0160Y         S0      
317GND              VIA   -    MD0080PA00X+115836Y+112195X0160Y         S0      
317GND              VIA   -    MD0080PA00X+116211Y+112195X0160Y         S0      
317GND              VIA   -    MD0080PA00X+116585Y+112195X0160Y         S0      
317GND              VIA   -    MD0080PA00X+116959Y+112195X0160Y         S0      
317GND              VIA   -    MD0080PA00X+117333Y+117057X0160Y         S0      
317GND              VIA   -    MD0080PA00X+117333Y+115935X0160Y         S0      
317GND              VIA   -    MD0080PA00X+116585Y+115935X0160Y         S0      
317GND              VIA   -    MD0080PA00X+116211Y+116683X0160Y         S0      
317GND              VIA   -    MD0080PA00X+115836Y+115935X0160Y         S0      
317GND              VIA   -    MD0080PA00X+116959Y+116683X0160Y         S0      
317GND              VIA   -    MD0080PA00X+116585Y+117057X0160Y         S0      
317GND              VIA   -    MD0080PA00X+115836Y+117057X0160Y         S0      
317GND              VIA   -    MD0080PA00X+116959Y+115561X0160Y         S0      
317GND              VIA   -    MD0080PA00X+116211Y+115561X0160Y         S0      
317GND              VIA   -    MD0080PA00X+116959Y+114813X0160Y         S0      
317GND              VIA   -    MD0080PA00X+116585Y+114813X0160Y         S0      
317GND              VIA   -    MD0080PA00X+116211Y+114813X0160Y         S0      
317GND              VIA   -    MD0080PA00X+115836Y+114813X0160Y         S0      
317GND              VIA   -    MD0080PA00X+117333Y+114813X0160Y         S0      
317GND              VIA   -    MD0080PA00X+115836Y+113317X0160Y         S0      
317GND              VIA   -    MD0080PA00X+117333Y+114065X0160Y         S0      
317GND              VIA   -    MD0080PA00X+117333Y+112569X0160Y         S0      
317GND              VIA   -    MD0080PA00X+117333Y+113317X0160Y         S0      
317GND              VIA   -    MD0080PA00X+116959Y+112569X0160Y         S0      
317GND              VIA   -    MD0080PA00X+116585Y+112569X0160Y         S0      
317GND              VIA   -    MD0080PA00X+116211Y+112569X0160Y         S0      
317GND              VIA   -    MD0080PA00X+115836Y+112569X0160Y         S0      
317GND              VIA   -    MD0080PA00X+116959Y+114065X0160Y         S0      
317GND              VIA   -    MD0080PA00X+116585Y+114065X0160Y         S0      
317GND              VIA   -    MD0080PA00X+116211Y+114065X0160Y         S0      
317GND              VIA   -    MD0080PA00X+115836Y+114065X0160Y         S0      
317GND              VIA   -    MD0080PA00X+116959Y+113317X0160Y         S0      
317GND              VIA   -    MD0080PA00X+116585Y+113317X0160Y         S0      
317GND              VIA   -    MD0080PA00X+116211Y+113317X0160Y         S0      
317GND              VIA   -    MD0080PA00X+116959Y+120797X0160Y         S0      
317GND              VIA   -    MD0080PA00X+116959Y+121171X0160Y         S0      
317GND              VIA   -    MD0080PA00X+117333Y+119675X0160Y         S0      
317GND              VIA   -    MD0080PA00X+117333Y+120423X0160Y         S0      
317GND              VIA   -    MD0080PA00X+116959Y+119675X0160Y         S0      
317GND              VIA   -    MD0080PA00X+116585Y+119675X0160Y         S0      
317GND              VIA   -    MD0080PA00X+116211Y+119675X0160Y         S0      
317GND              VIA   -    MD0080PA00X+115836Y+119675X0160Y         S0      
317GND              VIA   -    MD0080PA00X+116585Y+120423X0160Y         S0      
317GND              VIA   -    MD0080PA00X+116959Y+120423X0160Y         S0      
317GND              VIA   -    MD0080PA00X+115836Y+120423X0160Y         S0      
317GND              VIA   -    MD0080PA00X+116211Y+120423X0160Y         S0      
317GND              VIA   -    MD0080PA00X+116211Y+117431X0160Y         S0      
317GND              VIA   -    MD0080PA00X+116959Y+117431X0160Y         S0      
317GND              VIA   -    MD0080PA00X+117333Y+118179X0160Y         S0      
317GND              VIA   -    MD0080PA00X+116959Y+118927X0160Y         S0      
317GND              VIA   -    MD0080PA00X+116585Y+118927X0160Y         S0      
317GND              VIA   -    MD0080PA00X+116211Y+118927X0160Y         S0      
317GND              VIA   -    MD0080PA00X+115836Y+118927X0160Y         S0      
317GND              VIA   -    MD0080PA00X+116959Y+118179X0160Y         S0      
317GND              VIA   -    MD0080PA00X+116585Y+118179X0160Y         S0      
317GND              VIA   -    MD0080PA00X+116211Y+118179X0160Y         S0      
317GND              VIA   -    MD0080PA00X+115836Y+118179X0160Y         S0      
317GND              VIA   -    MD0080PA00X+117333Y+118927X0160Y         S0      
317GND              VIA   -    MD0080PA00X+116585Y+120797X0160Y         S0      
317GND              VIA   -    MD0080PA00X+116211Y+120797X0160Y         S0      
317GND              VIA   -    MD0080PA00X+117333Y+121171X0160Y         S0      
317GND              VIA   -    MD0080PA00X+117333Y+120797X0160Y         S0      
317GND              VIA   -    MD0080PA00X+115836Y+120797X0160Y         S0      
317GND              VIA   -    MD0080PA00X+115836Y+121171X0160Y         S0      
317GND              VIA   -    MD0080PA00X+118455Y+112195X0160Y         S0      
317GND              VIA   -    MD0080PA00X+117707Y+112195X0160Y         S0      
317GND              VIA   -    MD0080PA00X+118081Y+112195X0160Y         S0      
317GND              VIA   -    MD0080PA00X+118455Y+111821X0160Y         S0      
317GND              VIA   -    MD0080PA00X+118829Y+112195X0160Y    R180 S0      
317GND              VIA   -    MD0080PA00X+118829Y+111821X0160Y         S0      
317GND              VIA   -    MD0080PA00X+118829Y+117057X0160Y         S0      
317GND              VIA   -    MD0080PA00X+118829Y+115935X0160Y         S0      
317GND              VIA   -    MD0080PA00X+118829Y+116683X0160Y         S0      
317GND              VIA   -    MD0080PA00X+117707Y+116683X0160Y         S0      
317GND              VIA   -    MD0080PA00X+118455Y+115561X0160Y         S0      
317GND              VIA   -    MD0080PA00X+117707Y+115561X0160Y         S0      
317GND              VIA   -    MD0080PA00X+118455Y+115187X0160Y         S0      
317GND              VIA   -    MD0080PA00X+118455Y+114813X0160Y         S0      
317GND              VIA   -    MD0080PA00X+118455Y+114439X0160Y         S0      
317GND              VIA   -    MD0080PA00X+118081Y+114813X0160Y         S0      
317GND              VIA   -    MD0080PA00X+117707Y+114813X0160Y         S0      
317GND              VIA   -    MD0080PA00X+118829Y+114813X0160Y         S0      
317GND              VIA   -    MD0080PA00X+118829Y+115187X0160Y         S0      
317GND              VIA   -    MD0080PA00X+118829Y+115561X0160Y         S0      
317GND              VIA   -    MD0080PA00X+118455Y+114065X0160Y         S0      
317GND              VIA   -    MD0080PA00X+118081Y+112569X0160Y         S0      
317GND              VIA   -    MD0080PA00X+117707Y+112569X0160Y         S0      
317GND              VIA   -    MD0080PA00X+118455Y+112943X0160Y         S0      
317GND              VIA   -    MD0080PA00X+118455Y+112569X0160Y         S0      
317GND              VIA   -    MD0080PA00X+118081Y+114065X0160Y         S0      
317GND              VIA   -    MD0080PA00X+117707Y+114065X0160Y         S0      
317GND              VIA   -    MD0080PA00X+118455Y+113317X0160Y         S0      
317GND              VIA   -    MD0080PA00X+118081Y+113317X0160Y         S0      
317GND              VIA   -    MD0080PA00X+117707Y+113317X0160Y         S0      
317GND              VIA   -    MD0080PA00X+118455Y+113691X0160Y         S0      
317GND              VIA   -    MD0080PA00X+118829Y+112569X0160Y         S0      
317GND              VIA   -    MD0080PA00X+118455Y+120797X0160Y         S0      
317GND              VIA   -    MD0080PA00X+118081Y+121171X0160Y         S0      
317GND              VIA   -    MD0080PA00X+118081Y+120797X0160Y         S0      
317GND              VIA   -    MD0080PA00X+117707Y+121171X0160Y         S0      
317GND              VIA   -    MD0080PA00X+117707Y+120797X0160Y         S0      
317GND              VIA   -    MD0080PA00X+118455Y+121171X0160Y         S0      
317GND              VIA   -    MD0080PA00X+118829Y+120797X0160Y         S0      
317GND              VIA   -    MD0080PA00X+118457Y+119673X0160Y         S0      
317GND              VIA   -    MD0080PA00X+118829Y+119675X0160Y         S0      
317GND              VIA   -    MD0080PA00X+118829Y+120423X0160Y    R180 S0      
317GND              VIA   -    MD0080PA00X+118455Y+119301X0160Y         S0      
317GND              VIA   -    MD0080PA00X+118081Y+119675X0160Y         S0      
317GND              VIA   -    MD0080PA00X+117707Y+119675X0160Y         S0      
317GND              VIA   -    MD0080PA00X+118455Y+120049X0160Y         S0      
317GND              VIA   -    MD0080PA00X+118081Y+120423X0160Y         S0      
317GND              VIA   -    MD0080PA00X+117707Y+120423X0160Y         S0      
317GND              VIA   -    MD0080PA00X+118455Y+120423X0160Y         S0      
317GND              VIA   -    MD0080PA00X+118455Y+117431X0160Y         S0      
317GND              VIA   -    MD0080PA00X+118455Y+118927X0160Y         S0      
317GND              VIA   -    MD0080PA00X+118081Y+118179X0160Y         S0      
317GND              VIA   -    MD0080PA00X+117707Y+118179X0160Y         S0      
317GND              VIA   -    MD0080PA00X+118455Y+118553X0160Y         S0      
317GND              VIA   -    MD0080PA00X+117707Y+117431X0160Y         S0      
317GND              VIA   -    MD0080PA00X+118455Y+117805X0160Y         S0      
317GND              VIA   -    MD0080PA00X+118081Y+118927X0160Y         S0      
317GND              VIA   -    MD0080PA00X+117707Y+118927X0160Y         S0      
317GND              VIA   -    MD0080PA00X+118829Y+117431X0160Y         S0      
317GND              VIA   -    MD0080PA00X+118829Y+118179X0160Y         S0      
317GND              VIA   -    MD0080PA00X+119203Y+112195X0160Y    R270 S0      
317GND              VIA   -    MD0080PA00X+119203Y+111821X0160Y         S0      
317GND              VIA   -    MD0080PA00X+119577Y+116683X0160Y         S0      
317GND              VIA   -    MD0080PA00X+120325Y+115935X0160Y         S0      
317GND              VIA   -    MD0080PA00X+120325Y+117057X0160Y         S0      
317GND              VIA   -    MD0080PA00X+120325Y+116683X0160Y         S0      
317GND              VIA   -    MD0080PA00X+119577Y+115935X0160Y         S0      
317GND              VIA   -    MD0080PA00X+119577Y+117057X0160Y         S0      
317GND              VIA   -    MD0080PA00X+119203Y+115187X0160Y         S0      
317GND              VIA   -    MD0080PA00X+120325Y+114439X0160Y    R270 S0      
317GND              VIA   -    MD0080PA00X+120325Y+115561X0160Y         S0      
317GND              VIA   -    MD0080PA00X+120325Y+115187X0160Y         S0      
317GND              VIA   -    MD0080PA00X+119951Y+115187X0160Y         S0      
317GND              VIA   -    MD0080PA00X+119577Y+115187X0160Y         S0      
317GND              VIA   -    MD0080PA00X+119203Y+114813X0160Y         S0      
317GND              VIA   -    MD0080PA00X+119577Y+115561X0160Y         S0      
317GND              VIA   -    MD0080PA00X+119203Y+114439X0160Y         S0      
317GND              VIA   -    MD0080PA00X+119577Y+114813X0160Y         S0      
317GND              VIA   -    MD0080PA00X+119203Y+112943X0160Y    R270 S0      
317GND              VIA   -    MD0080PA00X+119203Y+112569X0160Y    R180 S0      
317GND              VIA   -    MD0080PA00X+119577Y+113691X0160Y         S0      
317GND              VIA   -    MD0080PA00X+119203Y+114065X0160Y         S0      
317GND              VIA   -    MD0080PA00X+119203Y+113317X0160Y    R180 S0      
317GND              VIA   -    MD0080PA00X+119577Y+114065X0160Y         S0      
317GND              VIA   -    MD0080PA00X+119203Y+113691X0160Y         S0      
317GND              VIA   -    MD0080PA00X+119203Y+119301X0160Y         S0      
317GND              VIA   -    MD0080PA00X+119577Y+119301X0160Y         S0      
317GND              VIA   -    MD0080PA00X+119577Y+119675X0160Y         S0      
317GND              VIA   -    MD0080PA00X+120325Y+119301X0160Y    R090 S0      
317GND              VIA   -    MD0080PA00X+119951Y+119301X0160Y         S0      
317GND              VIA   -    MD0080PA00X+119577Y+120423X0160Y         S0      
317GND              VIA   -    MD0080PA00X+119577Y+117431X0160Y         S0      
317GND              VIA   -    MD0080PA00X+119577Y+117805X0160Y         S0      
317GND              VIA   -    MD0080PA00X+119951Y+118179X0160Y         S0      
317GND              VIA   -    MD0080PA00X+119577Y+118553X0160Y         S0      
317GND              VIA   -    MD0080PA00X+119203Y+118553X0160Y         S0      
317GND              VIA   -    MD0080PA00X+119577Y+118927X0160Y         S0      
317GND              VIA   -    MD0080PA00X+119203Y+118927X0160Y         S0      
317GND              VIA   -    MD0080PA00X+119203Y+117805X0160Y         S0      
317GND              VIA   -    MD0080PA00X+120325Y+118553X0160Y         S0      
317GND              VIA   -    MD0080PA00X+120325Y+117805X0160Y         S0      
317GND              VIA   -    MD0080PA00X+120325Y+117431X0160Y         S0      
317GND              VIA   -    MD0080PA00X+119951Y+118553X0160Y         S0      
317GND              VIA   -    MD0080PA00X+119203Y+118179X0160Y         S0      
317GND              VIA   -    MD0080PA00X+119203Y+121171X0160Y         S0      
317GND              VIA   -    MD0080PA00X+120699Y+113691X0160Y         S0      
317GND              VIA   -    MD0080PA00X+121447Y+114065X0160Y         S0      
317GND              VIA   -    MD0080PA00X+121821Y+114065X0160Y    R090 S0      
317GND              VIA   -    MD0080PA00X+122195Y+115935X0160Y    R270 S0      
317GND              VIA   -    MD0080PA00X+122195Y+117057X0160Y         S0      
317GND              VIA   -    MD0080PA00X+121447Y+116683X0160Y         S0      
317GND              VIA   -    MD0080PA00X+121447Y+117057X0160Y    R090 S0      
317GND              VIA   -    MD0080PA00X+121821Y+117057X0160Y    R090 S0      
317GND              VIA   -    MD0080PA00X+120699Y+116683X0160Y         S0      
317GND              VIA   -    MD0080PA00X+121073Y+116683X0160Y    R090 S0      
317GND              VIA   -    MD0080PA00X+121447Y+115935X0160Y         S0      
317GND              VIA   -    MD0080PA00X+121073Y+115935X0160Y    R090 S0      
317GND              VIA   -    MD0080PA00X+120699Y+115935X0160Y         S0      
317GND              VIA   -    MD0080PA00X+122195Y+114813X0160Y    R270 S0      
317GND              VIA   -    MD0080PA00X+121073Y+114439X0160Y    R090 S0      
317GND              VIA   -    MD0080PA00X+120699Y+114439X0160Y         S0      
317GND              VIA   -    MD0080PA00X+121447Y+114439X0160Y    R270 S0      
317GND              VIA   -    MD0080PA00X+121447Y+114813X0160Y         S0      
317GND              VIA   -    MD0080PA00X+121447Y+115187X0160Y    R270 S0      
317GND              VIA   -    MD0080PA00X+121447Y+115561X0160Y    R180 S0      
317GND              VIA   -    MD0080PA00X+121821Y+114813X0160Y    R090 S0      
317GND              VIA   -    MD0080PA00X+121821Y+115561X0160Y    R090 S0      
317GND              VIA   -    MD0080PA00X+120699Y+115187X0160Y         S0      
317GND              VIA   -    MD0080PA00X+121073Y+115187X0160Y    R090 S0      
317GND              VIA   -    MD0080PA00X+122195Y+115561X0160Y    R270 S0      
317GND              VIA   -    MD0080PA00X+122195Y+114065X0160Y    R270 S0      
317GND              VIA   -    MD0080PA00X+122195Y+119301X0160Y         S0      
317GND              VIA   -    MD0080PA00X+121447Y+119301X0160Y    R090 S0      
317GND              VIA   -    MD0080PA00X+121821Y+119301X0160Y    R090 S0      
317GND              VIA   -    MD0080PA00X+121260Y+119488X0160Y    R090 S0      
317GND              VIA   -    MD0080PA00X+120886Y+119488X0160Y         S0      
317GND              VIA   -    MD0080PA00X+121073Y+117431X0160Y    R090 S0      
317GND              VIA   -    MD0080PA00X+121447Y+117431X0160Y         S0      
317GND              VIA   -    MD0080PA00X+121447Y+117805X0160Y    R090 S0      
317GND              VIA   -    MD0080PA00X+121447Y+118179X0160Y         S0      
317GND              VIA   -    MD0080PA00X+121447Y+118553X0160Y    R090 S0      
317GND              VIA   -    MD0080PA00X+120699Y+118927X0160Y         S0      
317GND              VIA   -    MD0080PA00X+120699Y+117431X0160Y         S0      
317GND              VIA   -    MD0080PA00X+122195Y+118553X0160Y         S0      
317GND              VIA   -    MD0080PA00X+122195Y+117805X0160Y         S0      
317GND              VIA   -    MD0080PA00X+121447Y+118927X0160Y         S0      
317GND              VIA   -    MD0080PA00X+121821Y+117805X0160Y    R090 S0      
317GND              VIA   -    MD0080PA00X+121821Y+118553X0160Y    R090 S0      
317GND              VIA   -    MD0080PA00X+121073Y+118927X0160Y    R090 S0      
317GND              VIA   -    MD0080PA00X+120699Y+118179X0160Y         S0      
317GND              VIA   -    MD0080PA00X+121073Y+118179X0160Y    R090 S0      
317GND              VIA   -    MD0080PA00X+123317Y+116683X0160Y    R270 S0      
317GND              VIA   -    MD0080PA00X+123317Y+117057X0160Y         S0      
317GND              VIA   -    MD0080PA00X+122943Y+116683X0160Y    R090 S0      
317GND              VIA   -    MD0080PA00X+122569Y+115935X0160Y    R090 S0      
317GND              VIA   -    MD0080PA00X+123317Y+115935X0160Y    R270 S0      
317GND              VIA   -    MD0080PA00X+122943Y+115935X0160Y    R090 S0      
317GND              VIA   -    MD0080PA00X+122569Y+116683X0160Y         S0      
317GND              VIA   -    MD0080PA00X+123691Y+116683X0160Y    R270 S0      
317GND              VIA   -    MD0080PA00X+123691Y+117057X0160Y         S0      
317GND              VIA   -    MD0080PA00X+123317Y+114813X0160Y         S0      
317GND              VIA   -    MD0080PA00X+123317Y+115187X0160Y    R270 S0      
317GND              VIA   -    MD0080PA00X+122943Y+115187X0160Y    R090 S0      
317GND              VIA   -    MD0080PA00X+123317Y+115561X0160Y         S0      
317GND              VIA   -    MD0080PA00X+122943Y+114439X0160Y    R090 S0      
317GND              VIA   -    MD0080PA00X+122569Y+115187X0160Y    R090 S0      
317GND              VIA   -    MD0080PA00X+122569Y+114439X0160Y    R090 S0      
317GND              VIA   -    MD0080PA00X+123317Y+114439X0160Y    R270 S0      
317GND              VIA   -    MD0080PA00X+123691Y+115561X0160Y    R180 S0      
317GND              VIA   -    MD0080PA00X+123691Y+114813X0160Y    R180 S0      
317GND              VIA   -    MD0080PA00X+123317Y+113691X0160Y    R270 S0      
317GND              VIA   -    MD0080PA00X+122943Y+113691X0160Y    R090 S0      
317GND              VIA   -    MD0080PA00X+123317Y+114065X0160Y         S0      
317GND              VIA   -    MD0080PA00X+123691Y+114065X0160Y    R180 S0      
317GND              VIA   -    MD0080PA00X+123691Y+119301X0160Y         S0      
317GND              VIA   -    MD0080PA00X+123317Y+119675X0160Y    R270 S0      
317GND              VIA   -    MD0080PA00X+122943Y+119675X0160Y    R090 S0      
317GND              VIA   -    MD0080PA00X+122382Y+119488X0160Y         S0      
317GND              VIA   -    MD0080PA00X+123317Y+119301X0160Y         S0      
317GND              VIA   -    MD0080PA00X+122569Y+118927X0160Y         S0      
317GND              VIA   -    MD0080PA00X+122569Y+118179X0160Y         S0      
317GND              VIA   -    MD0080PA00X+122569Y+117431X0160Y         S0      
317GND              VIA   -    MD0080PA00X+123317Y+117431X0160Y    R270 S0      
317GND              VIA   -    MD0080PA00X+122943Y+117431X0160Y    R090 S0      
317GND              VIA   -    MD0080PA00X+123317Y+117805X0160Y         S0      
317GND              VIA   -    MD0080PA00X+123317Y+118179X0160Y    R270 S0      
317GND              VIA   -    MD0080PA00X+123317Y+118553X0160Y         S0      
317GND              VIA   -    MD0080PA00X+123317Y+118927X0160Y    R270 S0      
317GND              VIA   -    MD0080PA00X+122943Y+118927X0160Y    R090 S0      
317GND              VIA   -    MD0080PA00X+122943Y+118179X0160Y    R090 S0      
317GND              VIA   -    MD0080PA00X+123691Y+118553X0160Y         S0      
317GND              VIA   -    MD0080PA00X+123691Y+117805X0160Y         S0      
317GND              VIA   -    MD0080PA00X+124065Y+118553X0160Y    R180 S0      
317GND              VIA   -    MD0080PA00X+124065Y+117805X0160Y    R180 S0      
317GND              VIA   -    MD0080PA00X+124065Y+117057X0160Y    R180 S0      
317GND              VIA   -    MD0080PA00X+124065Y+116683X0160Y    R270 S0      
317GND              VIA   -    MD0080PA00X+124065Y+115561X0160Y    R180 S0      
317GND              VIA   -    MD0080PA00X+124065Y+114813X0160Y    R180 S0      
317GND              VIA   -    MD0080PA00X+124065Y+114065X0160Y    R180 S0      
317GND              VIA   -    MD0080PA00X+124315Y+113691X0160Y    R270 S0      
317GND              VIA   -    MD0080PA00X+124059Y+119301X0160Y         S0      
317GND              VIA   -    MD0080PA00X+151447Y+118179X0160Y    R090 S0      
317GND              VIA   -    MD0080PA00X+151447Y+117431X0160Y    R090 S0      
317GND              VIA   -    MD0080PA00X+151197Y+117805X0160Y    R270 S0      
317GND              VIA   -    MD0080PA00X+151447Y+116683X0160Y    R090 S0      
317GND              VIA   -    MD0080PA00X+151447Y+115935X0160Y         S0      
317GND              VIA   -    MD0080PA00X+151197Y+117057X0160Y    R270 S0      
317GND              VIA   -    MD0080PA00X+151447Y+115187X0160Y         S0      
317GND              VIA   -    MD0080PA00X+151447Y+114439X0160Y         S0      
317GND              VIA   -    MD0080PA00X+151447Y+114065X0160Y         S0      
317GND              VIA   -    MD0080PA00X+151447Y+113317X0160Y         S0      
317GND              VIA   -    MD0080PA00X+151447Y+112569X0160Y         S0      
317GND              VIA   -    MD0080PA00X+151447Y+111821X0160Y    R180 S0      
317GND              VIA   -    MD0080PA00X+151447Y+111073X0160Y    R180 S0      
317GND              VIA   -    MD0080PA00X+151447Y+110325X0160Y         S0      
317GND              VIA   -    MD0080PA00X+151447Y+109577X0160Y    R180 S0      
317GND              VIA   -    MD0080PA00X+151447Y+109203X0160Y    R180 S0      
317GND              VIA   -    MD0080PA00X+151447Y+108455X0160Y    R180 S0      
317GND              VIA   -    MD0080PA00X+152943Y+110325X0160Y    R180 S0      
317GND              VIA   -    MD0080PA00X+152195Y+109951X0160Y    R180 S0      
317GND              VIA   -    MD0080PA00X+152943Y+109951X0160Y    R180 S0      
317GND              VIA   -    MD0080PA00X+151821Y+109577X0160Y    R180 S0      
317GND              VIA   -    MD0080PA00X+152569Y+109577X0160Y    R180 S0      
317GND              VIA   -    MD0080PA00X+152195Y+110699X0160Y    R180 S0      
317GND              VIA   -    MD0080PA00X+152569Y+110699X0160Y    R180 S0      
317GND              VIA   -    MD0080PA00X+152943Y+110699X0160Y         S0      
317GND              VIA   -    MD0080PA00X+151821Y+110325X0160Y         S0      
317GND              VIA   -    MD0080PA00X+151821Y+109203X0160Y    R180 S0      
317GND              VIA   -    MD0080PA00X+152569Y+109203X0160Y    R180 S0      
317GND              VIA   -    MD0080PA00X+152195Y+108829X0160Y    R180 S0      
317GND              VIA   -    MD0080PA00X+152569Y+108829X0160Y    R180 S0      
317GND              VIA   -    MD0080PA00X+152943Y+108829X0160Y    R180 S0      
317GND              VIA   -    MD0080PA00X+151821Y+108455X0160Y    R180 S0      
317GND              VIA   -    MD0080PA00X+152195Y+108455X0160Y    R180 S0      
317GND              VIA   -    MD0080PA00X+152943Y+108455X0160Y    R180 S0      
317GND              VIA   -    MD0080PA00X+152195Y+108081X0160Y    R180 S0      
317GND              VIA   -    MD0080PA00X+152943Y+108081X0160Y    R180 S0      
317GND              VIA   -    MD0080PA00X+151821Y+108081X0160Y         S0      
317GND              VIA   -    MD0080PA00X+151821Y+107707X0160Y    R180 S0      
317GND              VIA   -    MD0080PA00X+152569Y+107707X0160Y    R180 S0      
317GND              VIA   -    MD0080PA00X+152195Y+107707X0160Y         S0      
317GND              VIA   -    MD0080PA00X+152569Y+107333X0160Y    R180 S0      
317GND              VIA   -    MD0080PA00X+151821Y+118179X0160Y         S0      
317GND              VIA   -    MD0080PA00X+152382Y+117992X0160Y         S0      
317GND              VIA   -    MD0080PA00X+152756Y+117992X0160Y         S0      
317GND              VIA   -    MD0080PA00X+153130Y+117992X0160Y         S0      
317GND              VIA   -    MD0080PA00X+152943Y+117431X0160Y         S0      
317GND              VIA   -    MD0080PA00X+152569Y+117431X0160Y         S0      
317GND              VIA   -    MD0080PA00X+152195Y+117805X0160Y         S0      
317GND              VIA   -    MD0080PA00X+151821Y+117431X0160Y         S0      
317GND              VIA   -    MD0080PA00X+152195Y+117431X0160Y         S0      
317GND              VIA   -    MD0080PA00X+151821Y+116683X0160Y    R180 S0      
317GND              VIA   -    MD0080PA00X+152195Y+117057X0160Y         S0      
317GND              VIA   -    MD0080PA00X+152569Y+117057X0160Y         S0      
317GND              VIA   -    MD0080PA00X+152195Y+116683X0160Y         S0      
317GND              VIA   -    MD0080PA00X+152569Y+116683X0160Y    R270 S0      
317GND              VIA   -    MD0080PA00X+152943Y+116683X0160Y         S0      
317GND              VIA   -    MD0080PA00X+151821Y+115935X0160Y         S0      
317GND              VIA   -    MD0080PA00X+152195Y+115935X0160Y         S0      
317GND              VIA   -    MD0080PA00X+152195Y+115561X0160Y         S0      
317GND              VIA   -    MD0080PA00X+152569Y+115561X0160Y         S0      
317GND              VIA   -    MD0080PA00X+152943Y+115561X0160Y         S0      
317GND              VIA   -    MD0080PA00X+151821Y+115187X0160Y         S0      
317GND              VIA   -    MD0080PA00X+152195Y+115187X0160Y         S0      
317GND              VIA   -    MD0080PA00X+152195Y+114813X0160Y         S0      
317GND              VIA   -    MD0080PA00X+152569Y+115187X0160Y    R270 S0      
317GND              VIA   -    MD0080PA00X+152943Y+115187X0160Y    R270 S0      
317GND              VIA   -    MD0080PA00X+151821Y+114439X0160Y         S0      
317GND              VIA   -    MD0080PA00X+152195Y+114439X0160Y         S0      
317GND              VIA   -    MD0080PA00X+151821Y+114065X0160Y         S0      
317GND              VIA   -    MD0080PA00X+152195Y+114065X0160Y         S0      
317GND              VIA   -    MD0080PA00X+152569Y+114065X0160Y         S0      
317GND              VIA   -    MD0080PA00X+152943Y+114065X0160Y         S0      
317GND              VIA   -    MD0080PA00X+152195Y+113691X0160Y         S0      
317GND              VIA   -    MD0080PA00X+151821Y+113317X0160Y         S0      
317GND              VIA   -    MD0080PA00X+152195Y+112943X0160Y         S0      
317GND              VIA   -    MD0080PA00X+152569Y+112943X0160Y         S0      
317GND              VIA   -    MD0080PA00X+152943Y+112943X0160Y    R180 S0      
317GND              VIA   -    MD0080PA00X+151821Y+112569X0160Y         S0      
317GND              VIA   -    MD0080PA00X+152943Y+112569X0160Y         S0      
317GND              VIA   -    MD0080PA00X+152195Y+112195X0160Y         S0      
317GND              VIA   -    MD0080PA00X+152569Y+112195X0160Y         S0      
317GND              VIA   -    MD0080PA00X+152943Y+112195X0160Y         S0      
317GND              VIA   -    MD0080PA00X+151821Y+111821X0160Y    R180 S0      
317GND              VIA   -    MD0080PA00X+152943Y+111821X0160Y         S0      
317GND              VIA   -    MD0080PA00X+152195Y+111447X0160Y    R180 S0      
317GND              VIA   -    MD0080PA00X+152569Y+111447X0160Y    R180 S0      
317GND              VIA   -    MD0080PA00X+152943Y+111447X0160Y    R180 S0      
317GND              VIA   -    MD0080PA00X+151821Y+111073X0160Y    R180 S0      
317GND              VIA   -    MD0080PA00X+152943Y+111073X0160Y    R180 S0      
317GND              VIA   -    MD0080PA00X+152195Y+110325X0160Y    R180 S0      
317GND              VIA   -    MD0080PA00X+153317Y+111447X0160Y         S0      
317GND              VIA   -    MD0080PA00X+153691Y+111447X0160Y         S0      
317GND              VIA   -    MD0080PA00X+154065Y+111073X0160Y         S0      
317GND              VIA   -    MD0080PA00X+154439Y+111073X0160Y         S0      
317GND              VIA   -    MD0080PA00X+154065Y+109951X0160Y    R270 S0      
317GND              VIA   -    MD0080PA00X+154065Y+109577X0160Y         S0      
317GND              VIA   -    MD0080PA00X+154439Y+110699X0160Y         S0      
317GND              VIA   -    MD0080PA00X+153317Y+110699X0160Y         S0      
317GND              VIA   -    MD0080PA00X+153691Y+110699X0160Y         S0      
317GND              VIA   -    MD0080PA00X+154065Y+110699X0160Y         S0      
317GND              VIA   -    MD0080PA00X+153691Y+110325X0160Y    R180 S0      
317GND              VIA   -    MD0080PA00X+153691Y+109951X0160Y    R180 S0      
317GND              VIA   -    MD0080PA00X+153317Y+109577X0160Y    R180 S0      
317GND              VIA   -    MD0080PA00X+154439Y+109951X0160Y         S0      
317GND              VIA   -    MD0080PA00X+154065Y+109203X0160Y         S0      
317GND              VIA   -    MD0080PA00X+154065Y+107707X0160Y    R270 S0      
317GND              VIA   -    MD0080PA00X+153317Y+109203X0160Y    R180 S0      
317GND              VIA   -    MD0080PA00X+153317Y+108829X0160Y    R180 S0      
317GND              VIA   -    MD0080PA00X+153691Y+108829X0160Y    R180 S0      
317GND              VIA   -    MD0080PA00X+153691Y+108455X0160Y    R180 S0      
317GND              VIA   -    MD0080PA00X+153691Y+108081X0160Y    R180 S0      
317GND              VIA   -    MD0080PA00X+153317Y+107707X0160Y    R180 S0      
317GND              VIA   -    MD0080PA00X+154065Y+108829X0160Y    R180 S0      
317GND              VIA   -    MD0080PA00X+154065Y+107333X0160Y    R270 S0      
317GND              VIA   -    MD0080PA00X+153317Y+107333X0160Y    R180 S0      
317GND              VIA   -    MD0080PA00X+153504Y+117618X0160Y    R180 S0      
317GND              VIA   -    MD0080PA00X+153878Y+117992X0160Y         S0      
317GND              VIA   -    MD0080PA00X+154065Y+118179X0160Y         S0      
317GND              VIA   -    MD0080PA00X+154439Y+118179X0160Y         S0      
317GND              VIA   -    MD0080PA00X+154439Y+117805X0160Y         S0      
317GND              VIA   -    MD0080PA00X+154439Y+117431X0160Y         S0      
317GND              VIA   -    MD0080PA00X+153317Y+117805X0160Y         S0      
317GND              VIA   -    MD0080PA00X+153317Y+117431X0160Y         S0      
317GND              VIA   -    MD0080PA00X+153691Y+117431X0160Y    R180 S0      
317GND              VIA   -    MD0080PA00X+154439Y+117057X0160Y         S0      
317GND              VIA   -    MD0080PA00X+154439Y+116683X0160Y         S0      
317GND              VIA   -    MD0080PA00X+154439Y+115935X0160Y         S0      
317GND              VIA   -    MD0080PA00X+153691Y+117057X0160Y    R180 S0      
317GND              VIA   -    MD0080PA00X+153691Y+116683X0160Y    R180 S0      
317GND              VIA   -    MD0080PA00X+153317Y+115935X0160Y         S0      
317GND              VIA   -    MD0080PA00X+154439Y+115187X0160Y         S0      
317GND              VIA   -    MD0080PA00X+154439Y+115561X0160Y         S0      
317GND              VIA   -    MD0080PA00X+154439Y+114813X0160Y         S0      
317GND              VIA   -    MD0080PA00X+153317Y+115561X0160Y         S0      
317GND              VIA   -    MD0080PA00X+153317Y+115187X0160Y         S0      
317GND              VIA   -    MD0080PA00X+153317Y+114813X0160Y         S0      
317GND              VIA   -    MD0080PA00X+153317Y+114439X0160Y         S0      
317GND              VIA   -    MD0080PA00X+154065Y+114439X0160Y         S0      
317GND              VIA   -    MD0080PA00X+154439Y+114439X0160Y         S0      
317GND              VIA   -    MD0080PA00X+154065Y+113691X0160Y    R270 S0      
317GND              VIA   -    MD0080PA00X+153317Y+113317X0160Y    R270 S0      
317GND              VIA   -    MD0080PA00X+154439Y+113691X0160Y    R270 S0      
317GND              VIA   -    MD0080PA00X+153317Y+112943X0160Y    R090 S0      
317GND              VIA   -    MD0080PA00X+153691Y+112943X0160Y         S0      
317GND              VIA   -    MD0080PA00X+154065Y+112943X0160Y    R270 S0      
317GND              VIA   -    MD0080PA00X+154439Y+112943X0160Y    R270 S0      
317GND              VIA   -    MD0080PA00X+153317Y+112569X0160Y    R270 S0      
317GND              VIA   -    MD0080PA00X+153317Y+114065X0160Y         S0      
317GND              VIA   -    MD0080PA00X+153691Y+114065X0160Y         S0      
317GND              VIA   -    MD0080PA00X+154065Y+114065X0160Y         S0      
317GND              VIA   -    MD0080PA00X+154439Y+114065X0160Y         S0      
317GND              VIA   -    MD0080PA00X+154065Y+112195X0160Y    R090 S0      
317GND              VIA   -    MD0080PA00X+154065Y+111821X0160Y         S0      
317GND              VIA   -    MD0080PA00X+154439Y+111821X0160Y         S0      
317GND              VIA   -    MD0080PA00X+154813Y+111073X0160Y         S0      
317GND              VIA   -    MD0080PA00X+154813Y+112195X0160Y         S0      
317GND              VIA   -    MD0080PA00X+155187Y+112195X0160Y         S0      
317GND              VIA   -    MD0080PA00X+155561Y+112195X0160Y         S0      
317GND              VIA   -    MD0080PA00X+155935Y+112195X0160Y         S0      
317GND              VIA   -    MD0080PA00X+156309Y+112195X0160Y         S0      
317GND              VIA   -    MD0080PA00X+154813Y+111821X0160Y         S0      
317GND              VIA   -    MD0080PA00X+155187Y+111821X0160Y         S0      
317GND              VIA   -    MD0080PA00X+155561Y+111821X0160Y         S0      
317GND              VIA   -    MD0080PA00X+155935Y+111821X0160Y         S0      
317GND              VIA   -    MD0080PA00X+156309Y+111821X0160Y         S0      
317GND              VIA   -    MD0080PA00X+154813Y+111447X0160Y         S0      
317GND              VIA   -    MD0080PA00X+155187Y+111447X0160Y         S0      
317GND              VIA   -    MD0080PA00X+156309Y+117431X0160Y         S0      
317GND              VIA   -    MD0080PA00X+156309Y+118179X0160Y         S0      
317GND              VIA   -    MD0080PA00X+155187Y+118179X0160Y         S0      
317GND              VIA   -    MD0080PA00X+155935Y+117805X0160Y    R270 S0      
317GND              VIA   -    MD0080PA00X+155187Y+117431X0160Y         S0      
317GND              VIA   -    MD0080PA00X+155187Y+117805X0160Y         S0      
317GND              VIA   -    MD0080PA00X+155187Y+118553X0160Y         S0      
317GND              VIA   -    MD0080PA00X+155935Y+118553X0160Y         S0      
317GND              VIA   -    MD0080PA00X+155187Y+118927X0160Y         S0      
317GND              VIA   -    MD0080PA00X+156309Y+116683X0160Y         S0      
317GND              VIA   -    MD0080PA00X+155187Y+117057X0160Y    R270 S0      
317GND              VIA   -    MD0080PA00X+154813Y+117057X0160Y         S0      
317GND              VIA   -    MD0080PA00X+155187Y+115935X0160Y         S0      
317GND              VIA   -    MD0080PA00X+155935Y+115935X0160Y         S0      
317GND              VIA   -    MD0080PA00X+155187Y+116683X0160Y         S0      
317GND              VIA   -    MD0080PA00X+155935Y+117057X0160Y         S0      
317GND              VIA   -    MD0080PA00X+156309Y+114813X0160Y         S0      
317GND              VIA   -    MD0080PA00X+156309Y+115561X0160Y         S0      
317GND              VIA   -    MD0080PA00X+155935Y+115187X0160Y         S0      
317GND              VIA   -    MD0080PA00X+155187Y+114813X0160Y         S0      
317GND              VIA   -    MD0080PA00X+155187Y+114439X0160Y         S0      
317GND              VIA   -    MD0080PA00X+155935Y+114439X0160Y         S0      
317GND              VIA   -    MD0080PA00X+155187Y+115187X0160Y         S0      
317GND              VIA   -    MD0080PA00X+155187Y+115561X0160Y         S0      
317GND              VIA   -    MD0080PA00X+155187Y+114065X0160Y         S0      
317GND              VIA   -    MD0080PA00X+155561Y+114065X0160Y         S0      
317GND              VIA   -    MD0080PA00X+155935Y+114065X0160Y         S0      
317GND              VIA   -    MD0080PA00X+154813Y+113691X0160Y         S0      
317GND              VIA   -    MD0080PA00X+155187Y+113691X0160Y         S0      
317GND              VIA   -    MD0080PA00X+155935Y+113691X0160Y         S0      
317GND              VIA   -    MD0080PA00X+154813Y+113317X0160Y         S0      
317GND              VIA   -    MD0080PA00X+155187Y+113317X0160Y         S0      
317GND              VIA   -    MD0080PA00X+155561Y+113317X0160Y         S0      
317GND              VIA   -    MD0080PA00X+155935Y+113317X0160Y         S0      
317GND              VIA   -    MD0080PA00X+154813Y+112943X0160Y         S0      
317GND              VIA   -    MD0080PA00X+155187Y+112943X0160Y         S0      
317GND              VIA   -    MD0080PA00X+155561Y+112943X0160Y         S0      
317GND              VIA   -    MD0080PA00X+155935Y+112943X0160Y         S0      
317GND              VIA   -    MD0080PA00X+154813Y+112569X0160Y         S0      
317GND              VIA   -    MD0080PA00X+155187Y+112569X0160Y         S0      
317GND              VIA   -    MD0080PA00X+155561Y+112569X0160Y         S0      
317GND              VIA   -    MD0080PA00X+155935Y+112569X0160Y         S0      
317GND              VIA   -    MD0080PA00X+156309Y+112569X0160Y         S0      
317GND              VIA   -    MD0080PA00X+154813Y+114065X0160Y         S0      
317GND              VIA   -    MD0080PA00X+156309Y+121919X0160Y         S0      
317GND              VIA   -    MD0080PA00X+155561Y+120797X0160Y         S0      
317GND              VIA   -    MD0080PA00X+155935Y+120797X0160Y         S0      
317GND              VIA   -    MD0080PA00X+156309Y+120797X0160Y         S0      
317GND              VIA   -    MD0080PA00X+156309Y+121171X0160Y         S0      
317GND              VIA   -    MD0080PA00X+155935Y+121171X0160Y         S0      
317GND              VIA   -    MD0080PA00X+155561Y+121171X0160Y         S0      
317GND              VIA   -    MD0080PA00X+155561Y+119675X0160Y         S0      
317GND              VIA   -    MD0080PA00X+155561Y+119301X0160Y         S0      
317GND              VIA   -    MD0080PA00X+156309Y+120049X0160Y         S0      
317GND              VIA   -    MD0080PA00X+156309Y+119675X0160Y         S0      
317GND              VIA   -    MD0080PA00X+156309Y+120423X0160Y         S0      
317GND              VIA   -    MD0080PA00X+155935Y+120423X0160Y         S0      
317GND              VIA   -    MD0080PA00X+155561Y+120423X0160Y         S0      
317GND              VIA   -    MD0080PA00X+155561Y+120049X0160Y         S0      
317GND              VIA   -    MD0080PA00X+155935Y+120049X0160Y         S0      
317GND              VIA   -    MD0080PA00X+155935Y+119675X0160Y         S0      
317GND              VIA   -    MD0080PA00X+155935Y+119301X0160Y    R270 S0      
317GND              VIA   -    MD0080PA00X+155187Y+119301X0160Y         S0      
317GND              VIA   -    MD0080PA00X+157057Y+112195X0160Y         S0      
317GND              VIA   -    MD0080PA00X+156683Y+111821X0160Y         S0      
317GND              VIA   -    MD0080PA00X+157057Y+111821X0160Y         S0      
317GND              VIA   -    MD0080PA00X+157057Y+120423X0160Y         S0      
317GND              VIA   -    MD0080PA00X+156683Y+120423X0160Y         S0      
317GND              VIA   -    MD0080PA00X+156683Y+119301X0160Y         S0      
317GND              VIA   -    MD0080PA00X+156683Y+119675X0160Y         S0      
317GND              VIA   -    MD0080PA00X+156683Y+120049X0160Y         S0      
317GND              VIA   -    MD0080PA00X+157057Y+119675X0160Y         S0      
317GND              VIA   -    MD0080PA00X+157431Y+119675X0160Y         S0      
317GND              VIA   -    MD0080PA00X+157805Y+119675X0160Y         S0      
317GND              VIA   -    MD0080PA00X+157805Y+117431X0160Y         S0      
317GND              VIA   -    MD0080PA00X+156683Y+118553X0160Y         S0      
317GND              VIA   -    MD0080PA00X+157057Y+117431X0160Y         S0      
317GND              VIA   -    MD0080PA00X+156683Y+117805X0160Y         S0      
317GND              VIA   -    MD0080PA00X+156683Y+118927X0160Y         S0      
317GND              VIA   -    MD0080PA00X+157057Y+118927X0160Y         S0      
317GND              VIA   -    MD0080PA00X+157431Y+118927X0160Y         S0      
317GND              VIA   -    MD0080PA00X+157805Y+118927X0160Y         S0      
317GND              VIA   -    MD0080PA00X+157057Y+118179X0160Y         S0      
317GND              VIA   -    MD0080PA00X+157431Y+118179X0160Y         S0      
317GND              VIA   -    MD0080PA00X+157805Y+118179X0160Y         S0      
317GND              VIA   -    MD0080PA00X+157431Y+117057X0160Y         S0      
317GND              VIA   -    MD0080PA00X+156683Y+117057X0160Y         S0      
317GND              VIA   -    MD0080PA00X+157057Y+116683X0160Y         S0      
317GND              VIA   -    MD0080PA00X+157431Y+115935X0160Y         S0      
317GND              VIA   -    MD0080PA00X+157805Y+116683X0160Y         S0      
317GND              VIA   -    MD0080PA00X+156683Y+115935X0160Y         S0      
317GND              VIA   -    MD0080PA00X+156683Y+114439X0160Y         S0      
317GND              VIA   -    MD0080PA00X+157805Y+115561X0160Y         S0      
317GND              VIA   -    MD0080PA00X+156683Y+115187X0160Y         S0      
317GND              VIA   -    MD0080PA00X+157057Y+115561X0160Y         S0      
317GND              VIA   -    MD0080PA00X+157805Y+114813X0160Y         S0      
317GND              VIA   -    MD0080PA00X+157057Y+114813X0160Y         S0      
317GND              VIA   -    MD0080PA00X+157431Y+114813X0160Y         S0      
317GND              VIA   -    MD0080PA00X+156683Y+113691X0160Y         S0      
317GND              VIA   -    MD0080PA00X+157057Y+113317X0160Y         S0      
317GND              VIA   -    MD0080PA00X+157431Y+113317X0160Y         S0      
317GND              VIA   -    MD0080PA00X+157805Y+113317X0160Y         S0      
317GND              VIA   -    MD0080PA00X+156683Y+112569X0160Y         S0      
317GND              VIA   -    MD0080PA00X+157805Y+112569X0160Y         S0      
317GND              VIA   -    MD0080PA00X+157431Y+112569X0160Y         S0      
317GND              VIA   -    MD0080PA00X+157057Y+112569X0160Y         S0      
317GND              VIA   -    MD0080PA00X+157805Y+114065X0160Y         S0      
317GND              VIA   -    MD0080PA00X+157431Y+114065X0160Y         S0      
317GND              VIA   -    MD0080PA00X+157057Y+114065X0160Y         S0      
317GND              VIA   -    MD0080PA00X+156683Y+112943X0160Y         S0      
317GND              VIA   -    MD0080PA00X+156683Y+113317X0160Y         S0      
317GND              VIA   -    MD0080PA00X+157805Y+112195X0160Y         S0      
317GND              VIA   -    MD0080PA00X+157431Y+112195X0160Y         S0      
317GND              VIA   -    MD0080PA00X+157431Y+111821X0160Y         S0      
317GND              VIA   -    MD0080PA00X+157805Y+111821X0160Y         S0      
317GND              VIA   -    MD0080PA00X+156683Y+112195X0160Y         S0      
317GND              VIA   -    MD0080PA00X+157057Y+120797X0160Y         S0      
317GND              VIA   -    MD0080PA00X+157431Y+120797X0160Y         S0      
317GND              VIA   -    MD0080PA00X+157805Y+120797X0160Y         S0      
317GND              VIA   -    MD0080PA00X+156683Y+121171X0160Y         S0      
317GND              VIA   -    MD0080PA00X+156683Y+120797X0160Y         S0      
317GND              VIA   -    MD0080PA00X+157805Y+120423X0160Y         S0      
317GND              VIA   -    MD0080PA00X+157431Y+120423X0160Y         S0      
317GND              VIA   -    MD0080PA00X+158553Y+111447X0160Y    R180 S0      
317GND              VIA   -    MD0080PA00X+158179Y+111821X0160Y         S0      
317GND              VIA   -    MD0080PA00X+158179Y+121171X0160Y    R090 S0      
317GND              VIA   -    MD0080PA00X+158179Y+120797X0160Y         S0      
317GND              VIA   -    MD0080PA00X+158927Y+121171X0160Y    R090 S0      
317GND              VIA   -    MD0080PA00X+158927Y+120423X0160Y         S0      
317GND              VIA   -    MD0080PA00X+158553Y+120423X0160Y         S0      
317GND              VIA   -    MD0080PA00X+158179Y+120423X0160Y         S0      
317GND              VIA   -    MD0080PA00X+158179Y+119675X0160Y         S0      
317GND              VIA   -    MD0080PA00X+158553Y+119675X0160Y         S0      
317GND              VIA   -    MD0080PA00X+158927Y+119675X0160Y         S0      
317GND              VIA   -    MD0080PA00X+159301Y+119675X0160Y         S0      
317GND              VIA   -    MD0080PA00X+159301Y+120423X0160Y         S0      
317GND              VIA   -    MD0080PA00X+159301Y+117431X0160Y         S0      
317GND              VIA   -    MD0080PA00X+158553Y+117431X0160Y         S0      
317GND              VIA   -    MD0080PA00X+158179Y+118927X0160Y         S0      
317GND              VIA   -    MD0080PA00X+158553Y+118927X0160Y         S0      
317GND              VIA   -    MD0080PA00X+158927Y+118927X0160Y         S0      
317GND              VIA   -    MD0080PA00X+159301Y+118927X0160Y         S0      
317GND              VIA   -    MD0080PA00X+158179Y+118179X0160Y         S0      
317GND              VIA   -    MD0080PA00X+158553Y+118179X0160Y         S0      
317GND              VIA   -    MD0080PA00X+158927Y+118179X0160Y         S0      
317GND              VIA   -    MD0080PA00X+159301Y+118179X0160Y         S0      
317GND              VIA   -    MD0080PA00X+158179Y+117057X0160Y         S0      
317GND              VIA   -    MD0080PA00X+158927Y+115935X0160Y         S0      
317GND              VIA   -    MD0080PA00X+158179Y+115935X0160Y         S0      
317GND              VIA   -    MD0080PA00X+158553Y+116683X0160Y         S0      
317GND              VIA   -    MD0080PA00X+159301Y+116683X0160Y         S0      
317GND              VIA   -    MD0080PA00X+158927Y+117057X0160Y         S0      
317GND              VIA   -    MD0080PA00X+158553Y+115561X0160Y         S0      
317GND              VIA   -    MD0080PA00X+159301Y+115561X0160Y         S0      
317GND              VIA   -    MD0080PA00X+158179Y+114813X0160Y         S0      
317GND              VIA   -    MD0080PA00X+158553Y+114813X0160Y         S0      
317GND              VIA   -    MD0080PA00X+158927Y+114813X0160Y         S0      
317GND              VIA   -    MD0080PA00X+159301Y+114813X0160Y         S0      
317GND              VIA   -    MD0080PA00X+158553Y+113317X0160Y         S0      
317GND              VIA   -    MD0080PA00X+158927Y+113317X0160Y         S0      
317GND              VIA   -    MD0080PA00X+159301Y+113317X0160Y         S0      
317GND              VIA   -    MD0080PA00X+159301Y+112569X0160Y         S0      
317GND              VIA   -    MD0080PA00X+158179Y+112569X0160Y         S0      
317GND              VIA   -    MD0080PA00X+158553Y+112569X0160Y         S0      
317GND              VIA   -    MD0080PA00X+158927Y+112569X0160Y         S0      
317GND              VIA   -    MD0080PA00X+159301Y+114065X0160Y         S0      
317GND              VIA   -    MD0080PA00X+158927Y+114065X0160Y         S0      
317GND              VIA   -    MD0080PA00X+158553Y+114065X0160Y         S0      
317GND              VIA   -    MD0080PA00X+158179Y+114065X0160Y         S0      
317GND              VIA   -    MD0080PA00X+158179Y+113317X0160Y         S0      
317GND              VIA   -    MD0080PA00X+158553Y+112195X0160Y         S0      
317GND              VIA   -    MD0080PA00X+159301Y+112195X0160Y         S0      
317GND              VIA   -    MD0080PA00X+158927Y+112195X0160Y         S0      
317GND              VIA   -    MD0080PA00X+159301Y+111821X0160Y         S0      
317GND              VIA   -    MD0080PA00X+158927Y+111821X0160Y         S0      
317GND              VIA   -    MD0080PA00X+158553Y+111821X0160Y         S0      
317GND              VIA   -    MD0080PA00X+158179Y+112195X0160Y         S0      
317GND              VIA   -    MD0080PA00X+158553Y+120797X0160Y         S0      
317GND              VIA   -    MD0080PA00X+158927Y+120797X0160Y         S0      
317GND              VIA   -    MD0080PA00X+159301Y+120797X0160Y         S0      
317GND              VIA   -    MD0080PA00X+159114Y+121732X0160Y         S0      
317GND              VIA   -    MD0080PA00X+159301Y+121919X0160Y         S0      
317GND              VIA   -    MD0080PA00X+161171Y+114065X0160Y         S0      
317GND              VIA   -    MD0080PA00X+160797Y+114065X0160Y         S0      
317GND              VIA   -    MD0080PA00X+159675Y+112569X0160Y         S0      
317GND              VIA   -    MD0080PA00X+160049Y+112569X0160Y         S0      
317GND              VIA   -    MD0080PA00X+160049Y+114065X0160Y         S0      
317GND              VIA   -    MD0080PA00X+159675Y+114065X0160Y         S0      
317GND              VIA   -    MD0080PA00X+159675Y+113317X0160Y         S0      
317GND              VIA   -    MD0080PA00X+160059Y+113268X0160Y         S0      
317GND              VIA   -    MD0080PA00X+161171Y+113317X0160Y         S0      
317GND              VIA   -    MD0080PA00X+160797Y+113346X0160Y         S0      
317GND              VIA   -    MD0080PA00X+160049Y+112195X0160Y         S0      
317GND              VIA   -    MD0080PA00X+159675Y+111821X0160Y         S0      
317GND              VIA   -    MD0080PA00X+160797Y+112195X0160Y         S0      
317GND              VIA   -    MD0080PA00X+161171Y+112195X0160Y         S0      
317GND              VIA   -    MD0080PA00X+160049Y+111447X0160Y         S0      
317GND              VIA   -    MD0080PA00X+160049Y+111821X0160Y         S0      
317GND              VIA   -    MD0080PA00X+159675Y+112195X0160Y         S0      
317GND              VIA   -    MD0080PA00X+160049Y+120797X0160Y         S0      
317GND              VIA   -    MD0080PA00X+159675Y+121919X0160Y         S0      
317GND              VIA   -    MD0080PA00X+161171Y+121171X0160Y         S0      
317GND              VIA   -    MD0080PA00X+161171Y+120797X0160Y         S0      
317GND              VIA   -    MD0080PA00X+160797Y+120797X0160Y         S0      
317GND              VIA   -    MD0080PA00X+159675Y+120797X0160Y         S0      
317GND              VIA   -    MD0080PA00X+160049Y+120423X0160Y         S0      
317GND              VIA   -    MD0080PA00X+159675Y+120423X0160Y         S0      
317GND              VIA   -    MD0080PA00X+159675Y+119675X0160Y         S0      
317GND              VIA   -    MD0080PA00X+160049Y+119675X0160Y         S0      
317GND              VIA   -    MD0080PA00X+161171Y+119675X0160Y         S0      
317GND              VIA   -    MD0080PA00X+160797Y+119675X0160Y         S0      
317GND              VIA   -    MD0080PA00X+160797Y+120423X0160Y         S0      
317GND              VIA   -    MD0080PA00X+161171Y+120423X0160Y         S0      
317GND              VIA   -    MD0080PA00X+161171Y+117431X0160Y         S0      
317GND              VIA   -    MD0080PA00X+160049Y+117431X0160Y         S0      
317GND              VIA   -    MD0080PA00X+159675Y+118927X0160Y         S0      
317GND              VIA   -    MD0080PA00X+160049Y+118927X0160Y         S0      
317GND              VIA   -    MD0080PA00X+159675Y+118179X0160Y         S0      
317GND              VIA   -    MD0080PA00X+161171Y+118927X0160Y         S0      
317GND              VIA   -    MD0080PA00X+160797Y+118927X0160Y         S0      
317GND              VIA   -    MD0080PA00X+160797Y+118179X0160Y         S0      
317GND              VIA   -    MD0080PA00X+161171Y+118179X0160Y         S0      
317GND              VIA   -    MD0080PA00X+160049Y+118179X0160Y         S0      
317GND              VIA   -    MD0080PA00X+160797Y+115935X0160Y         S0      
317GND              VIA   -    MD0080PA00X+160049Y+116683X0160Y         S0      
317GND              VIA   -    MD0080PA00X+160797Y+117057X0160Y         S0      
317GND              VIA   -    MD0080PA00X+161171Y+116683X0160Y         S0      
317GND              VIA   -    MD0080PA00X+159675Y+115935X0160Y         S0      
317GND              VIA   -    MD0080PA00X+159675Y+117057X0160Y         S0      
317GND              VIA   -    MD0080PA00X+161171Y+115561X0160Y         S0      
317GND              VIA   -    MD0080PA00X+160049Y+115561X0160Y         S0      
317GND              VIA   -    MD0080PA00X+161171Y+114813X0160Y         S0      
317GND              VIA   -    MD0080PA00X+160797Y+114813X0160Y         S0      
317GND              VIA   -    MD0080PA00X+159675Y+114813X0160Y         S0      
317GND              VIA   -    MD0080PA00X+160049Y+114813X0160Y         S0      
317GND              VIA   -    MD0080PA00X+161171Y+112569X0160Y         S0      
317GND              VIA   -    MD0080PA00X+160797Y+112569X0160Y         S0      
317GND              VIA   -    MD0080PA00X+161919Y+117431X0160Y         S0      
317GND              VIA   -    MD0080PA00X+162667Y+117431X0160Y         S0      
317GND              VIA   -    MD0080PA00X+162667Y+118927X0160Y         S0      
317GND              VIA   -    MD0080PA00X+162293Y+118927X0160Y         S0      
317GND              VIA   -    MD0080PA00X+161919Y+118927X0160Y         S0      
317GND              VIA   -    MD0080PA00X+161545Y+118927X0160Y         S0      
317GND              VIA   -    MD0080PA00X+162667Y+118179X0160Y         S0      
317GND              VIA   -    MD0080PA00X+162293Y+118179X0160Y         S0      
317GND              VIA   -    MD0080PA00X+161919Y+118179X0160Y         S0      
317GND              VIA   -    MD0080PA00X+161545Y+118179X0160Y         S0      
317GND              VIA   -    MD0080PA00X+162293Y+115935X0160Y         S0      
317GND              VIA   -    MD0080PA00X+161919Y+116683X0160Y         S0      
317GND              VIA   -    MD0080PA00X+161545Y+115935X0160Y         S0      
317GND              VIA   -    MD0080PA00X+162667Y+116683X0160Y         S0      
317GND              VIA   -    MD0080PA00X+162293Y+117057X0160Y         S0      
317GND              VIA   -    MD0080PA00X+161545Y+117057X0160Y         S0      
317GND              VIA   -    MD0080PA00X+162667Y+115561X0160Y         S0      
317GND              VIA   -    MD0080PA00X+161919Y+115561X0160Y         S0      
317GND              VIA   -    MD0080PA00X+162667Y+114813X0160Y         S0      
317GND              VIA   -    MD0080PA00X+162293Y+114813X0160Y         S0      
317GND              VIA   -    MD0080PA00X+161919Y+114813X0160Y         S0      
317GND              VIA   -    MD0080PA00X+161545Y+114813X0160Y         S0      
317GND              VIA   -    MD0080PA00X+162667Y+112569X0160Y         S0      
317GND              VIA   -    MD0080PA00X+162293Y+112569X0160Y         S0      
317GND              VIA   -    MD0080PA00X+161919Y+112569X0160Y         S0      
317GND              VIA   -    MD0080PA00X+161545Y+112569X0160Y         S0      
317GND              VIA   -    MD0080PA00X+162667Y+114065X0160Y         S0      
317GND              VIA   -    MD0080PA00X+162293Y+114065X0160Y         S0      
317GND              VIA   -    MD0080PA00X+161919Y+114065X0160Y         S0      
317GND              VIA   -    MD0080PA00X+161545Y+114065X0160Y         S0      
317GND              VIA   -    MD0080PA00X+162667Y+113317X0160Y         S0      
317GND              VIA   -    MD0080PA00X+162293Y+113317X0160Y         S0      
317GND              VIA   -    MD0080PA00X+161919Y+113317X0160Y         S0      
317GND              VIA   -    MD0080PA00X+161545Y+113317X0160Y         S0      
317GND              VIA   -    MD0080PA00X+161545Y+112195X0160Y         S0      
317GND              VIA   -    MD0080PA00X+161919Y+112195X0160Y         S0      
317GND              VIA   -    MD0080PA00X+162293Y+112195X0160Y         S0      
317GND              VIA   -    MD0080PA00X+162667Y+112195X0160Y         S0      
317GND              VIA   -    MD0080PA00X+161545Y+120797X0160Y         S0      
317GND              VIA   -    MD0080PA00X+161545Y+121171X0160Y         S0      
317GND              VIA   -    MD0080PA00X+162667Y+120797X0160Y         S0      
317GND              VIA   -    MD0080PA00X+162667Y+121171X0160Y         S0      
317GND              VIA   -    MD0080PA00X+162293Y+120797X0160Y         S0      
317GND              VIA   -    MD0080PA00X+161919Y+120797X0160Y         S0      
317GND              VIA   -    MD0080PA00X+162667Y+119675X0160Y         S0      
317GND              VIA   -    MD0080PA00X+162293Y+119675X0160Y         S0      
317GND              VIA   -    MD0080PA00X+161919Y+119675X0160Y         S0      
317GND              VIA   -    MD0080PA00X+161545Y+119675X0160Y         S0      
317GND              VIA   -    MD0080PA00X+162293Y+120423X0160Y         S0      
317GND              VIA   -    MD0080PA00X+162667Y+120423X0160Y         S0      
317GND              VIA   -    MD0080PA00X+161545Y+120423X0160Y         S0      
317GND              VIA   -    MD0080PA00X+161919Y+120423X0160Y         S0      
317GND              VIA   -    MD0080PA00X+163041Y+117057X0160Y         S0      
317GND              VIA   -    MD0080PA00X+163041Y+115935X0160Y         S0      
317GND              VIA   -    MD0080PA00X+163415Y+116683X0160Y         S0      
317GND              VIA   -    MD0080PA00X+164163Y+115561X0160Y         S0      
317GND              VIA   -    MD0080PA00X+163415Y+115561X0160Y         S0      
317GND              VIA   -    MD0080PA00X+164163Y+115187X0160Y         S0      
317GND              VIA   -    MD0080PA00X+164163Y+114813X0160Y         S0      
317GND              VIA   -    MD0080PA00X+164163Y+114439X0160Y         S0      
317GND              VIA   -    MD0080PA00X+163789Y+114813X0160Y         S0      
317GND              VIA   -    MD0080PA00X+163415Y+114813X0160Y         S0      
317GND              VIA   -    MD0080PA00X+163041Y+114813X0160Y         S0      
317GND              VIA   -    MD0080PA00X+163041Y+114065X0160Y         S0      
317GND              VIA   -    MD0080PA00X+164163Y+114065X0160Y         S0      
317GND              VIA   -    MD0080PA00X+163789Y+112569X0160Y         S0      
317GND              VIA   -    MD0080PA00X+163415Y+112569X0160Y         S0      
317GND              VIA   -    MD0080PA00X+163041Y+112569X0160Y         S0      
317GND              VIA   -    MD0080PA00X+164163Y+112943X0160Y         S0      
317GND              VIA   -    MD0080PA00X+164163Y+112569X0160Y         S0      
317GND              VIA   -    MD0080PA00X+163789Y+114065X0160Y         S0      
317GND              VIA   -    MD0080PA00X+163415Y+114065X0160Y         S0      
317GND              VIA   -    MD0080PA00X+164163Y+113317X0160Y         S0      
317GND              VIA   -    MD0080PA00X+163789Y+113317X0160Y         S0      
317GND              VIA   -    MD0080PA00X+163415Y+113317X0160Y         S0      
317GND              VIA   -    MD0080PA00X+163041Y+113317X0160Y         S0      
317GND              VIA   -    MD0080PA00X+164163Y+113691X0160Y         S0      
317GND              VIA   -    MD0080PA00X+164163Y+112195X0160Y         S0      
317GND              VIA   -    MD0080PA00X+163041Y+112195X0160Y         S0      
317GND              VIA   -    MD0080PA00X+163415Y+112195X0160Y         S0      
317GND              VIA   -    MD0080PA00X+163789Y+112195X0160Y         S0      
317GND              VIA   -    MD0080PA00X+164163Y+111821X0160Y         S0      
317GND              VIA   -    MD0080PA00X+164163Y+120797X0160Y         S0      
317GND              VIA   -    MD0080PA00X+163041Y+121171X0160Y         S0      
317GND              VIA   -    MD0080PA00X+163789Y+121171X0160Y         S0      
317GND              VIA   -    MD0080PA00X+163789Y+120797X0160Y         S0      
317GND              VIA   -    MD0080PA00X+163415Y+121171X0160Y         S0      
317GND              VIA   -    MD0080PA00X+163041Y+120797X0160Y         S0      
317GND              VIA   -    MD0080PA00X+163415Y+120797X0160Y         S0      
317GND              VIA   -    MD0080PA00X+164163Y+121171X0160Y         S0      
317GND              VIA   -    MD0080PA00X+164163Y+119301X0160Y         S0      
317GND              VIA   -    MD0080PA00X+163789Y+119675X0160Y         S0      
317GND              VIA   -    MD0080PA00X+163415Y+119675X0160Y         S0      
317GND              VIA   -    MD0080PA00X+163041Y+119675X0160Y         S0      
317GND              VIA   -    MD0080PA00X+164163Y+120049X0160Y         S0      
317GND              VIA   -    MD0080PA00X+163789Y+120423X0160Y         S0      
317GND              VIA   -    MD0080PA00X+163415Y+120423X0160Y         S0      
317GND              VIA   -    MD0080PA00X+163041Y+120423X0160Y         S0      
317GND              VIA   -    MD0080PA00X+164163Y+120423X0160Y         S0      
317GND              VIA   -    MD0080PA00X+164165Y+119673X0160Y         S0      
317GND              VIA   -    MD0080PA00X+164163Y+117431X0160Y         S0      
317GND              VIA   -    MD0080PA00X+163041Y+118927X0160Y         S0      
317GND              VIA   -    MD0080PA00X+164163Y+118927X0160Y         S0      
317GND              VIA   -    MD0080PA00X+163789Y+118179X0160Y         S0      
317GND              VIA   -    MD0080PA00X+163415Y+118179X0160Y         S0      
317GND              VIA   -    MD0080PA00X+163041Y+118179X0160Y         S0      
317GND              VIA   -    MD0080PA00X+164163Y+118553X0160Y         S0      
317GND              VIA   -    MD0080PA00X+163415Y+117431X0160Y         S0      
317GND              VIA   -    MD0080PA00X+164163Y+117805X0160Y         S0      
317GND              VIA   -    MD0080PA00X+163789Y+118927X0160Y         S0      
317GND              VIA   -    MD0080PA00X+163415Y+118927X0160Y         S0      
317GND              VIA   -    MD0080PA00X+165285Y+114065X0160Y         S0      
317GND              VIA   -    MD0080PA00X+164911Y+113691X0160Y         S0      
317GND              VIA   -    MD0080PA00X+164911Y+112943X0160Y    R270 S0      
317GND              VIA   -    MD0080PA00X+164537Y+112195X0160Y    R180 S0      
317GND              VIA   -    MD0080PA00X+164911Y+112195X0160Y    R270 S0      
317GND              VIA   -    MD0080PA00X+164911Y+111821X0160Y         S0      
317GND              VIA   -    MD0080PA00X+164537Y+111821X0160Y         S0      
317GND              VIA   -    MD0080PA00X+166033Y+119675X0160Y    R090 S0      
317GND              VIA   -    MD0080PA00X+164537Y+119675X0160Y         S0      
317GND              VIA   -    MD0080PA00X+164911Y+119301X0160Y         S0      
317GND              VIA   -    MD0080PA00X+165285Y+119301X0160Y         S0      
317GND              VIA   -    MD0080PA00X+165285Y+119675X0160Y         S0      
317GND              VIA   -    MD0080PA00X+166033Y+119301X0160Y    R090 S0      
317GND              VIA   -    MD0080PA00X+166033Y+120049X0160Y    R090 S0      
317GND              VIA   -    MD0080PA00X+166033Y+120423X0160Y    R090 S0      
317GND              VIA   -    MD0080PA00X+165285Y+120423X0160Y         S0      
317GND              VIA   -    MD0080PA00X+165659Y+119301X0160Y         S0      
317GND              VIA   -    MD0080PA00X+164537Y+120423X0160Y    R180 S0      
317GND              VIA   -    MD0080PA00X+164911Y+118553X0160Y         S0      
317GND              VIA   -    MD0080PA00X+165285Y+118927X0160Y         S0      
317GND              VIA   -    MD0080PA00X+164911Y+118927X0160Y         S0      
317GND              VIA   -    MD0080PA00X+164911Y+117805X0160Y         S0      
317GND              VIA   -    MD0080PA00X+164537Y+117431X0160Y         S0      
317GND              VIA   -    MD0080PA00X+164537Y+118179X0160Y         S0      
317GND              VIA   -    MD0080PA00X+166033Y+118553X0160Y         S0      
317GND              VIA   -    MD0080PA00X+166033Y+117805X0160Y         S0      
317GND              VIA   -    MD0080PA00X+166033Y+117431X0160Y         S0      
317GND              VIA   -    MD0080PA00X+165659Y+118553X0160Y         S0      
317GND              VIA   -    MD0080PA00X+164911Y+118179X0160Y         S0      
317GND              VIA   -    MD0080PA00X+165285Y+117431X0160Y         S0      
317GND              VIA   -    MD0080PA00X+165285Y+117805X0160Y         S0      
317GND              VIA   -    MD0080PA00X+165659Y+118179X0160Y         S0      
317GND              VIA   -    MD0080PA00X+165285Y+118553X0160Y         S0      
317GND              VIA   -    MD0080PA00X+165285Y+116683X0160Y         S0      
317GND              VIA   -    MD0080PA00X+165285Y+117057X0160Y         S0      
317GND              VIA   -    MD0080PA00X+164537Y+117057X0160Y         S0      
317GND              VIA   -    MD0080PA00X+166033Y+115935X0160Y         S0      
317GND              VIA   -    MD0080PA00X+164537Y+115935X0160Y         S0      
317GND              VIA   -    MD0080PA00X+166033Y+117057X0160Y         S0      
317GND              VIA   -    MD0080PA00X+166033Y+116683X0160Y         S0      
317GND              VIA   -    MD0080PA00X+165285Y+115935X0160Y         S0      
317GND              VIA   -    MD0080PA00X+164537Y+116683X0160Y         S0      
317GND              VIA   -    MD0080PA00X+164911Y+115187X0160Y         S0      
317GND              VIA   -    MD0080PA00X+166033Y+114439X0160Y    R270 S0      
317GND              VIA   -    MD0080PA00X+166033Y+115561X0160Y         S0      
317GND              VIA   -    MD0080PA00X+166033Y+115187X0160Y         S0      
317GND              VIA   -    MD0080PA00X+165659Y+115187X0160Y         S0      
317GND              VIA   -    MD0080PA00X+165285Y+115187X0160Y         S0      
317GND              VIA   -    MD0080PA00X+164911Y+114813X0160Y         S0      
317GND              VIA   -    MD0080PA00X+165285Y+115561X0160Y         S0      
317GND              VIA   -    MD0080PA00X+164911Y+114439X0160Y         S0      
317GND              VIA   -    MD0080PA00X+165285Y+114813X0160Y         S0      
317GND              VIA   -    MD0080PA00X+164537Y+114813X0160Y         S0      
317GND              VIA   -    MD0080PA00X+164537Y+115187X0160Y         S0      
317GND              VIA   -    MD0080PA00X+164537Y+115561X0160Y         S0      
317GND              VIA   -    MD0080PA00X+164537Y+112569X0160Y         S0      
317GND              VIA   -    MD0080PA00X+164911Y+112569X0160Y    R180 S0      
317GND              VIA   -    MD0080PA00X+165285Y+113691X0160Y         S0      
317GND              VIA   -    MD0080PA00X+164911Y+114065X0160Y         S0      
317GND              VIA   -    MD0080PA00X+164911Y+113317X0160Y    R180 S0      
317GND              VIA   -    MD0080PA00X+166033Y+121171X0160Y         S0      
317GND              VIA   -    MD0080PA00X+166033Y+121545X0160Y         S0      
317GND              VIA   -    MD0080PA00X+166033Y+120797X0160Y    R090 S0      
317GND              VIA   -    MD0080PA00X+164537Y+120797X0160Y         S0      
317GND              VIA   -    MD0080PA00X+164911Y+121171X0160Y         S0      
317GND              VIA   -    MD0080PA00X+163976Y+109764X0160Y         S0      
317GND              VIA   -    MD0080PA00X+163976Y+109390X0160Y         S0      
317GND              VIA   -    MD0080PA00X+167156Y+119301X0160Y    R090 S0      
317GND              VIA   -    MD0080PA00X+167530Y+119301X0160Y    R090 S0      
317GND              VIA   -    MD0080PA00X+166407Y+120423X0160Y         S0      
317GND              VIA   -    MD0080PA00X+166968Y+119488X0160Y    R090 S0      
317GND              VIA   -    MD0080PA00X+166594Y+119488X0160Y         S0      
317GND              VIA   -    MD0080PA00X+167156Y+118927X0160Y         S0      
317GND              VIA   -    MD0080PA00X+167530Y+117805X0160Y    R090 S0      
317GND              VIA   -    MD0080PA00X+167530Y+118553X0160Y    R090 S0      
317GND              VIA   -    MD0080PA00X+166782Y+118927X0160Y    R090 S0      
317GND              VIA   -    MD0080PA00X+166407Y+118179X0160Y         S0      
317GND              VIA   -    MD0080PA00X+166782Y+118179X0160Y    R090 S0      
317GND              VIA   -    MD0080PA00X+166782Y+117431X0160Y    R090 S0      
317GND              VIA   -    MD0080PA00X+167156Y+117431X0160Y         S0      
317GND              VIA   -    MD0080PA00X+167156Y+117805X0160Y    R090 S0      
317GND              VIA   -    MD0080PA00X+167156Y+118179X0160Y         S0      
317GND              VIA   -    MD0080PA00X+167156Y+118553X0160Y    R090 S0      
317GND              VIA   -    MD0080PA00X+166407Y+117431X0160Y         S0      
317GND              VIA   -    MD0080PA00X+166407Y+118927X0160Y         S0      
317GND              VIA   -    MD0080PA00X+167156Y+116683X0160Y         S0      
317GND              VIA   -    MD0080PA00X+167156Y+117057X0160Y    R090 S0      
317GND              VIA   -    MD0080PA00X+167530Y+117057X0160Y    R090 S0      
317GND              VIA   -    MD0080PA00X+166407Y+116683X0160Y         S0      
317GND              VIA   -    MD0080PA00X+166782Y+116683X0160Y    R090 S0      
317GND              VIA   -    MD0080PA00X+167156Y+115935X0160Y         S0      
317GND              VIA   -    MD0080PA00X+166782Y+115935X0160Y    R090 S0      
317GND              VIA   -    MD0080PA00X+166407Y+115935X0160Y         S0      
317GND              VIA   -    MD0080PA00X+166782Y+114439X0160Y    R090 S0      
317GND              VIA   -    MD0080PA00X+166407Y+114439X0160Y         S0      
317GND              VIA   -    MD0080PA00X+167156Y+114439X0160Y    R270 S0      
317GND              VIA   -    MD0080PA00X+167156Y+114813X0160Y         S0      
317GND              VIA   -    MD0080PA00X+167156Y+115187X0160Y    R270 S0      
317GND              VIA   -    MD0080PA00X+167156Y+115561X0160Y    R180 S0      
317GND              VIA   -    MD0080PA00X+167530Y+114813X0160Y    R090 S0      
317GND              VIA   -    MD0080PA00X+167530Y+115561X0160Y    R090 S0      
317GND              VIA   -    MD0080PA00X+166407Y+115187X0160Y         S0      
317GND              VIA   -    MD0080PA00X+166782Y+115187X0160Y    R090 S0      
317GND              VIA   -    MD0080PA00X+164724Y+107894X0160Y    R180 S0      
317GND              VIA   -    MD0080PA00X+164724Y+109016X0160Y         S0      
317GND              VIA   -    MD0080PA00X+165098Y+109016X0160Y         S0      
317GND              VIA   -    MD0080PA00X+167156Y+113691X0160Y    R270 S0      
317GND              VIA   -    MD0080PA00X+167156Y+114065X0160Y         S0      
317GND              VIA   -    MD0080PA00X+167530Y+114065X0160Y    R090 S0      
317GND              VIA   -    MD0080PA00X+163976Y+109016X0160Y         S0      
317GND              VIA   -    MD0080PA00X+167904Y+119301X0160Y         S0      
317GND              VIA   -    MD0080PA00X+169026Y+119301X0160Y         S0      
317GND              VIA   -    MD0080PA00X+169026Y+118179X0160Y    R270 S0      
317GND              VIA   -    MD0080PA00X+169026Y+118553X0160Y         S0      
317GND              VIA   -    MD0080PA00X+169026Y+118927X0160Y    R270 S0      
317GND              VIA   -    MD0080PA00X+168652Y+118927X0160Y    R090 S0      
317GND              VIA   -    MD0080PA00X+168652Y+118179X0160Y    R090 S0      
317GND              VIA   -    MD0080PA00X+168278Y+118927X0160Y         S0      
317GND              VIA   -    MD0080PA00X+167904Y+118553X0160Y         S0      
317GND              VIA   -    MD0080PA00X+168278Y+118179X0160Y         S0      
317GND              VIA   -    MD0080PA00X+167904Y+117805X0160Y         S0      
317GND              VIA   -    MD0080PA00X+168278Y+117431X0160Y         S0      
317GND              VIA   -    MD0080PA00X+169026Y+117431X0160Y    R270 S0      
317GND              VIA   -    MD0080PA00X+168652Y+117431X0160Y    R090 S0      
317GND              VIA   -    MD0080PA00X+169026Y+117805X0160Y         S0      
317GND              VIA   -    MD0080PA00X+169026Y+116683X0160Y    R270 S0      
317GND              VIA   -    MD0080PA00X+169026Y+117057X0160Y         S0      
317GND              VIA   -    MD0080PA00X+168652Y+116683X0160Y    R090 S0      
317GND              VIA   -    MD0080PA00X+167904Y+115935X0160Y    R270 S0      
317GND              VIA   -    MD0080PA00X+168278Y+115935X0160Y    R090 S0      
317GND              VIA   -    MD0080PA00X+169026Y+115935X0160Y    R270 S0      
317GND              VIA   -    MD0080PA00X+168652Y+115935X0160Y    R090 S0      
317GND              VIA   -    MD0080PA00X+167904Y+117057X0160Y         S0      
317GND              VIA   -    MD0080PA00X+168278Y+116683X0160Y         S0      
317GND              VIA   -    MD0080PA00X+169026Y+114813X0160Y         S0      
317GND              VIA   -    MD0080PA00X+169026Y+115187X0160Y    R270 S0      
317GND              VIA   -    MD0080PA00X+168652Y+115187X0160Y    R090 S0      
317GND              VIA   -    MD0080PA00X+169026Y+115561X0160Y         S0      
317GND              VIA   -    MD0080PA00X+168652Y+114439X0160Y    R090 S0      
317GND              VIA   -    MD0080PA00X+167904Y+115561X0160Y    R270 S0      
317GND              VIA   -    MD0080PA00X+168278Y+115187X0160Y    R090 S0      
317GND              VIA   -    MD0080PA00X+167904Y+114813X0160Y    R270 S0      
317GND              VIA   -    MD0080PA00X+168278Y+114439X0160Y    R090 S0      
317GND              VIA   -    MD0080PA00X+169026Y+114439X0160Y    R270 S0      
317GND              VIA   -    MD0080PA00X+167904Y+114065X0160Y    R270 S0      
317GND              VIA   -    MD0080PA00X+168278Y+113691X0160Y    R090 S0      
317GND              VIA   -    MD0080PA00X+162480Y+109390X0160Y         S0      
317GND              VIA   -    MD0080PA00X+163228Y+109764X0160Y         S0      
317GND              VIA   -    MD0080PA00X+169026Y+113691X0160Y    R270 S0      
317GND              VIA   -    MD0080PA00X+168652Y+113691X0160Y    R090 S0      
317GND              VIA   -    MD0080PA00X+169026Y+114065X0160Y         S0      
317GND              VIA   -    MD0080PA00X+168090Y+119488X0160Y         S0      
317GND              VIA   -    MD0080PA00X+164350Y+108642X0160Y         S0      
317GND              VIA   -    MD0080PA00X+162854Y+110138X0160Y    R270 S0      
317GND              VIA   -    MD0080PA00X+169768Y+119301X0160Y         S0      
317GND              VIA   -    MD0080PA00X+169400Y+119301X0160Y         S0      
317GND              VIA   -    MD0080PA00X+169400Y+118553X0160Y         S0      
317GND              VIA   -    MD0080PA00X+169774Y+118553X0160Y    R180 S0      
317GND              VIA   -    MD0080PA00X+169400Y+117805X0160Y         S0      
317GND              VIA   -    MD0080PA00X+169774Y+117805X0160Y    R180 S0      
317GND              VIA   -    MD0080PA00X+169774Y+117057X0160Y    R180 S0      
317GND              VIA   -    MD0080PA00X+169774Y+116683X0160Y    R270 S0      
317GND              VIA   -    MD0080PA00X+169400Y+116683X0160Y    R270 S0      
317GND              VIA   -    MD0080PA00X+169400Y+117057X0160Y         S0      
317GND              VIA   -    MD0080PA00X+169400Y+115561X0160Y    R180 S0      
317GND              VIA   -    MD0080PA00X+169774Y+115561X0160Y    R180 S0      
317GND              VIA   -    MD0080PA00X+169400Y+114813X0160Y    R180 S0      
317GND              VIA   -    MD0080PA00X+169774Y+114813X0160Y    R180 S0      
317GND              VIA   -    MD0080PA00X+161732Y+107894X0160Y         S0      
317GND              VIA   -    MD0080PA00X+169400Y+114065X0160Y    R180 S0      
317GND              VIA   -    MD0080PA00X+169774Y+114065X0160Y    R180 S0      
317GND              VIA   -    MD0080PA00X+161732Y+109016X0160Y         S0      
317GND              VIA   -    MD0080PA00X+170024Y+113691X0160Y    R270 S0      
317GND              VIA   -    MD0080PA00X+160610Y+122106X0160Y         S0      
317GND              VIA   -    MD0080PA00X+161732Y+122106X0160Y         S0      
317GND              VIA   -    MD0080PA00X+165098Y+108642X0160Y    R180 S0      
317GND              VIA   -    MD0080PA00X+165098Y+108268X0160Y    R180 S0      
317GND              VIA   -    MD0080PA00X+164350Y+110138X0160Y    R270 S0      
317GND              VIA   -    MD0080PA00X+166220Y+109016X0160Y         S0      
317GND              VIA   -    MD0080PA00X+166220Y+107894X0160Y    R180 S0      
317GND              VIA   -    MD0080PA00X+165846Y+108268X0160Y    R180 S0      
317GND              VIA   -    MD0080PA00X+165846Y+108642X0160Y    R270 S0      
317GND              VIA   -    MD0080PA00X+165846Y+109016X0160Y         S0      
317GND              VIA   -    MD0080PA00X+165472Y+109016X0160Y         S0      
317GND              VIA   -    MD0080PA00X+165472Y+107894X0160Y         S0      
317GND              VIA   -    MD0080PA00X+164724Y+109390X0160Y         S0      
317GND              VIA   -    MD0080PA00X+164724Y+109764X0160Y    R180 S0      
317GND              VIA   -    MD0080PA00X+165472Y+107520X0160Y         S0      
317GND              VIA   -    MD0080PA00X+163602Y+110138X0160Y    R270 S0      
317GND              VIA   -    MD0080PA00X+161732Y+109764X0160Y         S0      
317GND              VIA   -    MD0080PA00X+161732Y+109390X0160Y         S0      
317GND              VIA   -    MD0080PA00X+163228Y+109390X0160Y         S0      
317GND              VIA   -    MD0080PA00X+164350Y+109016X0160Y         S0      
317GND              VIA   -    MD0080PA00X+163602Y+108642X0160Y         S0      
317GND              VIA   -    MD0080PA00X+163602Y+108268X0160Y    R180 S0      
317GND              VIA   -    MD0080PA00X+164350Y+108268X0160Y         S0      
317GND              VIA   -    MD0080PA00X+164724Y+107520X0160Y         S0      
317GND              VIA   -    MD0080PA00X+163976Y+107520X0160Y         S0      
317GND              VIA   -    MD0080PA00X+163602Y+109016X0160Y         S0      
317GND              VIA   -    MD0080PA00X+106860Y+107707X0160Y    R180 S0      
317GND              VIA   -    MD0080PA00X+106112Y+107707X0160Y    R180 S0      
317GND              VIA   -    MD0080PA00X+106112Y+108081X0160Y         S0      
317GND              VIA   -    MD0080PA00X+106486Y+108081X0160Y    R180 S0      
317GND              VIA   -    MD0080PA00X+106486Y+108455X0160Y    R180 S0      
317GND              VIA   -    MD0080PA00X+106112Y+108455X0160Y    R180 S0      
317GND              VIA   -    MD0080PA00X+106860Y+108829X0160Y    R180 S0      
317GND              VIA   -    MD0080PA00X+106486Y+108829X0160Y    R180 S0      
317GND              VIA   -    MD0080PA00X+106860Y+109203X0160Y    R180 S0      
317GND              VIA   -    MD0080PA00X+106112Y+109203X0160Y    R180 S0      
317GND              VIA   -    MD0080PA00X+106486Y+107707X0160Y         S0      
317GND              VIA   -    MD0080PA00X+106860Y+107333X0160Y    R180 S0      
317GND              VIA   -    MD0080PA00X+106860Y+112943X0160Y         S0      
317GND              VIA   -    MD0080PA00X+106486Y+112943X0160Y         S0      
317GND              VIA   -    MD0080PA00X+106112Y+113317X0160Y         S0      
317GND              VIA   -    MD0080PA00X+106486Y+113691X0160Y         S0      
317GND              VIA   -    MD0080PA00X+106860Y+114065X0160Y         S0      
317GND              VIA   -    MD0080PA00X+106486Y+114065X0160Y         S0      
317GND              VIA   -    MD0080PA00X+106112Y+114065X0160Y         S0      
317GND              VIA   -    MD0080PA00X+105738Y+111073X0160Y    R180 S0      
317GND              VIA   -    MD0080PA00X+105738Y+111821X0160Y    R180 S0      
317GND              VIA   -    MD0080PA00X+106112Y+111073X0160Y    R180 S0      
317GND              VIA   -    MD0080PA00X+106860Y+111447X0160Y    R180 S0      
317GND              VIA   -    MD0080PA00X+106486Y+111447X0160Y    R180 S0      
317GND              VIA   -    MD0080PA00X+106112Y+111821X0160Y    R180 S0      
317GND              VIA   -    MD0080PA00X+106860Y+112195X0160Y         S0      
317GND              VIA   -    MD0080PA00X+106486Y+112195X0160Y         S0      
317GND              VIA   -    MD0080PA00X+105738Y+110325X0160Y         S0      
317GND              VIA   -    MD0080PA00X+105738Y+109577X0160Y    R180 S0      
317GND              VIA   -    MD0080PA00X+106486Y+109951X0160Y    R180 S0      
317GND              VIA   -    MD0080PA00X+106486Y+110325X0160Y    R180 S0      
317GND              VIA   -    MD0080PA00X+106112Y+110325X0160Y         S0      
317GND              VIA   -    MD0080PA00X+106860Y+110699X0160Y    R180 S0      
317GND              VIA   -    MD0080PA00X+106486Y+110699X0160Y    R180 S0      
317GND              VIA   -    MD0080PA00X+106860Y+109577X0160Y    R180 S0      
317GND              VIA   -    MD0080PA00X+106112Y+109577X0160Y    R180 S0      
317GND              VIA   -    MD0080PA00X+105738Y+108455X0160Y    R180 S0      
317GND              VIA   -    MD0080PA00X+105738Y+109203X0160Y    R180 S0      
317GND              VIA   -    MD0080PA00X+106486Y+117431X0160Y         S0      
317GND              VIA   -    MD0080PA00X+106112Y+117431X0160Y         S0      
317GND              VIA   -    MD0080PA00X+106486Y+117805X0160Y         S0      
317GND              VIA   -    MD0080PA00X+106860Y+117431X0160Y         S0      
317GND              VIA   -    MD0080PA00X+106860Y+118179X0160Y         S0      
317GND              VIA   -    MD0080PA00X+106486Y+118179X0160Y         S0      
317GND              VIA   -    MD0080PA00X+106112Y+118179X0160Y         S0      
317GND              VIA   -    MD0080PA00X+105738Y+115935X0160Y         S0      
317GND              VIA   -    MD0080PA00X+106112Y+116683X0160Y    R180 S0      
317GND              VIA   -    MD0080PA00X+106486Y+115935X0160Y         S0      
317GND              VIA   -    MD0080PA00X+106112Y+115935X0160Y         S0      
317GND              VIA   -    MD0080PA00X+106860Y+116683X0160Y    R270 S0      
317GND              VIA   -    MD0080PA00X+106486Y+116683X0160Y         S0      
317GND              VIA   -    MD0080PA00X+106860Y+117057X0160Y         S0      
317GND              VIA   -    MD0080PA00X+106486Y+117057X0160Y         S0      
317GND              VIA   -    MD0080PA00X+105738Y+114439X0160Y         S0      
317GND              VIA   -    MD0080PA00X+105738Y+115187X0160Y         S0      
317GND              VIA   -    MD0080PA00X+106486Y+114439X0160Y         S0      
317GND              VIA   -    MD0080PA00X+106112Y+114439X0160Y         S0      
317GND              VIA   -    MD0080PA00X+106860Y+115187X0160Y    R270 S0      
317GND              VIA   -    MD0080PA00X+106486Y+114813X0160Y         S0      
317GND              VIA   -    MD0080PA00X+106486Y+115187X0160Y         S0      
317GND              VIA   -    MD0080PA00X+106112Y+115187X0160Y         S0      
317GND              VIA   -    MD0080PA00X+106860Y+115561X0160Y         S0      
317GND              VIA   -    MD0080PA00X+106486Y+115561X0160Y         S0      
317GND              VIA   -    MD0080PA00X+105738Y+112569X0160Y         S0      
317GND              VIA   -    MD0080PA00X+105738Y+113317X0160Y         S0      
317GND              VIA   -    MD0080PA00X+105738Y+114065X0160Y         S0      
317GND              VIA   -    MD0080PA00X+106112Y+112569X0160Y         S0      
317GND              VIA   -    MD0080PA00X+014321Y+110325X0160Y         S0      
317GND              VIA   -    MD0080PA00X+014695Y+109203X0160Y    R180 S0      
317GND              VIA   -    MD0080PA00X+014695Y+108455X0160Y    R180 S0      
317GND              VIA   -    MD0080PA00X+014695Y+108081X0160Y         S0      
317GND              VIA   -    MD0080PA00X+014695Y+107707X0160Y    R180 S0      
317GND              VIA   -    MD0080PA00X+014321Y+109203X0160Y    R180 S0      
317GND              VIA   -    MD0080PA00X+014321Y+108455X0160Y    R180 S0      
317GND              VIA   -    MD0080PA00X+014134Y+119862X0160Y         S0      
317GND              VIA   -    MD0080PA00X+014882Y+120236X0160Y         S0      
317GND              VIA   -    MD0080PA00X+014882Y+119488X0160Y         S0      
317GND              VIA   -    MD0080PA00X+014508Y+120236X0160Y         S0      
317GND              VIA   -    MD0080PA00X+014508Y+119488X0160Y         S0      
317GND              VIA   -    MD0080PA00X+014134Y+119114X0160Y         S0      
317GND              VIA   -    MD0080PA00X+014882Y+118740X0160Y         S0      
317GND              VIA   -    MD0080PA00X+014508Y+118366X0160Y         S0      
317GND              VIA   -    MD0080PA00X+014508Y+118740X0160Y         S0      
317GND              VIA   -    MD0080PA00X+014071Y+117805X0160Y         S0      
317GND              VIA   -    MD0080PA00X+014695Y+115935X0160Y         S0      
317GND              VIA   -    MD0080PA00X+014695Y+116683X0160Y    R180 S0      
317GND              VIA   -    MD0080PA00X+014321Y+115935X0160Y         S0      
317GND              VIA   -    MD0080PA00X+014071Y+117057X0160Y         S0      
317GND              VIA   -    MD0080PA00X+014695Y+115187X0160Y         S0      
317GND              VIA   -    MD0080PA00X+014695Y+114439X0160Y         S0      
317GND              VIA   -    MD0080PA00X+014321Y+115187X0160Y         S0      
317GND              VIA   -    MD0080PA00X+014321Y+114439X0160Y         S0      
317GND              VIA   -    MD0080PA00X+014695Y+112569X0160Y         S0      
317GND              VIA   -    MD0080PA00X+014321Y+114065X0160Y         S0      
317GND              VIA   -    MD0080PA00X+014321Y+113317X0160Y         S0      
317GND              VIA   -    MD0080PA00X+014321Y+112569X0160Y         S0      
317GND              VIA   -    MD0080PA00X+013947Y+113691X0160Y         S0      
317GND              VIA   -    MD0080PA00X+014695Y+114065X0160Y         S0      
317GND              VIA   -    MD0080PA00X+014695Y+113317X0160Y         S0      
317GND              VIA   -    MD0080PA00X+014695Y+111821X0160Y    R180 S0      
317GND              VIA   -    MD0080PA00X+014695Y+111073X0160Y    R180 S0      
317GND              VIA   -    MD0080PA00X+014321Y+111821X0160Y    R180 S0      
317GND              VIA   -    MD0080PA00X+014321Y+111073X0160Y    R180 S0      
317GND              VIA   -    MD0080PA00X+014695Y+110325X0160Y         S0      
317GND              VIA   -    MD0080PA00X+014695Y+109577X0160Y    R180 S0      
317GND              VIA   -    MD0080PA00X+014321Y+109577X0160Y    R180 S0      
317GND              VIA   -    MD0080PA00X+014508Y+124350X0160Y    R270 S0      
317GND              VIA   -    MD0080PA00X+014134Y+123976X0160Y    R090 S0      
317GND              VIA   -    MD0080PA00X+014134Y+124724X0160Y    R090 S0      
317GND              VIA   -    MD0080PA00X+014134Y+122854X0160Y    R090 S0      
317GND              VIA   -    MD0080PA00X+014508Y+122480X0160Y         S0      
317GND              VIA   -    MD0080PA00X+014882Y+123602X0160Y         S0      
317GND              VIA   -    MD0080PA00X+014882Y+123228X0160Y         S0      
317GND              VIA   -    MD0080PA00X+014508Y+123602X0160Y         S0      
317GND              VIA   -    MD0080PA00X+014508Y+123228X0160Y         S0      
317GND              VIA   -    MD0080PA00X+014134Y+122106X0160Y         S0      
317GND              VIA   -    MD0080PA00X+014134Y+121358X0160Y         S0      
317GND              VIA   -    MD0080PA00X+014882Y+121732X0160Y         S0      
317GND              VIA   -    MD0080PA00X+014882Y+120984X0160Y         S0      
317GND              VIA   -    MD0080PA00X+014508Y+121732X0160Y         S0      
317GND              VIA   -    MD0080PA00X+014508Y+120984X0160Y         S0      
317GND              VIA   -    MD0080PA00X+014134Y+120610X0160Y         S0      
317GND              VIA   -    MD0080PA00X+014882Y+125098X0160Y    R270 S0      
317GND              VIA   -    MD0080PA00X+014882Y+124350X0160Y    R270 S0      
317GND              VIA   -    MD0080PA00X+014508Y+125098X0160Y    R270 S0      
317GND              VIA   -    MD0080PA00X+015069Y+108829X0160Y    R180 S0      
317GND              VIA   -    MD0080PA00X+015443Y+108829X0160Y    R180 S0      
317GND              VIA   -    MD0080PA00X+015817Y+108829X0160Y    R180 S0      
317GND              VIA   -    MD0080PA00X+015069Y+108455X0160Y    R180 S0      
317GND              VIA   -    MD0080PA00X+015817Y+108455X0160Y    R180 S0      
317GND              VIA   -    MD0080PA00X+015069Y+108081X0160Y    R180 S0      
317GND              VIA   -    MD0080PA00X+015817Y+108081X0160Y    R180 S0      
317GND              VIA   -    MD0080PA00X+015443Y+107707X0160Y    R180 S0      
317GND              VIA   -    MD0080PA00X+015069Y+107707X0160Y         S0      
317GND              VIA   -    MD0080PA00X+016191Y+107333X0160Y    R180 S0      
317GND              VIA   -    MD0080PA00X+015443Y+107333X0160Y    R180 S0      
317GND              VIA   -    MD0080PA00X+015069Y+114813X0160Y         S0      
317GND              VIA   -    MD0080PA00X+015443Y+115187X0160Y    R270 S0      
317GND              VIA   -    MD0080PA00X+015817Y+115187X0160Y    R270 S0      
317GND              VIA   -    MD0080PA00X+015069Y+114439X0160Y         S0      
317GND              VIA   -    MD0080PA00X+016191Y+115561X0160Y         S0      
317GND              VIA   -    MD0080PA00X+016191Y+115187X0160Y         S0      
317GND              VIA   -    MD0080PA00X+016191Y+114813X0160Y         S0      
317GND              VIA   -    MD0080PA00X+016191Y+114439X0160Y         S0      
317GND              VIA   -    MD0080PA00X+015817Y+114065X0160Y         S0      
317GND              VIA   -    MD0080PA00X+016565Y+113691X0160Y         S0      
317GND              VIA   -    MD0080PA00X+016191Y+112943X0160Y    R090 S0      
317GND              VIA   -    MD0080PA00X+016565Y+112943X0160Y         S0      
317GND              VIA   -    MD0080PA00X+016191Y+112569X0160Y    R270 S0      
317GND              VIA   -    MD0080PA00X+016565Y+114065X0160Y         S0      
317GND              VIA   -    MD0080PA00X+015069Y+114065X0160Y         S0      
317GND              VIA   -    MD0080PA00X+015443Y+114065X0160Y         S0      
317GND              VIA   -    MD0080PA00X+015069Y+113691X0160Y         S0      
317GND              VIA   -    MD0080PA00X+015069Y+112943X0160Y         S0      
317GND              VIA   -    MD0080PA00X+015443Y+112943X0160Y         S0      
317GND              VIA   -    MD0080PA00X+015817Y+112943X0160Y    R180 S0      
317GND              VIA   -    MD0080PA00X+015817Y+112569X0160Y         S0      
317GND              VIA   -    MD0080PA00X+016191Y+114065X0160Y         S0      
317GND              VIA   -    MD0080PA00X+015817Y+113317X0160Y         S0      
317GND              VIA   -    MD0080PA00X+016191Y+111447X0160Y         S0      
317GND              VIA   -    MD0080PA00X+016565Y+111447X0160Y         S0      
317GND              VIA   -    MD0080PA00X+015069Y+112195X0160Y         S0      
317GND              VIA   -    MD0080PA00X+015443Y+112195X0160Y         S0      
317GND              VIA   -    MD0080PA00X+015817Y+112195X0160Y         S0      
317GND              VIA   -    MD0080PA00X+015817Y+111821X0160Y         S0      
317GND              VIA   -    MD0080PA00X+015069Y+111447X0160Y    R180 S0      
317GND              VIA   -    MD0080PA00X+015443Y+111447X0160Y    R180 S0      
317GND              VIA   -    MD0080PA00X+015817Y+111447X0160Y    R180 S0      
317GND              VIA   -    MD0080PA00X+015817Y+111073X0160Y    R180 S0      
317GND              VIA   -    MD0080PA00X+015443Y+109577X0160Y    R180 S0      
317GND              VIA   -    MD0080PA00X+015069Y+110699X0160Y    R180 S0      
317GND              VIA   -    MD0080PA00X+015443Y+110699X0160Y    R180 S0      
317GND              VIA   -    MD0080PA00X+016191Y+110699X0160Y         S0      
317GND              VIA   -    MD0080PA00X+016565Y+110699X0160Y         S0      
317GND              VIA   -    MD0080PA00X+016565Y+110325X0160Y    R180 S0      
317GND              VIA   -    MD0080PA00X+016565Y+109951X0160Y    R180 S0      
317GND              VIA   -    MD0080PA00X+016191Y+109577X0160Y    R180 S0      
317GND              VIA   -    MD0080PA00X+015817Y+110699X0160Y         S0      
317GND              VIA   -    MD0080PA00X+015069Y+110325X0160Y    R180 S0      
317GND              VIA   -    MD0080PA00X+015817Y+110325X0160Y    R180 S0      
317GND              VIA   -    MD0080PA00X+015069Y+109951X0160Y    R180 S0      
317GND              VIA   -    MD0080PA00X+015817Y+109951X0160Y    R180 S0      
317GND              VIA   -    MD0080PA00X+016191Y+109203X0160Y    R180 S0      
317GND              VIA   -    MD0080PA00X+016191Y+108829X0160Y    R180 S0      
317GND              VIA   -    MD0080PA00X+016565Y+108829X0160Y    R180 S0      
317GND              VIA   -    MD0080PA00X+016565Y+108081X0160Y    R180 S0      
317GND              VIA   -    MD0080PA00X+016191Y+107707X0160Y    R180 S0      
317GND              VIA   -    MD0080PA00X+015443Y+109203X0160Y    R180 S0      
317GND              VIA   -    MD0080PA00X+016565Y+117431X0160Y    R180 S0      
317GND              VIA   -    MD0080PA00X+016565Y+117805X0160Y    R180 S0      
317GND              VIA   -    MD0080PA00X+016191Y+118179X0160Y         S0      
317GND              VIA   -    MD0080PA00X+016565Y+118179X0160Y         S0      
317GND              VIA   -    MD0080PA00X+016191Y+117805X0160Y         S0      
317GND              VIA   -    MD0080PA00X+016191Y+117431X0160Y         S0      
317GND              VIA   -    MD0080PA00X+016378Y+119114X0160Y         S0      
317GND              VIA   -    MD0080PA00X+016752Y+119114X0160Y         S0      
317GND              VIA   -    MD0080PA00X+016004Y+119114X0160Y         S0      
317GND              VIA   -    MD0080PA00X+015630Y+119114X0160Y         S0      
317GND              VIA   -    MD0080PA00X+015256Y+119114X0160Y         S0      
317GND              VIA   -    MD0080PA00X+014882Y+118366X0160Y         S0      
317GND              VIA   -    MD0080PA00X+015256Y+118366X0160Y         S0      
317GND              VIA   -    MD0080PA00X+015630Y+118366X0160Y         S0      
317GND              VIA   -    MD0080PA00X+016004Y+118740X0160Y         S0      
317GND              VIA   -    MD0080PA00X+016565Y+117057X0160Y    R180 S0      
317GND              VIA   -    MD0080PA00X+016565Y+116683X0160Y    R180 S0      
317GND              VIA   -    MD0080PA00X+016191Y+115935X0160Y         S0      
317GND              VIA   -    MD0080PA00X+015069Y+117057X0160Y         S0      
317GND              VIA   -    MD0080PA00X+015443Y+117057X0160Y         S0      
317GND              VIA   -    MD0080PA00X+015069Y+116683X0160Y         S0      
317GND              VIA   -    MD0080PA00X+015443Y+116683X0160Y    R270 S0      
317GND              VIA   -    MD0080PA00X+015817Y+116683X0160Y         S0      
317GND              VIA   -    MD0080PA00X+015069Y+115935X0160Y         S0      
317GND              VIA   -    MD0080PA00X+015069Y+115561X0160Y         S0      
317GND              VIA   -    MD0080PA00X+015443Y+115561X0160Y         S0      
317GND              VIA   -    MD0080PA00X+015817Y+115561X0160Y         S0      
317GND              VIA   -    MD0080PA00X+015069Y+115187X0160Y         S0      
317GND              VIA   -    MD0080PA00X+016004Y+121358X0160Y    R180 S0      
317GND              VIA   -    MD0080PA00X+016378Y+122106X0160Y         S0      
317GND              VIA   -    MD0080PA00X+016378Y+121358X0160Y    R180 S0      
317GND              VIA   -    MD0080PA00X+015256Y+122106X0160Y         S0      
317GND              VIA   -    MD0080PA00X+015630Y+122106X0160Y         S0      
317GND              VIA   -    MD0080PA00X+016004Y+122106X0160Y         S0      
317GND              VIA   -    MD0080PA00X+015256Y+121358X0160Y         S0      
317GND              VIA   -    MD0080PA00X+015630Y+121358X0160Y         S0      
317GND              VIA   -    MD0080PA00X+016004Y+121732X0160Y    R270 S0      
317GND              VIA   -    MD0080PA00X+016004Y+120984X0160Y    R270 S0      
317GND              VIA   -    MD0080PA00X+016752Y+122106X0160Y    R270 S0      
317GND              VIA   -    MD0080PA00X+016004Y+119862X0160Y         S0      
317GND              VIA   -    MD0080PA00X+016378Y+119862X0160Y         S0      
317GND              VIA   -    MD0080PA00X+016752Y+120610X0160Y         S0      
317GND              VIA   -    MD0080PA00X+016378Y+120610X0160Y         S0      
317GND              VIA   -    MD0080PA00X+015256Y+120610X0160Y         S0      
317GND              VIA   -    MD0080PA00X+015630Y+120610X0160Y         S0      
317GND              VIA   -    MD0080PA00X+016004Y+120610X0160Y         S0      
317GND              VIA   -    MD0080PA00X+015256Y+119862X0160Y         S0      
317GND              VIA   -    MD0080PA00X+015630Y+119862X0160Y         S0      
317GND              VIA   -    MD0080PA00X+016004Y+120236X0160Y    R270 S0      
317GND              VIA   -    MD0080PA00X+016004Y+119488X0160Y    R270 S0      
317GND              VIA   -    MD0080PA00X+016378Y+123976X0160Y         S0      
317GND              VIA   -    MD0080PA00X+016378Y+123228X0160Y         S0      
317GND              VIA   -    MD0080PA00X+016752Y+122480X0160Y         S0      
317GND              VIA   -    MD0080PA00X+016752Y+122854X0160Y    R090 S0      
317GND              VIA   -    MD0080PA00X+016378Y+123602X0160Y         S0      
317GND              VIA   -    MD0080PA00X+015630Y+123602X0160Y         S0      
317GND              VIA   -    MD0080PA00X+015630Y+123228X0160Y         S0      
317GND              VIA   -    MD0080PA00X+015256Y+122480X0160Y         S0      
317GND              VIA   -    MD0080PA00X+016004Y+122480X0160Y         S0      
317GND              VIA   -    MD0080PA00X+014882Y+122480X0160Y         S0      
317GND              VIA   -    MD0080PA00X+015256Y+122854X0160Y         S0      
317GND              VIA   -    MD0080PA00X+016004Y+122854X0160Y    R090 S0      
317GND              VIA   -    MD0080PA00X+016378Y+125472X0160Y    R270 S0      
317GND              VIA   -    MD0080PA00X+015630Y+125472X0160Y    R270 S0      
317GND              VIA   -    MD0080PA00X+016004Y+125846X0160Y         S0      
317GND              VIA   -    MD0080PA00X+015256Y+125846X0160Y         S0      
317GND              VIA   -    MD0080PA00X+016752Y+125846X0160Y         S0      
317GND              VIA   -    MD0080PA00X+016378Y+125098X0160Y    R270 S0      
317GND              VIA   -    MD0080PA00X+016752Y+124724X0160Y    R270 S0      
317GND              VIA   -    MD0080PA00X+016752Y+124350X0160Y         S0      
317GND              VIA   -    MD0080PA00X+016752Y+123976X0160Y         S0      
317GND              VIA   -    MD0080PA00X+015630Y+123976X0160Y    R270 S0      
317GND              VIA   -    MD0080PA00X+015256Y+124724X0160Y    R270 S0      
317GND              VIA   -    MD0080PA00X+016004Y+124350X0160Y         S0      
317GND              VIA   -    MD0080PA00X+016004Y+124724X0160Y    R270 S0      
317GND              VIA   -    MD0080PA00X+015630Y+125098X0160Y    R270 S0      
317GND              VIA   -    MD0080PA00X+015256Y+124350X0160Y         S0      
317GND              VIA   -    MD0080PA00X+015256Y+123976X0160Y         S0      
317GND              VIA   -    MD0080PA00X+016004Y+123976X0160Y         S0      
317GND              VIA   -    MD0080PA00X+017126Y+107520X0160Y    R270 S0      
317GND              VIA   -    MD0080PA00X+017874Y+107520X0160Y    R270 S0      
317GND              VIA   -    MD0080PA00X+018248Y+107146X0160Y         S0      
317GND              VIA   -    MD0080PA00X+017500Y+107146X0160Y         S0      
317GND              VIA   -    MD0080PA00X+018061Y+113317X0160Y         S0      
317GND              VIA   -    MD0080PA00X+018061Y+112943X0160Y         S0      
317GND              VIA   -    MD0080PA00X+018061Y+112569X0160Y         S0      
317GND              VIA   -    MD0080PA00X+018061Y+114065X0160Y         S0      
317GND              VIA   -    MD0080PA00X+016939Y+112943X0160Y    R270 S0      
317GND              VIA   -    MD0080PA00X+017313Y+112943X0160Y    R270 S0      
317GND              VIA   -    MD0080PA00X+016939Y+114065X0160Y         S0      
317GND              VIA   -    MD0080PA00X+017313Y+114065X0160Y         S0      
317GND              VIA   -    MD0080PA00X+017687Y+113691X0160Y         S0      
317GND              VIA   -    MD0080PA00X+017687Y+113317X0160Y         S0      
317GND              VIA   -    MD0080PA00X+017687Y+112943X0160Y         S0      
317GND              VIA   -    MD0080PA00X+017687Y+112569X0160Y         S0      
317GND              VIA   -    MD0080PA00X+017687Y+114065X0160Y         S0      
317GND              VIA   -    MD0080PA00X+016939Y+113317X0160Y         S0      
317GND              VIA   -    MD0080PA00X+017313Y+113317X0160Y         S0      
317GND              VIA   -    MD0080PA00X+018248Y+111260X0160Y         S0      
317GND              VIA   -    MD0080PA00X+018061Y+112195X0160Y         S0      
317GND              VIA   -    MD0080PA00X+018061Y+111821X0160Y         S0      
317GND              VIA   -    MD0080PA00X+018061Y+111447X0160Y         S0      
317GND              VIA   -    MD0080PA00X+016939Y+111073X0160Y         S0      
317GND              VIA   -    MD0080PA00X+017313Y+111073X0160Y         S0      
317GND              VIA   -    MD0080PA00X+017874Y+111260X0160Y         S0      
317GND              VIA   -    MD0080PA00X+017687Y+112195X0160Y         S0      
317GND              VIA   -    MD0080PA00X+017687Y+111821X0160Y         S0      
317GND              VIA   -    MD0080PA00X+017687Y+111447X0160Y         S0      
317GND              VIA   -    MD0080PA00X+016939Y+112195X0160Y    R090 S0      
317GND              VIA   -    MD0080PA00X+017874Y+110886X0160Y         S0      
317GND              VIA   -    MD0080PA00X+018248Y+110512X0160Y         S0      
317GND              VIA   -    MD0080PA00X+018248Y+110138X0160Y         S0      
317GND              VIA   -    MD0080PA00X+017500Y+110512X0160Y         S0      
317GND              VIA   -    MD0080PA00X+017126Y+109764X0160Y    R270 S0      
317GND              VIA   -    MD0080PA00X+017126Y+109390X0160Y         S0      
317GND              VIA   -    MD0080PA00X+017500Y+110886X0160Y         S0      
317GND              VIA   -    MD0080PA00X+016939Y+110699X0160Y         S0      
317GND              VIA   -    MD0080PA00X+017500Y+110138X0160Y         S0      
317GND              VIA   -    MD0080PA00X+017874Y+109764X0160Y         S0      
317GND              VIA   -    MD0080PA00X+018248Y+109016X0160Y         S0      
317GND              VIA   -    MD0080PA00X+018248Y+108268X0160Y    R270 S0      
317GND              VIA   -    MD0080PA00X+018248Y+108642X0160Y    R270 S0      
317GND              VIA   -    MD0080PA00X+017126Y+109016X0160Y         S0      
317GND              VIA   -    MD0080PA00X+017874Y+109390X0160Y         S0      
317GND              VIA   -    MD0080PA00X+017500Y+109016X0160Y         S0      
317GND              VIA   -    MD0080PA00X+017126Y+107894X0160Y    R270 S0      
317GND              VIA   -    MD0080PA00X+017500Y+108268X0160Y    R270 S0      
317GND              VIA   -    MD0080PA00X+017500Y+108642X0160Y    R270 S0      
317GND              VIA   -    MD0080PA00X+017874Y+107894X0160Y    R270 S0      
317GND              VIA   -    MD0080PA00X+017874Y+109016X0160Y         S0      
317GND              VIA   -    MD0080PA00X+017500Y+119488X0160Y         S0      
317GND              VIA   -    MD0080PA00X+017500Y+120236X0160Y         S0      
317GND              VIA   -    MD0080PA00X+017126Y+119488X0160Y         S0      
317GND              VIA   -    MD0080PA00X+016752Y+119862X0160Y    R090 S0      
317GND              VIA   -    MD0080PA00X+017126Y+120236X0160Y         S0      
317GND              VIA   -    MD0080PA00X+018061Y+117805X0160Y         S0      
317GND              VIA   -    MD0080PA00X+017500Y+118740X0160Y         S0      
317GND              VIA   -    MD0080PA00X+017126Y+118740X0160Y         S0      
317GND              VIA   -    MD0080PA00X+017313Y+118179X0160Y         S0      
317GND              VIA   -    MD0080PA00X+017313Y+117805X0160Y         S0      
317GND              VIA   -    MD0080PA00X+017313Y+117431X0160Y         S0      
317GND              VIA   -    MD0080PA00X+018061Y+118179X0160Y         S0      
317GND              VIA   -    MD0080PA00X+018061Y+117431X0160Y         S0      
317GND              VIA   -    MD0080PA00X+018061Y+117057X0160Y    R270 S0      
317GND              VIA   -    MD0080PA00X+018061Y+115935X0160Y         S0      
317GND              VIA   -    MD0080PA00X+018061Y+116683X0160Y         S0      
317GND              VIA   -    MD0080PA00X+017313Y+117057X0160Y         S0      
317GND              VIA   -    MD0080PA00X+017313Y+116683X0160Y         S0      
317GND              VIA   -    MD0080PA00X+017313Y+115935X0160Y         S0      
317GND              VIA   -    MD0080PA00X+017687Y+117057X0160Y         S0      
317GND              VIA   -    MD0080PA00X+018061Y+114439X0160Y         S0      
317GND              VIA   -    MD0080PA00X+018061Y+115187X0160Y         S0      
317GND              VIA   -    MD0080PA00X+018061Y+115561X0160Y         S0      
317GND              VIA   -    MD0080PA00X+017313Y+115187X0160Y         S0      
317GND              VIA   -    MD0080PA00X+017313Y+115561X0160Y         S0      
317GND              VIA   -    MD0080PA00X+017313Y+114813X0160Y         S0      
317GND              VIA   -    MD0080PA00X+016939Y+114439X0160Y         S0      
317GND              VIA   -    MD0080PA00X+017313Y+114439X0160Y         S0      
317GND              VIA   -    MD0080PA00X+018061Y+114813X0160Y         S0      
317GND              VIA   -    MD0080PA00X+018061Y+113691X0160Y         S0      
317GND              VIA   -    MD0080PA00X+018248Y+122480X0160Y         S0      
317GND              VIA   -    MD0080PA00X+018248Y+122854X0160Y    R090 S0      
317GND              VIA   -    MD0080PA00X+017126Y+123976X0160Y         S0      
317GND              VIA   -    MD0080PA00X+017126Y+123602X0160Y         S0      
317GND              VIA   -    MD0080PA00X+017500Y+122480X0160Y         S0      
317GND              VIA   -    MD0080PA00X+017126Y+123228X0160Y         S0      
317GND              VIA   -    MD0080PA00X+017500Y+122854X0160Y    R090 S0      
317GND              VIA   -    MD0080PA00X+017500Y+123976X0160Y         S0      
317GND              VIA   -    MD0080PA00X+017874Y+123602X0160Y         S0      
317GND              VIA   -    MD0080PA00X+017874Y+123228X0160Y         S0      
317GND              VIA   -    MD0080PA00X+016752Y+121358X0160Y    R090 S0      
317GND              VIA   -    MD0080PA00X+017500Y+120984X0160Y    R270 S0      
317GND              VIA   -    MD0080PA00X+017126Y+121732X0160Y         S0      
317GND              VIA   -    MD0080PA00X+017500Y+122106X0160Y         S0      
317GND              VIA   -    MD0080PA00X+017126Y+122106X0160Y         S0      
317GND              VIA   -    MD0080PA00X+017500Y+121732X0160Y         S0      
317GND              VIA   -    MD0080PA00X+017126Y+120984X0160Y         S0      
317GND              VIA   -    MD0080PA00X+017126Y+125472X0160Y    R270 S0      
317GND              VIA   -    MD0080PA00X+017874Y+125472X0160Y    R270 S0      
317GND              VIA   -    MD0080PA00X+018248Y+125846X0160Y         S0      
317GND              VIA   -    MD0080PA00X+017500Y+125846X0160Y         S0      
317GND              VIA   -    MD0080PA00X+017500Y+124724X0160Y         S0      
317GND              VIA   -    MD0080PA00X+017500Y+124350X0160Y    R270 S0      
317GND              VIA   -    MD0080PA00X+017874Y+123976X0160Y    R270 S0      
317GND              VIA   -    MD0080PA00X+017874Y+125098X0160Y    R270 S0      
317GND              VIA   -    MD0080PA00X+017126Y+125098X0160Y         S0      
317GND              VIA   -    MD0080PA00X+018248Y+124724X0160Y    R270 S0      
317GND              VIA   -    MD0080PA00X+018248Y+124350X0160Y         S0      
317GND              VIA   -    MD0080PA00X+018248Y+123976X0160Y    R270 S0      
317GND              VIA   -    MD0080PA00X+019370Y+107520X0160Y    R270 S0      
317GND              VIA   -    MD0080PA00X+018622Y+107520X0160Y    R270 S0      
317GND              VIA   -    MD0080PA00X+018996Y+107146X0160Y         S0      
317GND              VIA   -    MD0080PA00X+019744Y+107146X0160Y         S0      
317GND              VIA   -    MD0080PA00X+019557Y+111821X0160Y         S0      
317GND              VIA   -    MD0080PA00X+018435Y+112195X0160Y         S0      
317GND              VIA   -    MD0080PA00X+018809Y+112195X0160Y         S0      
317GND              VIA   -    MD0080PA00X+019183Y+112195X0160Y         S0      
317GND              VIA   -    MD0080PA00X+018435Y+111821X0160Y         S0      
317GND              VIA   -    MD0080PA00X+018809Y+111821X0160Y         S0      
317GND              VIA   -    MD0080PA00X+019183Y+111821X0160Y         S0      
317GND              VIA   -    MD0080PA00X+019744Y+110512X0160Y         S0      
317GND              VIA   -    MD0080PA00X+019744Y+110138X0160Y         S0      
317GND              VIA   -    MD0080PA00X+019370Y+109764X0160Y         S0      
317GND              VIA   -    MD0080PA00X+018622Y+109390X0160Y         S0      
317GND              VIA   -    MD0080PA00X+018996Y+110512X0160Y         S0      
317GND              VIA   -    MD0080PA00X+018622Y+109764X0160Y         S0      
317GND              VIA   -    MD0080PA00X+018996Y+110138X0160Y         S0      
317GND              VIA   -    MD0080PA00X+019744Y+109016X0160Y         S0      
317GND              VIA   -    MD0080PA00X+019744Y+108268X0160Y    R270 S0      
317GND              VIA   -    MD0080PA00X+019744Y+108642X0160Y    R270 S0      
317GND              VIA   -    MD0080PA00X+019370Y+109390X0160Y         S0      
317GND              VIA   -    MD0080PA00X+018622Y+109016X0160Y         S0      
317GND              VIA   -    MD0080PA00X+018996Y+109016X0160Y         S0      
317GND              VIA   -    MD0080PA00X+018622Y+107894X0160Y    R270 S0      
317GND              VIA   -    MD0080PA00X+019370Y+107894X0160Y    R270 S0      
317GND              VIA   -    MD0080PA00X+018996Y+108268X0160Y    R270 S0      
317GND              VIA   -    MD0080PA00X+018996Y+108642X0160Y    R270 S0      
317GND              VIA   -    MD0080PA00X+019370Y+109016X0160Y         S0      
317GND              VIA   -    MD0080PA00X+019183Y+121919X0160Y         S0      
317GND              VIA   -    MD0080PA00X+019557Y+120423X0160Y         S0      
317GND              VIA   -    MD0080PA00X+019557Y+119301X0160Y         S0      
317GND              VIA   -    MD0080PA00X+019557Y+119675X0160Y         S0      
317GND              VIA   -    MD0080PA00X+019557Y+120049X0160Y         S0      
317GND              VIA   -    MD0080PA00X+018435Y+119675X0160Y         S0      
317GND              VIA   -    MD0080PA00X+018435Y+119301X0160Y         S0      
317GND              VIA   -    MD0080PA00X+019183Y+120049X0160Y         S0      
317GND              VIA   -    MD0080PA00X+019183Y+119675X0160Y         S0      
317GND              VIA   -    MD0080PA00X+019183Y+120423X0160Y         S0      
317GND              VIA   -    MD0080PA00X+018809Y+120423X0160Y         S0      
317GND              VIA   -    MD0080PA00X+018809Y+120049X0160Y         S0      
317GND              VIA   -    MD0080PA00X+018809Y+119675X0160Y         S0      
317GND              VIA   -    MD0080PA00X+018809Y+119301X0160Y    R270 S0      
317GND              VIA   -    MD0080PA00X+019557Y+117805X0160Y         S0      
317GND              VIA   -    MD0080PA00X+019557Y+118553X0160Y         S0      
317GND              VIA   -    MD0080PA00X+019183Y+117431X0160Y         S0      
317GND              VIA   -    MD0080PA00X+019183Y+118179X0160Y         S0      
317GND              VIA   -    MD0080PA00X+019557Y+118927X0160Y         S0      
317GND              VIA   -    MD0080PA00X+018809Y+117805X0160Y    R270 S0      
317GND              VIA   -    MD0080PA00X+018809Y+118553X0160Y         S0      
317GND              VIA   -    MD0080PA00X+019557Y+117057X0160Y         S0      
317GND              VIA   -    MD0080PA00X+019557Y+115935X0160Y         S0      
317GND              VIA   -    MD0080PA00X+019183Y+116683X0160Y         S0      
317GND              VIA   -    MD0080PA00X+018809Y+117057X0160Y         S0      
317GND              VIA   -    MD0080PA00X+018809Y+115935X0160Y         S0      
317GND              VIA   -    MD0080PA00X+019557Y+114439X0160Y         S0      
317GND              VIA   -    MD0080PA00X+019557Y+115187X0160Y         S0      
317GND              VIA   -    MD0080PA00X+019183Y+114813X0160Y         S0      
317GND              VIA   -    MD0080PA00X+019183Y+115561X0160Y         S0      
317GND              VIA   -    MD0080PA00X+018809Y+115187X0160Y         S0      
317GND              VIA   -    MD0080PA00X+018809Y+114439X0160Y         S0      
317GND              VIA   -    MD0080PA00X+019557Y+113691X0160Y         S0      
317GND              VIA   -    MD0080PA00X+019557Y+112569X0160Y         S0      
317GND              VIA   -    MD0080PA00X+019557Y+112943X0160Y         S0      
317GND              VIA   -    MD0080PA00X+019557Y+113317X0160Y         S0      
317GND              VIA   -    MD0080PA00X+018435Y+114065X0160Y         S0      
317GND              VIA   -    MD0080PA00X+018809Y+114065X0160Y         S0      
317GND              VIA   -    MD0080PA00X+018809Y+113691X0160Y         S0      
317GND              VIA   -    MD0080PA00X+018435Y+113317X0160Y         S0      
317GND              VIA   -    MD0080PA00X+018809Y+113317X0160Y         S0      
317GND              VIA   -    MD0080PA00X+018435Y+112943X0160Y         S0      
317GND              VIA   -    MD0080PA00X+018809Y+112943X0160Y         S0      
317GND              VIA   -    MD0080PA00X+018435Y+112569X0160Y         S0      
317GND              VIA   -    MD0080PA00X+018809Y+112569X0160Y         S0      
317GND              VIA   -    MD0080PA00X+019183Y+112569X0160Y         S0      
317GND              VIA   -    MD0080PA00X+019557Y+112195X0160Y         S0      
317GND              VIA   -    MD0080PA00X+018996Y+124350X0160Y         S0      
317GND              VIA   -    MD0080PA00X+019370Y+125098X0160Y    R270 S0      
317GND              VIA   -    MD0080PA00X+018996Y+124724X0160Y    R270 S0      
317GND              VIA   -    MD0080PA00X+018622Y+125098X0160Y    R270 S0      
317GND              VIA   -    MD0080PA00X+018996Y+123976X0160Y    R270 S0      
317GND              VIA   -    MD0080PA00X+019744Y+122854X0160Y    R090 S0      
317GND              VIA   -    MD0080PA00X+018622Y+123976X0160Y         S0      
317GND              VIA   -    MD0080PA00X+019370Y+123976X0160Y         S0      
317GND              VIA   -    MD0080PA00X+018622Y+123602X0160Y         S0      
317GND              VIA   -    MD0080PA00X+019370Y+123602X0160Y         S0      
317GND              VIA   -    MD0080PA00X+018996Y+122480X0160Y         S0      
317GND              VIA   -    MD0080PA00X+018622Y+123228X0160Y         S0      
317GND              VIA   -    MD0080PA00X+018996Y+122854X0160Y    R090 S0      
317GND              VIA   -    MD0080PA00X+019370Y+123228X0160Y         S0      
317GND              VIA   -    MD0080PA00X+019744Y+122480X0160Y         S0      
317GND              VIA   -    MD0080PA00X+019370Y+121358X0160Y         S0      
317GND              VIA   -    MD0080PA00X+019557Y+120797X0160Y         S0      
317GND              VIA   -    MD0080PA00X+018996Y+120984X0160Y         S0      
317GND              VIA   -    MD0080PA00X+019183Y+120797X0160Y         S0      
317GND              VIA   -    MD0080PA00X+019370Y+120984X0160Y         S0      
317GND              VIA   -    MD0080PA00X+018622Y+125472X0160Y    R270 S0      
317GND              VIA   -    MD0080PA00X+019370Y+125472X0160Y    R270 S0      
317GND              VIA   -    MD0080PA00X+019744Y+125846X0160Y         S0      
317GND              VIA   -    MD0080PA00X+018996Y+125846X0160Y         S0      
317GND              VIA   -    MD0080PA00X+019744Y+124350X0160Y         S0      
317GND              VIA   -    MD0080PA00X+019744Y+124724X0160Y    R270 S0      
317GND              VIA   -    MD0080PA00X+020118Y+107894X0160Y    R270 S0      
317GND              VIA   -    MD0080PA00X+020492Y+108268X0160Y    R270 S0      
317GND              VIA   -    MD0080PA00X+020492Y+108642X0160Y    R270 S0      
317GND              VIA   -    MD0080PA00X+020118Y+109016X0160Y         S0      
317GND              VIA   -    MD0080PA00X+020866Y+109016X0160Y         S0      
317GND              VIA   -    MD0080PA00X+021614Y+109390X0160Y         S0      
317GND              VIA   -    MD0080PA00X+021240Y+109016X0160Y         S0      
317GND              VIA   -    MD0080PA00X+021614Y+107894X0160Y    R270 S0      
317GND              VIA   -    MD0080PA00X+021240Y+108268X0160Y    R270 S0      
317GND              VIA   -    MD0080PA00X+021240Y+108642X0160Y    R270 S0      
317GND              VIA   -    MD0080PA00X+021614Y+109016X0160Y         S0      
317GND              VIA   -    MD0080PA00X+020866Y+109390X0160Y         S0      
317GND              VIA   -    MD0080PA00X+020118Y+109390X0160Y         S0      
317GND              VIA   -    MD0080PA00X+020492Y+109016X0160Y         S0      
317GND              VIA   -    MD0080PA00X+020866Y+107894X0160Y    R270 S0      
317GND              VIA   -    MD0080PA00X+021240Y+107146X0160Y         S0      
317GND              VIA   -    MD0080PA00X+020492Y+107146X0160Y         S0      
317GND              VIA   -    MD0080PA00X+021614Y+107520X0160Y    R270 S0      
317GND              VIA   -    MD0080PA00X+020866Y+107520X0160Y    R270 S0      
317GND              VIA   -    MD0080PA00X+020118Y+107520X0160Y    R270 S0      
317GND              VIA   -    MD0080PA00X+021427Y+113317X0160Y         S0      
317GND              VIA   -    MD0080PA00X+021053Y+112569X0160Y         S0      
317GND              VIA   -    MD0080PA00X+021427Y+112569X0160Y         S0      
317GND              VIA   -    MD0080PA00X+021427Y+114065X0160Y         S0      
317GND              VIA   -    MD0080PA00X+021053Y+114065X0160Y         S0      
317GND              VIA   -    MD0080PA00X+021053Y+113317X0160Y         S0      
317GND              VIA   -    MD0080PA00X+019931Y+113317X0160Y         S0      
317GND              VIA   -    MD0080PA00X+020305Y+113317X0160Y         S0      
317GND              VIA   -    MD0080PA00X+020679Y+113317X0160Y         S0      
317GND              VIA   -    MD0080PA00X+020679Y+112569X0160Y         S0      
317GND              VIA   -    MD0080PA00X+020305Y+112569X0160Y         S0      
317GND              VIA   -    MD0080PA00X+019931Y+112569X0160Y         S0      
317GND              VIA   -    MD0080PA00X+020679Y+114065X0160Y         S0      
317GND              VIA   -    MD0080PA00X+020305Y+114065X0160Y         S0      
317GND              VIA   -    MD0080PA00X+019931Y+114065X0160Y         S0      
317GND              VIA   -    MD0080PA00X+021427Y+112195X0160Y         S0      
317GND              VIA   -    MD0080PA00X+021427Y+111821X0160Y         S0      
317GND              VIA   -    MD0080PA00X+021053Y+112195X0160Y         S0      
317GND              VIA   -    MD0080PA00X+021427Y+111447X0160Y    R180 S0      
317GND              VIA   -    MD0080PA00X+021427Y+111073X0160Y         S0      
317GND              VIA   -    MD0080PA00X+021053Y+111821X0160Y         S0      
317GND              VIA   -    MD0080PA00X+020679Y+112195X0160Y         S0      
317GND              VIA   -    MD0080PA00X+020305Y+112195X0160Y         S0      
317GND              VIA   -    MD0080PA00X+020305Y+111821X0160Y         S0      
317GND              VIA   -    MD0080PA00X+020679Y+111821X0160Y         S0      
317GND              VIA   -    MD0080PA00X+019931Y+112195X0160Y         S0      
317GND              VIA   -    MD0080PA00X+019931Y+111821X0160Y         S0      
317GND              VIA   -    MD0080PA00X+021614Y+109764X0160Y         S0      
317GND              VIA   -    MD0080PA00X+021240Y+110512X0160Y         S0      
317GND              VIA   -    MD0080PA00X+021240Y+110138X0160Y         S0      
317GND              VIA   -    MD0080PA00X+020492Y+110512X0160Y         S0      
317GND              VIA   -    MD0080PA00X+020118Y+109764X0160Y         S0      
317GND              VIA   -    MD0080PA00X+020866Y+109764X0160Y         S0      
317GND              VIA   -    MD0080PA00X+020492Y+110138X0160Y         S0      
317GND              VIA   -    MD0080PA00X+021427Y+120797X0160Y         S0      
317GND              VIA   -    MD0080PA00X+021053Y+121171X0160Y    R090 S0      
317GND              VIA   -    MD0080PA00X+021053Y+120797X0160Y         S0      
317GND              VIA   -    MD0080PA00X+019931Y+120797X0160Y         S0      
317GND              VIA   -    MD0080PA00X+020305Y+120797X0160Y         S0      
317GND              VIA   -    MD0080PA00X+020679Y+120797X0160Y         S0      
317GND              VIA   -    MD0080PA00X+021427Y+120423X0160Y         S0      
317GND              VIA   -    MD0080PA00X+021053Y+120423X0160Y         S0      
317GND              VIA   -    MD0080PA00X+021053Y+119675X0160Y         S0      
317GND              VIA   -    MD0080PA00X+021427Y+119675X0160Y         S0      
317GND              VIA   -    MD0080PA00X+020679Y+120423X0160Y         S0      
317GND              VIA   -    MD0080PA00X+020305Y+120423X0160Y         S0      
317GND              VIA   -    MD0080PA00X+019931Y+120423X0160Y         S0      
317GND              VIA   -    MD0080PA00X+019931Y+119675X0160Y         S0      
317GND              VIA   -    MD0080PA00X+020305Y+119675X0160Y         S0      
317GND              VIA   -    MD0080PA00X+020679Y+119675X0160Y         S0      
317GND              VIA   -    MD0080PA00X+021427Y+117431X0160Y         S0      
317GND              VIA   -    MD0080PA00X+020679Y+117431X0160Y         S0      
317GND              VIA   -    MD0080PA00X+019931Y+117431X0160Y         S0      
317GND              VIA   -    MD0080PA00X+021053Y+118927X0160Y         S0      
317GND              VIA   -    MD0080PA00X+021427Y+118927X0160Y         S0      
317GND              VIA   -    MD0080PA00X+021053Y+118179X0160Y         S0      
317GND              VIA   -    MD0080PA00X+021427Y+118179X0160Y         S0      
317GND              VIA   -    MD0080PA00X+019931Y+118927X0160Y         S0      
317GND              VIA   -    MD0080PA00X+020305Y+118927X0160Y         S0      
317GND              VIA   -    MD0080PA00X+020679Y+118927X0160Y         S0      
317GND              VIA   -    MD0080PA00X+019931Y+118179X0160Y         S0      
317GND              VIA   -    MD0080PA00X+020305Y+118179X0160Y         S0      
317GND              VIA   -    MD0080PA00X+020679Y+118179X0160Y         S0      
317GND              VIA   -    MD0080PA00X+021053Y+117057X0160Y         S0      
317GND              VIA   -    MD0080PA00X+021053Y+115935X0160Y         S0      
317GND              VIA   -    MD0080PA00X+021427Y+116683X0160Y         S0      
317GND              VIA   -    MD0080PA00X+020305Y+117057X0160Y         S0      
317GND              VIA   -    MD0080PA00X+019931Y+116683X0160Y         S0      
317GND              VIA   -    MD0080PA00X+020305Y+115935X0160Y         S0      
317GND              VIA   -    MD0080PA00X+020679Y+116683X0160Y         S0      
317GND              VIA   -    MD0080PA00X+021427Y+115561X0160Y         S0      
317GND              VIA   -    MD0080PA00X+020679Y+115561X0160Y         S0      
317GND              VIA   -    MD0080PA00X+019931Y+115561X0160Y         S0      
317GND              VIA   -    MD0080PA00X+021053Y+114813X0160Y         S0      
317GND              VIA   -    MD0080PA00X+021427Y+114813X0160Y         S0      
317GND              VIA   -    MD0080PA00X+020679Y+114813X0160Y         S0      
317GND              VIA   -    MD0080PA00X+019931Y+114813X0160Y         S0      
317GND              VIA   -    MD0080PA00X+020305Y+114813X0160Y         S0      
317GND              VIA   -    MD0080PA00X+020492Y+124724X0160Y    R270 S0      
317GND              VIA   -    MD0080PA00X+020118Y+125098X0160Y    R270 S0      
317GND              VIA   -    MD0080PA00X+020492Y+124350X0160Y         S0      
317GND              VIA   -    MD0080PA00X+020492Y+123976X0160Y    R270 S0      
317GND              VIA   -    MD0080PA00X+019744Y+123976X0160Y         S0      
317GND              VIA   -    MD0080PA00X+020866Y+123602X0160Y         S0      
317GND              VIA   -    MD0080PA00X+020118Y+123602X0160Y         S0      
317GND              VIA   -    MD0080PA00X+020492Y+122480X0160Y         S0      
317GND              VIA   -    MD0080PA00X+020118Y+123228X0160Y         S0      
317GND              VIA   -    MD0080PA00X+020492Y+122854X0160Y    R090 S0      
317GND              VIA   -    MD0080PA00X+020866Y+123228X0160Y         S0      
317GND              VIA   -    MD0080PA00X+021614Y+123976X0160Y         S0      
317GND              VIA   -    MD0080PA00X+021614Y+123602X0160Y         S0      
317GND              VIA   -    MD0080PA00X+021240Y+122480X0160Y         S0      
317GND              VIA   -    MD0080PA00X+021614Y+123228X0160Y         S0      
317GND              VIA   -    MD0080PA00X+021240Y+122854X0160Y    R090 S0      
317GND              VIA   -    MD0080PA00X+020866Y+123976X0160Y         S0      
317GND              VIA   -    MD0080PA00X+021614Y+125472X0160Y    R270 S0      
317GND              VIA   -    MD0080PA00X+020118Y+125472X0160Y    R270 S0      
317GND              VIA   -    MD0080PA00X+020492Y+125846X0160Y         S0      
317GND              VIA   -    MD0080PA00X+021240Y+125846X0160Y         S0      
317GND              VIA   -    MD0080PA00X+021240Y+124350X0160Y         S0      
317GND              VIA   -    MD0080PA00X+021614Y+125098X0160Y    R270 S0      
317GND              VIA   -    MD0080PA00X+021240Y+124724X0160Y    R270 S0      
317GND              VIA   -    MD0080PA00X+021240Y+123976X0160Y    R270 S0      
317GND              VIA   -    MD0080PA00X+020118Y+123976X0160Y    R270 S0      
317GND              VIA   -    MD0080PA00X+023110Y+107520X0160Y    R270 S0      
317GND              VIA   -    MD0080PA00X+022362Y+107520X0160Y    R270 S0      
317GND              VIA   -    MD0080PA00X+022736Y+107146X0160Y         S0      
317GND              VIA   -    MD0080PA00X+021988Y+107146X0160Y         S0      
317GND              VIA   -    MD0080PA00X+022923Y+111447X0160Y         S0      
317GND              VIA   -    MD0080PA00X+022923Y+111821X0160Y         S0      
317GND              VIA   -    MD0080PA00X+022923Y+112195X0160Y         S0      
317GND              VIA   -    MD0080PA00X+022175Y+112195X0160Y         S0      
317GND              VIA   -    MD0080PA00X+021801Y+112195X0160Y         S0      
317GND              VIA   -    MD0080PA00X+022175Y+111821X0160Y         S0      
317GND              VIA   -    MD0080PA00X+021801Y+111821X0160Y         S0      
317GND              VIA   -    MD0080PA00X+022549Y+112195X0160Y         S0      
317GND              VIA   -    MD0080PA00X+022549Y+111821X0160Y         S0      
317GND              VIA   -    MD0080PA00X+022362Y+109764X0160Y         S0      
317GND              VIA   -    MD0080PA00X+021988Y+110512X0160Y         S0      
317GND              VIA   -    MD0080PA00X+021988Y+110138X0160Y         S0      
317GND              VIA   -    MD0080PA00X+022736Y+110512X0160Y         S0      
317GND              VIA   -    MD0080PA00X+022736Y+110138X0160Y         S0      
317GND              VIA   -    MD0080PA00X+023110Y+109764X0160Y         S0      
317GND              VIA   -    MD0080PA00X+023110Y+109390X0160Y         S0      
317GND              VIA   -    MD0080PA00X+023110Y+107894X0160Y    R270 S0      
317GND              VIA   -    MD0080PA00X+023110Y+109016X0160Y         S0      
317GND              VIA   -    MD0080PA00X+022362Y+109390X0160Y         S0      
317GND              VIA   -    MD0080PA00X+022362Y+107894X0160Y    R270 S0      
317GND              VIA   -    MD0080PA00X+021988Y+109016X0160Y         S0      
317GND              VIA   -    MD0080PA00X+021988Y+108268X0160Y    R270 S0      
317GND              VIA   -    MD0080PA00X+021988Y+108642X0160Y    R270 S0      
317GND              VIA   -    MD0080PA00X+022362Y+109016X0160Y         S0      
317GND              VIA   -    MD0080PA00X+022736Y+109016X0160Y         S0      
317GND              VIA   -    MD0080PA00X+022736Y+108268X0160Y    R270 S0      
317GND              VIA   -    MD0080PA00X+022736Y+108642X0160Y    R270 S0      
317GND              VIA   -    MD0080PA00X+022923Y+120797X0160Y         S0      
317GND              VIA   -    MD0080PA00X+021801Y+120797X0160Y         S0      
317GND              VIA   -    MD0080PA00X+022175Y+120797X0160Y         S0      
317GND              VIA   -    MD0080PA00X+021801Y+121171X0160Y    R090 S0      
317GND              VIA   -    MD0080PA00X+022549Y+120797X0160Y         S0      
317GND              VIA   -    MD0080PA00X+021801Y+119675X0160Y         S0      
317GND              VIA   -    MD0080PA00X+022175Y+119675X0160Y         S0      
317GND              VIA   -    MD0080PA00X+022175Y+120423X0160Y         S0      
317GND              VIA   -    MD0080PA00X+022549Y+120423X0160Y         S0      
317GND              VIA   -    MD0080PA00X+022549Y+119675X0160Y         S0      
317GND              VIA   -    MD0080PA00X+022923Y+120423X0160Y         S0      
317GND              VIA   -    MD0080PA00X+022923Y+119675X0160Y         S0      
317GND              VIA   -    MD0080PA00X+021801Y+120423X0160Y         S0      
317GND              VIA   -    MD0080PA00X+022923Y+117431X0160Y         S0      
317GND              VIA   -    MD0080PA00X+022175Y+117431X0160Y         S0      
317GND              VIA   -    MD0080PA00X+022923Y+118927X0160Y         S0      
317GND              VIA   -    MD0080PA00X+022923Y+118179X0160Y         S0      
317GND              VIA   -    MD0080PA00X+021801Y+118927X0160Y         S0      
317GND              VIA   -    MD0080PA00X+022175Y+118927X0160Y         S0      
317GND              VIA   -    MD0080PA00X+021801Y+118179X0160Y         S0      
317GND              VIA   -    MD0080PA00X+022175Y+118179X0160Y         S0      
317GND              VIA   -    MD0080PA00X+022549Y+118927X0160Y         S0      
317GND              VIA   -    MD0080PA00X+022549Y+118179X0160Y         S0      
317GND              VIA   -    MD0080PA00X+022923Y+116683X0160Y         S0      
317GND              VIA   -    MD0080PA00X+021801Y+115935X0160Y         S0      
317GND              VIA   -    MD0080PA00X+022175Y+116683X0160Y         S0      
317GND              VIA   -    MD0080PA00X+021801Y+117057X0160Y         S0      
317GND              VIA   -    MD0080PA00X+022549Y+115935X0160Y         S0      
317GND              VIA   -    MD0080PA00X+022549Y+117057X0160Y         S0      
317GND              VIA   -    MD0080PA00X+022923Y+115561X0160Y         S0      
317GND              VIA   -    MD0080PA00X+022175Y+115561X0160Y         S0      
317GND              VIA   -    MD0080PA00X+022923Y+114813X0160Y         S0      
317GND              VIA   -    MD0080PA00X+021801Y+114813X0160Y         S0      
317GND              VIA   -    MD0080PA00X+022175Y+114813X0160Y         S0      
317GND              VIA   -    MD0080PA00X+022549Y+114813X0160Y         S0      
317GND              VIA   -    MD0080PA00X+022923Y+112569X0160Y         S0      
317GND              VIA   -    MD0080PA00X+022923Y+114065X0160Y         S0      
317GND              VIA   -    MD0080PA00X+022933Y+113268X0160Y         S0      
317GND              VIA   -    MD0080PA00X+021801Y+113317X0160Y         S0      
317GND              VIA   -    MD0080PA00X+022175Y+113317X0160Y         S0      
317GND              VIA   -    MD0080PA00X+022175Y+112569X0160Y         S0      
317GND              VIA   -    MD0080PA00X+021801Y+112569X0160Y         S0      
317GND              VIA   -    MD0080PA00X+022175Y+114065X0160Y         S0      
317GND              VIA   -    MD0080PA00X+021801Y+114065X0160Y         S0      
317GND              VIA   -    MD0080PA00X+022549Y+112569X0160Y         S0      
317GND              VIA   -    MD0080PA00X+022549Y+114065X0160Y         S0      
317GND              VIA   -    MD0080PA00X+022549Y+113317X0160Y         S0      
317GND              VIA   -    MD0080PA00X+022736Y+125846X0160Y         S0      
317GND              VIA   -    MD0080PA00X+021988Y+125846X0160Y         S0      
317GND              VIA   -    MD0080PA00X+022736Y+123976X0160Y    R270 S0      
317GND              VIA   -    MD0080PA00X+023110Y+125098X0160Y    R270 S0      
317GND              VIA   -    MD0080PA00X+021988Y+124350X0160Y         S0      
317GND              VIA   -    MD0080PA00X+021988Y+124724X0160Y    R270 S0      
317GND              VIA   -    MD0080PA00X+022362Y+125098X0160Y    R270 S0      
317GND              VIA   -    MD0080PA00X+021988Y+123976X0160Y    R270 S0      
317GND              VIA   -    MD0080PA00X+022736Y+124724X0160Y    R270 S0      
317GND              VIA   -    MD0080PA00X+022736Y+124350X0160Y         S0      
317GND              VIA   -    MD0080PA00X+023110Y+123976X0160Y         S0      
317GND              VIA   -    MD0080PA00X+023110Y+123602X0160Y         S0      
317GND              VIA   -    MD0080PA00X+023110Y+123228X0160Y         S0      
317GND              VIA   -    MD0080PA00X+022362Y+123976X0160Y         S0      
317GND              VIA   -    MD0080PA00X+022362Y+123602X0160Y         S0      
317GND              VIA   -    MD0080PA00X+021988Y+122480X0160Y         S0      
317GND              VIA   -    MD0080PA00X+021988Y+122854X0160Y    R090 S0      
317GND              VIA   -    MD0080PA00X+022362Y+123228X0160Y         S0      
317GND              VIA   -    MD0080PA00X+022736Y+122480X0160Y         S0      
317GND              VIA   -    MD0080PA00X+022736Y+122854X0160Y    R090 S0      
317GND              VIA   -    MD0080PA00X+023110Y+125472X0160Y    R270 S0      
317GND              VIA   -    MD0080PA00X+022362Y+125472X0160Y    R270 S0      
317GND              VIA   -    MD0080PA00X+024232Y+109016X0160Y         S0      
317GND              VIA   -    MD0080PA00X+023484Y+108642X0160Y         S0      
317GND              VIA   -    MD0080PA00X+023484Y+108268X0160Y         S0      
317GND              VIA   -    MD0080PA00X+024232Y+108642X0160Y         S0      
317GND              VIA   -    MD0080PA00X+024232Y+108268X0160Y    R180 S0      
317GND              VIA   -    MD0080PA00X+023858Y+109016X0160Y         S0      
317GND              VIA   -    MD0080PA00X+023858Y+107894X0160Y    R180 S0      
317GND              VIA   -    MD0080PA00X+023858Y+107520X0160Y         S0      
317GND              VIA   -    MD0080PA00X+024232Y+107146X0160Y         S0      
317GND              VIA   -    MD0080PA00X+023484Y+107145X0160Y         S0      
317GND              VIA   -    MD0080PA00X+024419Y+119675X0160Y         S0      
317GND              VIA   -    MD0080PA00X+024419Y+120423X0160Y         S0      
317GND              VIA   -    MD0080PA00X+024045Y+119675X0160Y         S0      
317GND              VIA   -    MD0080PA00X+023671Y+119675X0160Y         S0      
317GND              VIA   -    MD0080PA00X+023671Y+120423X0160Y         S0      
317GND              VIA   -    MD0080PA00X+024045Y+120423X0160Y         S0      
317GND              VIA   -    MD0080PA00X+024045Y+117431X0160Y         S0      
317GND              VIA   -    MD0080PA00X+024419Y+118927X0160Y         S0      
317GND              VIA   -    MD0080PA00X+024419Y+118179X0160Y         S0      
317GND              VIA   -    MD0080PA00X+024045Y+118927X0160Y         S0      
317GND              VIA   -    MD0080PA00X+023671Y+118927X0160Y         S0      
317GND              VIA   -    MD0080PA00X+023671Y+118179X0160Y         S0      
317GND              VIA   -    MD0080PA00X+024045Y+118179X0160Y         S0      
317GND              VIA   -    MD0080PA00X+024419Y+115935X0160Y         S0      
317GND              VIA   -    MD0080PA00X+024419Y+117057X0160Y         S0      
317GND              VIA   -    MD0080PA00X+023671Y+115935X0160Y         S0      
317GND              VIA   -    MD0080PA00X+023671Y+117057X0160Y         S0      
317GND              VIA   -    MD0080PA00X+024045Y+116683X0160Y         S0      
317GND              VIA   -    MD0080PA00X+024045Y+115561X0160Y         S0      
317GND              VIA   -    MD0080PA00X+024419Y+114813X0160Y         S0      
317GND              VIA   -    MD0080PA00X+024045Y+114813X0160Y         S0      
317GND              VIA   -    MD0080PA00X+023671Y+114813X0160Y         S0      
317GND              VIA   -    MD0080PA00X+024419Y+112569X0160Y         S0      
317GND              VIA   -    MD0080PA00X+024419Y+114065X0160Y         S0      
317GND              VIA   -    MD0080PA00X+024419Y+113317X0160Y         S0      
317GND              VIA   -    MD0080PA00X+024045Y+112569X0160Y         S0      
317GND              VIA   -    MD0080PA00X+023671Y+112569X0160Y         S0      
317GND              VIA   -    MD0080PA00X+024045Y+114065X0160Y         S0      
317GND              VIA   -    MD0080PA00X+023671Y+114065X0160Y         S0      
317GND              VIA   -    MD0080PA00X+024045Y+113317X0160Y         S0      
317GND              VIA   -    MD0080PA00X+023671Y+113346X0160Y         S0      
317GND              VIA   -    MD0080PA00X+024419Y+112195X0160Y         S0      
317GND              VIA   -    MD0080PA00X+024045Y+112195X0160Y         S0      
317GND              VIA   -    MD0080PA00X+023671Y+112195X0160Y         S0      
317GND              VIA   -    MD0080PA00X+023484Y+110512X0160Y         S0      
317GND              VIA   -    MD0080PA00X+024232Y+110138X0160Y         S0      
317GND              VIA   -    MD0080PA00X+023858Y+109390X0160Y         S0      
317GND              VIA   -    MD0080PA00X+023858Y+109764X0160Y    R180 S0      
317GND              VIA   -    MD0080PA00X+023484Y+110138X0160Y         S0      
317GND              VIA   -    MD0080PA00X+024232Y+110512X0160Y         S0      
317GND              VIA   -    MD0080PA00X+024606Y+125098X0160Y    R180 S0      
317GND              VIA   -    MD0080PA00X+024232Y+124724X0160Y    R180 S0      
317GND              VIA   -    MD0080PA00X+024232Y+123976X0160Y    R270 S0      
317GND              VIA   -    MD0080PA00X+024232Y+124350X0160Y    R180 S0      
317GND              VIA   -    MD0080PA00X+023484Y+124724X0160Y    R180 S0      
317GND              VIA   -    MD0080PA00X+023484Y+124350X0160Y    R270 S0      
317GND              VIA   -    MD0080PA00X+023858Y+125098X0160Y    R180 S0      
317GND              VIA   -    MD0080PA00X+023484Y+123976X0160Y    R270 S0      
317GND              VIA   -    MD0080PA00X+024232Y+122480X0160Y         S0      
317GND              VIA   -    MD0080PA00X+024232Y+122854X0160Y         S0      
317GND              VIA   -    MD0080PA00X+023858Y+123976X0160Y         S0      
317GND              VIA   -    MD0080PA00X+023858Y+123602X0160Y         S0      
317GND              VIA   -    MD0080PA00X+023484Y+122480X0160Y         S0      
317GND              VIA   -    MD0080PA00X+023484Y+122854X0160Y         S0      
317GND              VIA   -    MD0080PA00X+023858Y+123228X0160Y         S0      
317GND              VIA   -    MD0080PA00X+023671Y+120797X0160Y         S0      
317GND              VIA   -    MD0080PA00X+024419Y+120797X0160Y         S0      
317GND              VIA   -    MD0080PA00X+024419Y+121171X0160Y         S0      
317GND              VIA   -    MD0080PA00X+024232Y+122106X0160Y         S0      
317GND              VIA   -    MD0080PA00X+024045Y+121171X0160Y         S0      
317GND              VIA   -    MD0080PA00X+024045Y+120797X0160Y         S0      
317GND              VIA   -    MD0080PA00X+072933Y+110138X0160Y    R270 S0      
317GND              VIA   -    MD0080PA00X+024232Y+125846X0160Y         S0      
317GND              VIA   -    MD0080PA00X+023484Y+125846X0160Y         S0      
317GND              VIA   -    MD0080PA00X+023858Y+125472X0160Y    R180 S0      
317GND              VIA   -    MD0080PA00X+024606Y+107520X0160Y         S0      
317GND              VIA   -    MD0080PA00X+025728Y+107146X0160Y         S0      
317GND              VIA   -    MD0080PA00X+024980Y+107146X0160Y         S0      
317GND              VIA   -    MD0080PA00X+026102Y+107520X0160Y         S0      
317GND              VIA   -    MD0080PA00X+025354Y+107520X0160Y         S0      
317GND              VIA   -    MD0080PA00X+026102Y+107894X0160Y         S0      
317GND              VIA   -    MD0080PA00X+026102Y+109016X0160Y         S0      
317GND              VIA   -    MD0080PA00X+025728Y+108642X0160Y         S0      
317GND              VIA   -    MD0080PA00X+025728Y+108268X0160Y    R180 S0      
317GND              VIA   -    MD0080PA00X+026476Y+109016X0160Y         S0      
317GND              VIA   -    MD0080PA00X+025728Y+109016X0160Y         S0      
317GND              VIA   -    MD0080PA00X+024606Y+109390X0160Y         S0      
317GND              VIA   -    MD0080PA00X+025354Y+107894X0160Y         S0      
317GND              VIA   -    MD0080PA00X+024980Y+108642X0160Y         S0      
317GND              VIA   -    MD0080PA00X+024980Y+109016X0160Y         S0      
317GND              VIA   -    MD0080PA00X+024606Y+107894X0160Y         S0      
317GND              VIA   -    MD0080PA00X+024980Y+108268X0160Y    R180 S0      
317GND              VIA   -    MD0080PA00X+024606Y+109016X0160Y         S0      
317GND              VIA   -    MD0080PA00X+025354Y+109016X0160Y         S0      
317GND              VIA   -    MD0080PA00X+025541Y+115561X0160Y         S0      
317GND              VIA   -    MD0080PA00X+024793Y+115561X0160Y         S0      
317GND              VIA   -    MD0080PA00X+025541Y+114813X0160Y         S0      
317GND              VIA   -    MD0080PA00X+025167Y+114813X0160Y         S0      
317GND              VIA   -    MD0080PA00X+024793Y+114813X0160Y         S0      
317GND              VIA   -    MD0080PA00X+026289Y+115561X0160Y         S0      
317GND              VIA   -    MD0080PA00X+026289Y+114813X0160Y         S0      
317GND              VIA   -    MD0080PA00X+025915Y+114813X0160Y         S0      
317GND              VIA   -    MD0080PA00X+025915Y+114065X0160Y         S0      
317GND              VIA   -    MD0080PA00X+026289Y+112569X0160Y         S0      
317GND              VIA   -    MD0080PA00X+025915Y+112569X0160Y         S0      
317GND              VIA   -    MD0080PA00X+026289Y+114065X0160Y         S0      
317GND              VIA   -    MD0080PA00X+026289Y+113317X0160Y         S0      
317GND              VIA   -    MD0080PA00X+025915Y+113317X0160Y         S0      
317GND              VIA   -    MD0080PA00X+025541Y+112569X0160Y         S0      
317GND              VIA   -    MD0080PA00X+025167Y+112569X0160Y         S0      
317GND              VIA   -    MD0080PA00X+024793Y+112569X0160Y         S0      
317GND              VIA   -    MD0080PA00X+025541Y+114065X0160Y         S0      
317GND              VIA   -    MD0080PA00X+025167Y+114065X0160Y         S0      
317GND              VIA   -    MD0080PA00X+024793Y+114065X0160Y         S0      
317GND              VIA   -    MD0080PA00X+025541Y+113317X0160Y         S0      
317GND              VIA   -    MD0080PA00X+025167Y+113317X0160Y         S0      
317GND              VIA   -    MD0080PA00X+024793Y+113317X0160Y         S0      
317GND              VIA   -    MD0080PA00X+025915Y+112195X0160Y         S0      
317GND              VIA   -    MD0080PA00X+026289Y+112195X0160Y         S0      
317GND              VIA   -    MD0080PA00X+024793Y+112195X0160Y         S0      
317GND              VIA   -    MD0080PA00X+025167Y+112195X0160Y         S0      
317GND              VIA   -    MD0080PA00X+025541Y+112195X0160Y         S0      
317GND              VIA   -    MD0080PA00X+026476Y+110512X0160Y         S0      
317GND              VIA   -    MD0080PA00X+026476Y+110138X0160Y    R270 S0      
317GND              VIA   -    MD0080PA00X+026102Y+109764X0160Y         S0      
317GND              VIA   -    MD0080PA00X+026102Y+109390X0160Y         S0      
317GND              VIA   -    MD0080PA00X+025728Y+110512X0160Y         S0      
317GND              VIA   -    MD0080PA00X+025354Y+109764X0160Y         S0      
317GND              VIA   -    MD0080PA00X+025728Y+110138X0160Y    R270 S0      
317GND              VIA   -    MD0080PA00X+025354Y+109390X0160Y         S0      
317GND              VIA   -    MD0080PA00X+024606Y+109764X0160Y         S0      
317GND              VIA   -    MD0080PA00X+024980Y+110138X0160Y    R180 S0      
317GND              VIA   -    MD0080PA00X+024980Y+110512X0160Y         S0      
317GND              VIA   -    MD0080PA00X+025728Y+122106X0160Y    R270 S0      
317GND              VIA   -    MD0080PA00X+026102Y+122106X0160Y    R270 S0      
317GND              VIA   -    MD0080PA00X+025915Y+121171X0160Y         S0      
317GND              VIA   -    MD0080PA00X+026289Y+121171X0160Y         S0      
317GND              VIA   -    MD0080PA00X+025915Y+120797X0160Y         S0      
317GND              VIA   -    MD0080PA00X+026289Y+120797X0160Y         S0      
317GND              VIA   -    MD0080PA00X+025354Y+122106X0160Y    R270 S0      
317GND              VIA   -    MD0080PA00X+024606Y+122106X0160Y    R270 S0      
317GND              VIA   -    MD0080PA00X+024980Y+122106X0160Y    R270 S0      
317GND              VIA   -    MD0080PA00X+025541Y+120797X0160Y         S0      
317GND              VIA   -    MD0080PA00X+025541Y+121171X0160Y         S0      
317GND              VIA   -    MD0080PA00X+025167Y+120797X0160Y         S0      
317GND              VIA   -    MD0080PA00X+024793Y+120797X0160Y         S0      
317GND              VIA   -    MD0080PA00X+026289Y+119675X0160Y         S0      
317GND              VIA   -    MD0080PA00X+025915Y+119675X0160Y         S0      
317GND              VIA   -    MD0080PA00X+026289Y+120423X0160Y         S0      
317GND              VIA   -    MD0080PA00X+025915Y+120423X0160Y         S0      
317GND              VIA   -    MD0080PA00X+025541Y+119675X0160Y         S0      
317GND              VIA   -    MD0080PA00X+025167Y+119675X0160Y         S0      
317GND              VIA   -    MD0080PA00X+024793Y+119675X0160Y         S0      
317GND              VIA   -    MD0080PA00X+025167Y+120423X0160Y         S0      
317GND              VIA   -    MD0080PA00X+025541Y+120423X0160Y         S0      
317GND              VIA   -    MD0080PA00X+024793Y+120423X0160Y         S0      
317GND              VIA   -    MD0080PA00X+024793Y+117431X0160Y         S0      
317GND              VIA   -    MD0080PA00X+025541Y+117431X0160Y         S0      
317GND              VIA   -    MD0080PA00X+025915Y+118927X0160Y         S0      
317GND              VIA   -    MD0080PA00X+026289Y+118179X0160Y         S0      
317GND              VIA   -    MD0080PA00X+025915Y+118179X0160Y         S0      
317GND              VIA   -    MD0080PA00X+026289Y+117431X0160Y         S0      
317GND              VIA   -    MD0080PA00X+026289Y+118927X0160Y         S0      
317GND              VIA   -    MD0080PA00X+025541Y+118927X0160Y         S0      
317GND              VIA   -    MD0080PA00X+025167Y+118927X0160Y         S0      
317GND              VIA   -    MD0080PA00X+024793Y+118927X0160Y         S0      
317GND              VIA   -    MD0080PA00X+025541Y+118179X0160Y         S0      
317GND              VIA   -    MD0080PA00X+025167Y+118179X0160Y         S0      
317GND              VIA   -    MD0080PA00X+024793Y+118179X0160Y         S0      
317GND              VIA   -    MD0080PA00X+025915Y+117057X0160Y         S0      
317GND              VIA   -    MD0080PA00X+025915Y+115935X0160Y         S0      
317GND              VIA   -    MD0080PA00X+025167Y+115935X0160Y         S0      
317GND              VIA   -    MD0080PA00X+024793Y+116683X0160Y         S0      
317GND              VIA   -    MD0080PA00X+025541Y+116683X0160Y         S0      
317GND              VIA   -    MD0080PA00X+025167Y+117057X0160Y         S0      
317GND              VIA   -    MD0080PA00X+026289Y+116683X0160Y         S0      
317GND              VIA   -    MD0080PA00X+026102Y+123228X0160Y         S0      
317GND              VIA   -    MD0080PA00X+025354Y+123228X0160Y         S0      
317GND              VIA   -    MD0080PA00X+026102Y+123602X0160Y         S0      
317GND              VIA   -    MD0080PA00X+025728Y+122480X0160Y         S0      
317GND              VIA   -    MD0080PA00X+025728Y+123976X0160Y         S0      
317GND              VIA   -    MD0080PA00X+026476Y+122854X0160Y         S0      
317GND              VIA   -    MD0080PA00X+024606Y+123976X0160Y         S0      
317GND              VIA   -    MD0080PA00X+025354Y+123602X0160Y         S0      
317GND              VIA   -    MD0080PA00X+024606Y+123602X0160Y         S0      
317GND              VIA   -    MD0080PA00X+024606Y+123228X0160Y         S0      
317GND              VIA   -    MD0080PA00X+024980Y+122480X0160Y         S0      
317GND              VIA   -    MD0080PA00X+025728Y+122854X0160Y         S0      
317GND              VIA   -    MD0080PA00X+024980Y+122854X0160Y         S0      
317GND              VIA   -    MD0080PA00X+026102Y+125472X0160Y    R180 S0      
317GND              VIA   -    MD0080PA00X+025728Y+125846X0160Y         S0      
317GND              VIA   -    MD0080PA00X+024980Y+125846X0160Y         S0      
317GND              VIA   -    MD0080PA00X+026102Y+123976X0160Y    R180 S0      
317GND              VIA   -    MD0080PA00X+026102Y+125098X0160Y    R180 S0      
317GND              VIA   -    MD0080PA00X+025728Y+124724X0160Y    R180 S0      
317GND              VIA   -    MD0080PA00X+025728Y+124350X0160Y    R270 S0      
317GND              VIA   -    MD0080PA00X+024980Y+123976X0160Y    R180 S0      
317GND              VIA   -    MD0080PA00X+025354Y+123976X0160Y    R180 S0      
317GND              VIA   -    MD0080PA00X+024606Y+125472X0160Y    R180 S0      
317GND              VIA   -    MD0080PA00X+024980Y+124724X0160Y    R180 S0      
317GND              VIA   -    MD0080PA00X+025354Y+125472X0160Y    R180 S0      
317GND              VIA   -    MD0080PA00X+025354Y+125098X0160Y    R180 S0      
317GND              VIA   -    MD0080PA00X+024980Y+124350X0160Y    R270 S0      
317GND              VIA   -    MD0080PA00X+027224Y+109016X0160Y         S0      
317GND              VIA   -    MD0080PA00X+026476Y+108642X0160Y         S0      
317GND              VIA   -    MD0080PA00X+026850Y+109016X0160Y         S0      
317GND              VIA   -    MD0080PA00X+026850Y+107894X0160Y         S0      
317GND              VIA   -    MD0080PA00X+026476Y+108268X0160Y    R180 S0      
317GND              VIA   -    MD0080PA00X+027224Y+108642X0160Y         S0      
317GND              VIA   -    MD0080PA00X+027598Y+109016X0160Y         S0      
317GND              VIA   -    MD0080PA00X+027224Y+108268X0160Y         S0      
317GND              VIA   -    MD0080PA00X+027598Y+107894X0160Y    R180 S0      
317GND              VIA   -    MD0080PA00X+027598Y+109390X0160Y         S0      
317GND              VIA   -    MD0080PA00X+027598Y+107520X0160Y         S0      
317GND              VIA   -    MD0080PA00X+027972Y+109016X0160Y         S0      
317GND              VIA   -    MD0080PA00X+026850Y+107520X0160Y         S0      
317GND              VIA   -    MD0080PA00X+027224Y+107146X0160Y         S0      
317GND              VIA   -    MD0080PA00X+026476Y+107146X0160Y         S0      
317GND              VIA   -    MD0080PA00X+027037Y+118553X0160Y         S0      
317GND              VIA   -    MD0080PA00X+027037Y+117805X0160Y         S0      
317GND              VIA   -    MD0080PA00X+026663Y+118927X0160Y         S0      
317GND              VIA   -    MD0080PA00X+027411Y+117431X0160Y         S0      
317GND              VIA   -    MD0080PA00X+027411Y+118179X0160Y         S0      
317GND              VIA   -    MD0080PA00X+027785Y+118179X0160Y         S0      
317GND              VIA   -    MD0080PA00X+027411Y+117057X0160Y         S0      
317GND              VIA   -    MD0080PA00X+027411Y+115935X0160Y         S0      
317GND              VIA   -    MD0080PA00X+027411Y+116683X0160Y         S0      
317GND              VIA   -    MD0080PA00X+027037Y+115561X0160Y         S0      
317GND              VIA   -    MD0080PA00X+027785Y+115187X0160Y         S0      
317GND              VIA   -    MD0080PA00X+027785Y+114813X0160Y         S0      
317GND              VIA   -    MD0080PA00X+027785Y+114439X0160Y         S0      
317GND              VIA   -    MD0080PA00X+027037Y+115187X0160Y         S0      
317GND              VIA   -    MD0080PA00X+027037Y+114813X0160Y         S0      
317GND              VIA   -    MD0080PA00X+027037Y+114439X0160Y         S0      
317GND              VIA   -    MD0080PA00X+026663Y+114813X0160Y         S0      
317GND              VIA   -    MD0080PA00X+027411Y+114813X0160Y         S0      
317GND              VIA   -    MD0080PA00X+027411Y+115187X0160Y         S0      
317GND              VIA   -    MD0080PA00X+027411Y+115561X0160Y         S0      
317GND              VIA   -    MD0080PA00X+027785Y+112569X0160Y    R180 S0      
317GND              VIA   -    MD0080PA00X+027785Y+114065X0160Y         S0      
317GND              VIA   -    MD0080PA00X+027785Y+113317X0160Y    R180 S0      
317GND              VIA   -    MD0080PA00X+027785Y+113691X0160Y         S0      
317GND              VIA   -    MD0080PA00X+027037Y+114065X0160Y         S0      
317GND              VIA   -    MD0080PA00X+026663Y+112569X0160Y         S0      
317GND              VIA   -    MD0080PA00X+027037Y+112943X0160Y         S0      
317GND              VIA   -    MD0080PA00X+027037Y+112569X0160Y         S0      
317GND              VIA   -    MD0080PA00X+026663Y+114065X0160Y         S0      
317GND              VIA   -    MD0080PA00X+027037Y+113317X0160Y         S0      
317GND              VIA   -    MD0080PA00X+026663Y+113317X0160Y         S0      
317GND              VIA   -    MD0080PA00X+027037Y+113691X0160Y         S0      
317GND              VIA   -    MD0080PA00X+027411Y+112569X0160Y         S0      
317GND              VIA   -    MD0080PA00X+027785Y+112943X0160Y    R270 S0      
317GND              VIA   -    MD0080PA00X+027785Y+112195X0160Y    R270 S0      
317GND              VIA   -    MD0080PA00X+027785Y+111821X0160Y         S0      
317GND              VIA   -    MD0080PA00X+027037Y+112195X0160Y         S0      
317GND              VIA   -    MD0080PA00X+026663Y+112195X0160Y         S0      
317GND              VIA   -    MD0080PA00X+027037Y+111821X0160Y         S0      
317GND              VIA   -    MD0080PA00X+027411Y+112195X0160Y    R180 S0      
317GND              VIA   -    MD0080PA00X+027411Y+111821X0160Y         S0      
317GND              VIA   -    MD0080PA00X+027972Y+110512X0160Y         S0      
317GND              VIA   -    MD0080PA00X+027598Y+109764X0160Y    R180 S0      
317GND              VIA   -    MD0080PA00X+027972Y+110138X0160Y    R270 S0      
317GND              VIA   -    MD0080PA00X+027224Y+110512X0160Y         S0      
317GND              VIA   -    MD0080PA00X+027224Y+110138X0160Y    R270 S0      
317GND              VIA   -    MD0080PA00X+026850Y+109764X0160Y         S0      
317GND              VIA   -    MD0080PA00X+026850Y+109390X0160Y         S0      
317GND              VIA   -    MD0080PA00X+027598Y+123602X0160Y         S0      
317GND              VIA   -    MD0080PA00X+027598Y+123228X0160Y         S0      
317GND              VIA   -    MD0080PA00X+027785Y+121171X0160Y         S0      
317GND              VIA   -    MD0080PA00X+027037Y+120797X0160Y         S0      
317GND              VIA   -    MD0080PA00X+026476Y+122106X0160Y    R270 S0      
317GND              VIA   -    MD0080PA00X+026663Y+121171X0160Y         S0      
317GND              VIA   -    MD0080PA00X+026663Y+120797X0160Y         S0      
317GND              VIA   -    MD0080PA00X+027037Y+121171X0160Y         S0      
317GND              VIA   -    MD0080PA00X+027411Y+120797X0160Y         S0      
317GND              VIA   -    MD0080PA00X+027785Y+119301X0160Y         S0      
317GND              VIA   -    MD0080PA00X+027037Y+119301X0160Y         S0      
317GND              VIA   -    MD0080PA00X+026663Y+119675X0160Y         S0      
317GND              VIA   -    MD0080PA00X+027037Y+120049X0160Y         S0      
317GND              VIA   -    MD0080PA00X+026663Y+120423X0160Y         S0      
317GND              VIA   -    MD0080PA00X+027037Y+120423X0160Y         S0      
317GND              VIA   -    MD0080PA00X+027039Y+119673X0160Y         S0      
317GND              VIA   -    MD0080PA00X+027411Y+119675X0160Y         S0      
317GND              VIA   -    MD0080PA00X+027411Y+120423X0160Y    R180 S0      
317GND              VIA   -    MD0080PA00X+027037Y+117431X0160Y         S0      
317GND              VIA   -    MD0080PA00X+027785Y+118553X0160Y         S0      
317GND              VIA   -    MD0080PA00X+027785Y+118927X0160Y         S0      
317GND              VIA   -    MD0080PA00X+027785Y+117805X0160Y         S0      
317GND              VIA   -    MD0080PA00X+027037Y+118927X0160Y         S0      
317GND              VIA   -    MD0080PA00X+026663Y+118179X0160Y         S0      
317GND              VIA   -    MD0080PA00X+027598Y+125472X0160Y    R180 S0      
317GND              VIA   -    MD0080PA00X+026850Y+125472X0160Y    R180 S0      
317GND              VIA   -    MD0080PA00X+027224Y+125846X0160Y         S0      
317GND              VIA   -    MD0080PA00X+026476Y+125846X0160Y         S0      
317GND              VIA   -    MD0080PA00X+027972Y+124350X0160Y    R180 S0      
317GND              VIA   -    MD0080PA00X+027598Y+125098X0160Y    R180 S0      
317GND              VIA   -    MD0080PA00X+027224Y+123976X0160Y    R180 S0      
317GND              VIA   -    MD0080PA00X+026476Y+124350X0160Y    R180 S0      
317GND              VIA   -    MD0080PA00X+026850Y+125098X0160Y    R180 S0      
317GND              VIA   -    MD0080PA00X+026476Y+124724X0160Y    R180 S0      
317GND              VIA   -    MD0080PA00X+026476Y+123976X0160Y    R270 S0      
317GND              VIA   -    MD0080PA00X+027224Y+124724X0160Y    R180 S0      
317GND              VIA   -    MD0080PA00X+027224Y+124350X0160Y    R180 S0      
317GND              VIA   -    MD0080PA00X+027598Y+123976X0160Y    R270 S0      
317GND              VIA   -    MD0080PA00X+026850Y+123976X0160Y         S0      
317GND              VIA   -    MD0080PA00X+026476Y+122480X0160Y         S0      
317GND              VIA   -    MD0080PA00X+027224Y+122854X0160Y         S0      
317GND              VIA   -    MD0080PA00X+026850Y+123228X0160Y         S0      
317GND              VIA   -    MD0080PA00X+026850Y+123602X0160Y         S0      
317GND              VIA   -    MD0080PA00X+027224Y+122480X0160Y         S0      
317GND              VIA   -    MD0080PA00X+028346Y+107520X0160Y         S0      
317GND              VIA   -    MD0080PA00X+028720Y+107146X0160Y         S0      
317GND              VIA   -    MD0080PA00X+027972Y+107146X0160Y         S0      
317GND              VIA   -    MD0080PA00X+029468Y+111260X0160Y         S0      
317GND              VIA   -    MD0080PA00X+029468Y+112008X0160Y         S0      
317GND              VIA   -    MD0080PA00X+029468Y+110512X0160Y         S0      
317GND              VIA   -    MD0080PA00X+029468Y+110138X0160Y    R270 S0      
317GND              VIA   -    MD0080PA00X+029094Y+109764X0160Y    R180 S0      
317GND              VIA   -    MD0080PA00X+028720Y+110512X0160Y         S0      
317GND              VIA   -    MD0080PA00X+028346Y+109764X0160Y    R270 S0      
317GND              VIA   -    MD0080PA00X+028720Y+110138X0160Y         S0      
317GND              VIA   -    MD0080PA00X+028346Y+109390X0160Y    R180 S0      
317GND              VIA   -    MD0080PA00X+029094Y+109390X0160Y         S0      
317GND              VIA   -    MD0080PA00X+029094Y+107520X0160Y         S0      
317GND              VIA   -    MD0080PA00X+029094Y+109016X0160Y         S0      
317GND              VIA   -    MD0080PA00X+028346Y+109016X0160Y         S0      
317GND              VIA   -    MD0080PA00X+028346Y+107894X0160Y         S0      
317GND              VIA   -    MD0080PA00X+027972Y+108642X0160Y    R180 S0      
317GND              VIA   -    MD0080PA00X+028720Y+108642X0160Y    R270 S0      
317GND              VIA   -    MD0080PA00X+028720Y+108268X0160Y    R180 S0      
317GND              VIA   -    MD0080PA00X+027972Y+108268X0160Y    R180 S0      
317GND              VIA   -    MD0080PA00X+029094Y+107894X0160Y    R180 S0      
317GND              VIA   -    MD0080PA00X+028720Y+109016X0160Y         S0      
317GND              VIA   -    MD0080PA00X+028533Y+119301X0160Y         S0      
317GND              VIA   -    MD0080PA00X+028159Y+119301X0160Y         S0      
317GND              VIA   -    MD0080PA00X+029094Y+119114X0160Y    R090 S0      
317GND              VIA   -    MD0080PA00X+028159Y+120423X0160Y         S0      
317GND              VIA   -    MD0080PA00X+028159Y+119675X0160Y         S0      
317GND              VIA   -    MD0080PA00X+029281Y+118927X0160Y         S0      
317GND              VIA   -    MD0080PA00X+029281Y+117431X0160Y         S0      
317GND              VIA   -    MD0080PA00X+028159Y+117431X0160Y         S0      
317GND              VIA   -    MD0080PA00X+028159Y+117805X0160Y         S0      
317GND              VIA   -    MD0080PA00X+028533Y+118179X0160Y         S0      
317GND              VIA   -    MD0080PA00X+028159Y+118553X0160Y         S0      
317GND              VIA   -    MD0080PA00X+028159Y+118927X0160Y         S0      
317GND              VIA   -    MD0080PA00X+028907Y+118553X0160Y         S0      
317GND              VIA   -    MD0080PA00X+028907Y+117805X0160Y         S0      
317GND              VIA   -    MD0080PA00X+028907Y+117431X0160Y         S0      
317GND              VIA   -    MD0080PA00X+028533Y+118553X0160Y         S0      
317GND              VIA   -    MD0080PA00X+029281Y+118179X0160Y         S0      
317GND              VIA   -    MD0080PA00X+029281Y+116683X0160Y         S0      
317GND              VIA   -    MD0080PA00X+029281Y+115935X0160Y         S0      
317GND              VIA   -    MD0080PA00X+028159Y+116683X0160Y         S0      
317GND              VIA   -    MD0080PA00X+028159Y+117057X0160Y         S0      
317GND              VIA   -    MD0080PA00X+028907Y+115935X0160Y         S0      
317GND              VIA   -    MD0080PA00X+028907Y+117057X0160Y         S0      
317GND              VIA   -    MD0080PA00X+028907Y+116683X0160Y         S0      
317GND              VIA   -    MD0080PA00X+028159Y+115935X0160Y         S0      
317GND              VIA   -    MD0080PA00X+029281Y+114439X0160Y         S0      
317GND              VIA   -    MD0080PA00X+029281Y+115187X0160Y         S0      
317GND              VIA   -    MD0080PA00X+028907Y+114439X0160Y    R270 S0      
317GND              VIA   -    MD0080PA00X+028907Y+115561X0160Y         S0      
317GND              VIA   -    MD0080PA00X+028907Y+115187X0160Y         S0      
317GND              VIA   -    MD0080PA00X+028533Y+115187X0160Y         S0      
317GND              VIA   -    MD0080PA00X+028159Y+115187X0160Y         S0      
317GND              VIA   -    MD0080PA00X+028159Y+115561X0160Y         S0      
317GND              VIA   -    MD0080PA00X+028159Y+114813X0160Y         S0      
317GND              VIA   -    MD0080PA00X+028159Y+113691X0160Y         S0      
317GND              VIA   -    MD0080PA00X+028159Y+114065X0160Y         S0      
317GND              VIA   -    MD0080PA00X+028720Y+122480X0160Y         S0      
317GND              VIA   -    MD0080PA00X+028346Y+123602X0160Y         S0      
317GND              VIA   -    MD0080PA00X+028720Y+122854X0160Y         S0      
317GND              VIA   -    MD0080PA00X+028346Y+123228X0160Y         S0      
317GND              VIA   -    MD0080PA00X+029094Y+123976X0160Y         S0      
317GND              VIA   -    MD0080PA00X+029094Y+123602X0160Y         S0      
317GND              VIA   -    MD0080PA00X+029094Y+123228X0160Y         S0      
317GND              VIA   -    MD0080PA00X+028346Y+123976X0160Y         S0      
317GND              VIA   -    MD0080PA00X+027972Y+122480X0160Y         S0      
317GND              VIA   -    MD0080PA00X+029468Y+121732X0160Y         S0      
317GND              VIA   -    MD0080PA00X+029094Y+125472X0160Y    R180 S0      
317GND              VIA   -    MD0080PA00X+028346Y+125472X0160Y    R180 S0      
317GND              VIA   -    MD0080PA00X+028720Y+125846X0160Y         S0      
317GND              VIA   -    MD0080PA00X+027972Y+125846X0160Y         S0      
317GND              VIA   -    MD0080PA00X+029094Y+125098X0160Y    R180 S0      
317GND              VIA   -    MD0080PA00X+029468Y+123976X0160Y    R270 S0      
317GND              VIA   -    MD0080PA00X+028720Y+123976X0160Y    R180 S0      
317GND              VIA   -    MD0080PA00X+027972Y+124724X0160Y    R180 S0      
317GND              VIA   -    MD0080PA00X+028720Y+124350X0160Y    R180 S0      
317GND              VIA   -    MD0080PA00X+028720Y+124724X0160Y    R180 S0      
317GND              VIA   -    MD0080PA00X+028346Y+125098X0160Y    R180 S0      
317GND              VIA   -    MD0080PA00X+027972Y+123976X0160Y    R270 S0      
317GND              VIA   -    MD0080PA00X+030591Y+107520X0160Y         S0      
317GND              VIA   -    MD0080PA00X+029842Y+107520X0160Y         S0      
317GND              VIA   -    MD0080PA00X+030216Y+107146X0160Y         S0      
317GND              VIA   -    MD0080PA00X+030964Y+107146X0160Y         S0      
317GND              VIA   -    MD0080PA00X+029468Y+107146X0160Y         S0      
317GND              VIA   -    MD0080PA00X+030590Y+109390X0160Y         S0      
317GND              VIA   -    MD0080PA00X+030964Y+109016X0160Y    R270 S0      
317GND              VIA   -    MD0080PA00X+030964Y+108642X0160Y    R180 S0      
317GND              VIA   -    MD0080PA00X+030591Y+107894X0160Y         S0      
317GND              VIA   -    MD0080PA00X+030964Y+108268X0160Y    R180 S0      
317GND              VIA   -    MD0080PA00X+030590Y+109016X0160Y    R270 S0      
317GND              VIA   -    MD0080PA00X+029842Y+109390X0160Y         S0      
317GND              VIA   -    MD0080PA00X+030216Y+108642X0160Y    R180 S0      
317GND              VIA   -    MD0080PA00X+030216Y+109016X0160Y    R270 S0      
317GND              VIA   -    MD0080PA00X+029468Y+108642X0160Y    R180 S0      
317GND              VIA   -    MD0080PA00X+029468Y+109016X0160Y    R180 S0      
317GND              VIA   -    MD0080PA00X+029843Y+107894X0160Y         S0      
317GND              VIA   -    MD0080PA00X+030216Y+108268X0160Y    R180 S0      
317GND              VIA   -    MD0080PA00X+029468Y+108268X0160Y    R180 S0      
317GND              VIA   -    MD0080PA00X+029842Y+109016X0160Y         S0      
317GND              VIA   -    MD0080PA00X+029842Y+112756X0160Y    R270 S0      
317GND              VIA   -    MD0080PA00X+030216Y+113130X0160Y         S0      
317GND              VIA   -    MD0080PA00X+029468Y+113504X0160Y    R090 S0      
317GND              VIA   -    MD0080PA00X+029842Y+113504X0160Y    R270 S0      
317GND              VIA   -    MD0080PA00X+030030Y+114065X0160Y         S0      
317GND              VIA   -    MD0080PA00X+030590Y+112382X0160Y    R090 S0      
317GND              VIA   -    MD0080PA00X+030590Y+113130X0160Y    R090 S0      
317GND              VIA   -    MD0080PA00X+030404Y+114065X0160Y    R090 S0      
317GND              VIA   -    MD0080PA00X+030778Y+114065X0160Y    R270 S0      
317GND              VIA   -    MD0080PA00X+031152Y+113691X0160Y    R090 S0      
317GND              VIA   -    MD0080PA00X+030964Y+113130X0160Y    R270 S0      
317GND              VIA   -    MD0080PA00X+030964Y+112756X0160Y    R090 S0      
317GND              VIA   -    MD0080PA00X+029842Y+112008X0160Y    R090 S0      
317GND              VIA   -    MD0080PA00X+030590Y+111634X0160Y    R090 S0      
317GND              VIA   -    MD0080PA00X+030964Y+112008X0160Y    R090 S0      
317GND              VIA   -    MD0080PA00X+030964Y+111634X0160Y    R270 S0      
317GND              VIA   -    MD0080PA00X+030964Y+111260X0160Y    R090 S0      
317GND              VIA   -    MD0080PA00X+031338Y+111634X0160Y    R090 S0      
317GND              VIA   -    MD0080PA00X+029842Y+111260X0160Y    R090 S0      
317GND              VIA   -    MD0080PA00X+030216Y+110886X0160Y    R090 S0      
317GND              VIA   -    MD0080PA00X+029842Y+110886X0160Y         S0      
317GND              VIA   -    MD0080PA00X+030216Y+111634X0160Y         S0      
317GND              VIA   -    MD0080PA00X+030590Y+109764X0160Y    R180 S0      
317GND              VIA   -    MD0080PA00X+030964Y+110886X0160Y    R270 S0      
317GND              VIA   -    MD0080PA00X+030964Y+110138X0160Y    R270 S0      
317GND              VIA   -    MD0080PA00X+030964Y+110512X0160Y         S0      
317GND              VIA   -    MD0080PA00X+030590Y+110886X0160Y         S0      
317GND              VIA   -    MD0080PA00X+030216Y+110512X0160Y         S0      
317GND              VIA   -    MD0080PA00X+029842Y+109764X0160Y    R180 S0      
317GND              VIA   -    MD0080PA00X+030216Y+110138X0160Y    R270 S0      
317GND              VIA   -    MD0080PA00X+030964Y+120236X0160Y         S0      
317GND              VIA   -    MD0080PA00X+030590Y+119862X0160Y         S0      
317GND              VIA   -    MD0080PA00X+031152Y+119675X0160Y         S0      
317GND              VIA   -    MD0080PA00X+030778Y+119301X0160Y         S0      
317GND              VIA   -    MD0080PA00X+030964Y+119862X0160Y         S0      
317GND              VIA   -    MD0080PA00X+029842Y+119488X0160Y         S0      
317GND              VIA   -    MD0080PA00X+029842Y+120236X0160Y         S0      
317GND              VIA   -    MD0080PA00X+030216Y+119862X0160Y    R090 S0      
317GND              VIA   -    MD0080PA00X+030404Y+119301X0160Y    R090 S0      
317GND              VIA   -    MD0080PA00X+029468Y+120236X0160Y    R090 S0      
317GND              VIA   -    MD0080PA00X+029468Y+119488X0160Y    R090 S0      
317GND              VIA   -    MD0080PA00X+031152Y+118927X0160Y         S0      
317GND              VIA   -    MD0080PA00X+030778Y+118553X0160Y         S0      
317GND              VIA   -    MD0080PA00X+031152Y+118179X0160Y         S0      
317GND              VIA   -    MD0080PA00X+030778Y+117805X0160Y         S0      
317GND              VIA   -    MD0080PA00X+031152Y+117431X0160Y         S0      
317GND              VIA   -    MD0080PA00X+030030Y+118927X0160Y         S0      
317GND              VIA   -    MD0080PA00X+030404Y+117805X0160Y    R090 S0      
317GND              VIA   -    MD0080PA00X+030404Y+118553X0160Y    R090 S0      
317GND              VIA   -    MD0080PA00X+029842Y+118740X0160Y    R090 S0      
317GND              VIA   -    MD0080PA00X+029656Y+117431X0160Y    R090 S0      
317GND              VIA   -    MD0080PA00X+030030Y+117431X0160Y         S0      
317GND              VIA   -    MD0080PA00X+030030Y+117805X0160Y    R090 S0      
317GND              VIA   -    MD0080PA00X+030030Y+118179X0160Y         S0      
317GND              VIA   -    MD0080PA00X+030030Y+118553X0160Y    R090 S0      
317GND              VIA   -    MD0080PA00X+031152Y+115935X0160Y    R090 S0      
317GND              VIA   -    MD0080PA00X+030778Y+117057X0160Y         S0      
317GND              VIA   -    MD0080PA00X+031152Y+116683X0160Y         S0      
317GND              VIA   -    MD0080PA00X+030030Y+116683X0160Y         S0      
317GND              VIA   -    MD0080PA00X+030030Y+117057X0160Y    R090 S0      
317GND              VIA   -    MD0080PA00X+030404Y+117057X0160Y    R090 S0      
317GND              VIA   -    MD0080PA00X+029656Y+116683X0160Y    R090 S0      
317GND              VIA   -    MD0080PA00X+030030Y+115935X0160Y         S0      
317GND              VIA   -    MD0080PA00X+029656Y+115935X0160Y    R090 S0      
317GND              VIA   -    MD0080PA00X+030778Y+115935X0160Y    R270 S0      
317GND              VIA   -    MD0080PA00X+030778Y+115561X0160Y    R270 S0      
317GND              VIA   -    MD0080PA00X+031152Y+115187X0160Y    R090 S0      
317GND              VIA   -    MD0080PA00X+030778Y+114813X0160Y    R270 S0      
317GND              VIA   -    MD0080PA00X+031152Y+114439X0160Y    R090 S0      
317GND              VIA   -    MD0080PA00X+029656Y+114439X0160Y    R090 S0      
317GND              VIA   -    MD0080PA00X+030030Y+114439X0160Y    R270 S0      
317GND              VIA   -    MD0080PA00X+030030Y+114813X0160Y         S0      
317GND              VIA   -    MD0080PA00X+030030Y+115187X0160Y    R270 S0      
317GND              VIA   -    MD0080PA00X+030030Y+115561X0160Y    R180 S0      
317GND              VIA   -    MD0080PA00X+030404Y+114813X0160Y    R090 S0      
317GND              VIA   -    MD0080PA00X+030404Y+115561X0160Y    R090 S0      
317GND              VIA   -    MD0080PA00X+029656Y+115187X0160Y    R090 S0      
317GND              VIA   -    MD0080PA00X+030964Y+112382X0160Y    R270 S0      
317GND              VIA   -    MD0080PA00X+031338Y+112382X0160Y    R090 S0      
317GND              VIA   -    MD0080PA00X+030964Y+113504X0160Y    R090 S0      
317GND              VIA   -    MD0080PA00X+030216Y+112382X0160Y         S0      
317GND              VIA   -    MD0080PA00X+029468Y+112756X0160Y    R090 S0      
317GND              VIA   -    MD0080PA00X+030964Y+123976X0160Y         S0      
317GND              VIA   -    MD0080PA00X+030590Y+123602X0160Y         S0      
317GND              VIA   -    MD0080PA00X+030964Y+122480X0160Y         S0      
317GND              VIA   -    MD0080PA00X+030964Y+122854X0160Y         S0      
317GND              VIA   -    MD0080PA00X+030590Y+123228X0160Y         S0      
317GND              VIA   -    MD0080PA00X+029842Y+123976X0160Y         S0      
317GND              VIA   -    MD0080PA00X+030590Y+122106X0160Y         S0      
317GND              VIA   -    MD0080PA00X+030216Y+122480X0160Y         S0      
317GND              VIA   -    MD0080PA00X+029468Y+122106X0160Y         S0      
317GND              VIA   -    MD0080PA00X+029468Y+122480X0160Y         S0      
317GND              VIA   -    MD0080PA00X+030216Y+122854X0160Y         S0      
317GND              VIA   -    MD0080PA00X+029468Y+122854X0160Y         S0      
317GND              VIA   -    MD0080PA00X+029842Y+123228X0160Y         S0      
317GND              VIA   -    MD0080PA00X+029842Y+123602X0160Y         S0      
317GND              VIA   -    MD0080PA00X+030964Y+122106X0160Y         S0      
317GND              VIA   -    MD0080PA00X+030964Y+120610X0160Y         S0      
317GND              VIA   -    MD0080PA00X+030964Y+121358X0160Y         S0      
317GND              VIA   -    MD0080PA00X+030590Y+121358X0160Y         S0      
317GND              VIA   -    MD0080PA00X+030964Y+120984X0160Y         S0      
317GND              VIA   -    MD0080PA00X+030964Y+121732X0160Y         S0      
317GND              VIA   -    MD0080PA00X+029842Y+121732X0160Y    R090 S0      
317GND              VIA   -    MD0080PA00X+030216Y+122106X0160Y         S0      
317GND              VIA   -    MD0080PA00X+029842Y+122106X0160Y    R090 S0      
317GND              VIA   -    MD0080PA00X+030216Y+120610X0160Y    R090 S0      
317GND              VIA   -    MD0080PA00X+029842Y+120984X0160Y         S0      
317GND              VIA   -    MD0080PA00X+029468Y+120984X0160Y    R090 S0      
317GND              VIA   -    MD0080PA00X+030216Y+121358X0160Y    R090 S0      
317GND              VIA   -    MD0080PA00X+030590Y+120610X0160Y    R090 S0      
317GND              VIA   -    MD0080PA00X+030590Y+125472X0160Y    R180 S0      
317GND              VIA   -    MD0080PA00X+029842Y+125472X0160Y    R180 S0      
317GND              VIA   -    MD0080PA00X+030216Y+125846X0160Y         S0      
317GND              VIA   -    MD0080PA00X+029468Y+125846X0160Y         S0      
317GND              VIA   -    MD0080PA00X+030964Y+125846X0160Y         S0      
317GND              VIA   -    MD0080PA00X+030590Y+125098X0160Y    R180 S0      
317GND              VIA   -    MD0080PA00X+031338Y+123976X0160Y    R270 S0      
317GND              VIA   -    MD0080PA00X+030216Y+123976X0160Y    R180 S0      
317GND              VIA   -    MD0080PA00X+030590Y+123976X0160Y    R270 S0      
317GND              VIA   -    MD0080PA00X+030216Y+124350X0160Y    R180 S0      
317GND              VIA   -    MD0080PA00X+029468Y+124350X0160Y    R180 S0      
317GND              VIA   -    MD0080PA00X+030216Y+124724X0160Y    R180 S0      
317GND              VIA   -    MD0080PA00X+029842Y+125098X0160Y    R180 S0      
317GND              VIA   -    MD0080PA00X+029468Y+124724X0160Y    R180 S0      
317GND              VIA   -    MD0080PA00X+031712Y+123976X0160Y    R180 S0      
317GND              VIA   -    MD0080PA00X+030964Y+124350X0160Y    R180 S0      
317GND              VIA   -    MD0080PA00X+030964Y+124724X0160Y    R180 S0      
317GND              VIA   -    MD0080PA00X+032835Y+109016X0160Y         S0      
317GND              VIA   -    MD0080PA00X+032835Y+108268X0160Y         S0      
317GND              VIA   -    MD0080PA00X+031339Y+107520X0160Y         S0      
317GND              VIA   -    MD0080PA00X+032087Y+107520X0160Y         S0      
317GND              VIA   -    MD0080PA00X+031712Y+107146X0160Y         S0      
317GND              VIA   -    MD0080PA00X+031338Y+109764X0160Y    R180 S0      
317GND              VIA   -    MD0080PA00X+031712Y+110138X0160Y    R270 S0      
317GND              VIA   -    MD0080PA00X+031713Y+110512X0160Y    R270 S0      
317GND              VIA   -    MD0080PA00X+031712Y+110886X0160Y    R180 S0      
317GND              VIA   -    MD0080PA00X+031338Y+110886X0160Y         S0      
317GND              VIA   -    MD0080PA00X+032087Y+109764X0160Y    R180 S0      
317GND              VIA   -    MD0080PA00X+032087Y+110512X0160Y    R180 S0      
317GND              VIA   -    MD0080PA00X+032835Y+110886X0160Y         S0      
317GND              VIA   -    MD0080PA00X+032835Y+110138X0160Y         S0      
317GND              VIA   -    MD0080PA00X+032461Y+109764X0160Y    R180 S0      
317GND              VIA   -    MD0080PA00X+032461Y+110512X0160Y    R180 S0      
317GND              VIA   -    MD0080PA00X+032461Y+109390X0160Y    R180 S0      
317GND              VIA   -    MD0080PA00X+032461Y+108642X0160Y    R180 S0      
317GND              VIA   -    MD0080PA00X+031338Y+109390X0160Y         S0      
317GND              VIA   -    MD0080PA00X+032087Y+109390X0160Y    R180 S0      
317GND              VIA   -    MD0080PA00X+031339Y+107894X0160Y         S0      
317GND              VIA   -    MD0080PA00X+031712Y+108268X0160Y    R180 S0      
317GND              VIA   -    MD0080PA00X+031713Y+108642X0160Y    R180 S0      
317GND              VIA   -    MD0080PA00X+031712Y+109016X0160Y    R270 S0      
317GND              VIA   -    MD0080PA00X+031338Y+109016X0160Y         S0      
317GND              VIA   -    MD0080PA00X+032087Y+107894X0160Y         S0      
317GND              VIA   -    MD0080PA00X+032087Y+108642X0160Y    R180 S0      
317GND              VIA   -    MD0080PA00X+032274Y+114813X0160Y    R180 S0      
317GND              VIA   -    MD0080PA00X+032648Y+114065X0160Y    R180 S0      
317GND              VIA   -    MD0080PA00X+032461Y+113504X0160Y    R180 S0      
317GND              VIA   -    MD0080PA00X+032461Y+112756X0160Y    R180 S0      
317GND              VIA   -    MD0080PA00X+031712Y+113130X0160Y    R270 S0      
317GND              VIA   -    MD0080PA00X+031338Y+113130X0160Y    R090 S0      
317GND              VIA   -    MD0080PA00X+031900Y+113691X0160Y    R270 S0      
317GND              VIA   -    MD0080PA00X+031526Y+113691X0160Y    R090 S0      
317GND              VIA   -    MD0080PA00X+031900Y+114065X0160Y         S0      
317GND              VIA   -    MD0080PA00X+032274Y+114065X0160Y    R180 S0      
317GND              VIA   -    MD0080PA00X+032087Y+113504X0160Y    R180 S0      
317GND              VIA   -    MD0080PA00X+032087Y+112756X0160Y    R180 S0      
317GND              VIA   -    MD0080PA00X+032835Y+113130X0160Y         S0      
317GND              VIA   -    MD0080PA00X+031712Y+112382X0160Y    R090 S0      
317GND              VIA   -    MD0080PA00X+032087Y+112008X0160Y    R180 S0      
317GND              VIA   -    MD0080PA00X+032087Y+111260X0160Y    R180 S0      
317GND              VIA   -    MD0080PA00X+032835Y+112382X0160Y         S0      
317GND              VIA   -    MD0080PA00X+032835Y+111634X0160Y         S0      
317GND              VIA   -    MD0080PA00X+032461Y+112008X0160Y    R180 S0      
317GND              VIA   -    MD0080PA00X+032461Y+111260X0160Y    R180 S0      
317GND              VIA   -    MD0080PA00X+031712Y+111634X0160Y    R090 S0      
317GND              VIA   -    MD0080PA00X+032461Y+121732X0160Y    R090 S0      
317GND              VIA   -    MD0080PA00X+032461Y+120984X0160Y    R090 S0      
317GND              VIA   -    MD0080PA00X+031712Y+121358X0160Y    R270 S0      
317GND              VIA   -    MD0080PA00X+031338Y+121358X0160Y    R090 S0      
317GND              VIA   -    MD0080PA00X+031712Y+122106X0160Y    R090 S0      
317GND              VIA   -    MD0080PA00X+031338Y+122106X0160Y         S0      
317GND              VIA   -    MD0080PA00X+032087Y+120984X0160Y         S0      
317GND              VIA   -    MD0080PA00X+032087Y+121732X0160Y    R090 S0      
317GND              VIA   -    MD0080PA00X+032835Y+121358X0160Y         S0      
317GND              VIA   -    MD0080PA00X+032835Y+122106X0160Y         S0      
317GND              VIA   -    MD0080PA00X+032461Y+120236X0160Y         S0      
317GND              VIA   -    MD0080PA00X+032642Y+119301X0160Y         S0      
317GND              VIA   -    MD0080PA00X+031712Y+119862X0160Y    R270 S0      
317GND              VIA   -    MD0080PA00X+031338Y+120610X0160Y    R090 S0      
317GND              VIA   -    MD0080PA00X+031712Y+120610X0160Y    R270 S0      
317GND              VIA   -    MD0080PA00X+031338Y+119862X0160Y    R090 S0      
317GND              VIA   -    MD0080PA00X+031900Y+119301X0160Y         S0      
317GND              VIA   -    MD0080PA00X+032087Y+120236X0160Y         S0      
317GND              VIA   -    MD0080PA00X+032274Y+119301X0160Y         S0      
317GND              VIA   -    MD0080PA00X+032835Y+120610X0160Y         S0      
317GND              VIA   -    MD0080PA00X+032835Y+119862X0160Y         S0      
317GND              VIA   -    MD0080PA00X+032274Y+118553X0160Y         S0      
317GND              VIA   -    MD0080PA00X+032274Y+117805X0160Y         S0      
317GND              VIA   -    MD0080PA00X+032648Y+118553X0160Y    R180 S0      
317GND              VIA   -    MD0080PA00X+032648Y+117805X0160Y    R180 S0      
317GND              VIA   -    MD0080PA00X+031900Y+117431X0160Y    R270 S0      
317GND              VIA   -    MD0080PA00X+031526Y+117431X0160Y    R090 S0      
317GND              VIA   -    MD0080PA00X+031900Y+117805X0160Y         S0      
317GND              VIA   -    MD0080PA00X+031900Y+118179X0160Y    R270 S0      
317GND              VIA   -    MD0080PA00X+031900Y+118553X0160Y         S0      
317GND              VIA   -    MD0080PA00X+031900Y+118927X0160Y    R270 S0      
317GND              VIA   -    MD0080PA00X+031526Y+118927X0160Y    R090 S0      
317GND              VIA   -    MD0080PA00X+031526Y+118179X0160Y    R090 S0      
317GND              VIA   -    MD0080PA00X+032648Y+117057X0160Y    R180 S0      
317GND              VIA   -    MD0080PA00X+032648Y+116683X0160Y    R270 S0      
317GND              VIA   -    MD0080PA00X+031900Y+116683X0160Y    R270 S0      
317GND              VIA   -    MD0080PA00X+031900Y+117057X0160Y         S0      
317GND              VIA   -    MD0080PA00X+031526Y+116683X0160Y    R090 S0      
317GND              VIA   -    MD0080PA00X+031900Y+115935X0160Y    R270 S0      
317GND              VIA   -    MD0080PA00X+031526Y+115935X0160Y    R090 S0      
317GND              VIA   -    MD0080PA00X+032274Y+116683X0160Y    R270 S0      
317GND              VIA   -    MD0080PA00X+032274Y+117057X0160Y         S0      
317GND              VIA   -    MD0080PA00X+032648Y+115561X0160Y    R180 S0      
317GND              VIA   -    MD0080PA00X+032648Y+114813X0160Y    R180 S0      
317GND              VIA   -    MD0080PA00X+031900Y+114813X0160Y         S0      
317GND              VIA   -    MD0080PA00X+031900Y+115187X0160Y    R270 S0      
317GND              VIA   -    MD0080PA00X+031526Y+115187X0160Y    R090 S0      
317GND              VIA   -    MD0080PA00X+031900Y+115561X0160Y         S0      
317GND              VIA   -    MD0080PA00X+031526Y+114439X0160Y    R090 S0      
317GND              VIA   -    MD0080PA00X+031900Y+114439X0160Y    R270 S0      
317GND              VIA   -    MD0080PA00X+032274Y+115561X0160Y    R180 S0      
317GND              VIA   -    MD0080PA00X+031338Y+125472X0160Y    R180 S0      
317GND              VIA   -    MD0080PA00X+031712Y+125846X0160Y         S0      
317GND              VIA   -    MD0080PA00X+032461Y+125098X0160Y         S0      
317GND              VIA   -    MD0080PA00X+032461Y+124350X0160Y    R090 S0      
317GND              VIA   -    MD0080PA00X+031712Y+124350X0160Y    R180 S0      
317GND              VIA   -    MD0080PA00X+031712Y+124724X0160Y    R180 S0      
317GND              VIA   -    MD0080PA00X+031338Y+125098X0160Y    R180 S0      
317GND              VIA   -    MD0080PA00X+032087Y+124350X0160Y    R270 S0      
317GND              VIA   -    MD0080PA00X+032087Y+125098X0160Y    R180 S0      
317GND              VIA   -    MD0080PA00X+032835Y+124724X0160Y         S0      
317GND              VIA   -    MD0080PA00X+032835Y+123976X0160Y         S0      
317GND              VIA   -    MD0080PA00X+032461Y+122480X0160Y    R090 S0      
317GND              VIA   -    MD0080PA00X+032461Y+123602X0160Y    R090 S0      
317GND              VIA   -    MD0080PA00X+032461Y+123228X0160Y    R090 S0      
317GND              VIA   -    MD0080PA00X+031338Y+123602X0160Y         S0      
317GND              VIA   -    MD0080PA00X+031712Y+122480X0160Y         S0      
317GND              VIA   -    MD0080PA00X+031712Y+122854X0160Y         S0      
317GND              VIA   -    MD0080PA00X+031338Y+123228X0160Y         S0      
317GND              VIA   -    MD0080PA00X+032087Y+123228X0160Y         S0      
317GND              VIA   -    MD0080PA00X+032087Y+122480X0160Y    R090 S0      
317GND              VIA   -    MD0080PA00X+032087Y+123602X0160Y    R090 S0      
317GND              VIA   -    MD0080PA00X+059780Y+117057X0160Y         S0      
317GND              VIA   -    MD0080PA00X+060404Y+115935X0160Y         S0      
317GND              VIA   -    MD0080PA00X+060404Y+116683X0160Y    R180 S0      
317GND              VIA   -    MD0080PA00X+060030Y+115935X0160Y         S0      
317GND              VIA   -    MD0080PA00X+060404Y+115187X0160Y         S0      
317GND              VIA   -    MD0080PA00X+060404Y+114439X0160Y         S0      
317GND              VIA   -    MD0080PA00X+060030Y+115187X0160Y         S0      
317GND              VIA   -    MD0080PA00X+060030Y+114439X0160Y         S0      
317GND              VIA   -    MD0080PA00X+060404Y+114065X0160Y         S0      
317GND              VIA   -    MD0080PA00X+060404Y+113317X0160Y         S0      
317GND              VIA   -    MD0080PA00X+060404Y+112569X0160Y         S0      
317GND              VIA   -    MD0080PA00X+060030Y+114065X0160Y         S0      
317GND              VIA   -    MD0080PA00X+060030Y+113317X0160Y         S0      
317GND              VIA   -    MD0080PA00X+060030Y+112569X0160Y         S0      
317GND              VIA   -    MD0080PA00X+060404Y+111821X0160Y    R180 S0      
317GND              VIA   -    MD0080PA00X+060404Y+111073X0160Y    R180 S0      
317GND              VIA   -    MD0080PA00X+060030Y+111821X0160Y    R180 S0      
317GND              VIA   -    MD0080PA00X+060030Y+111073X0160Y    R180 S0      
317GND              VIA   -    MD0080PA00X+060404Y+109577X0160Y    R180 S0      
317GND              VIA   -    MD0080PA00X+060030Y+109577X0160Y    R180 S0      
317GND              VIA   -    MD0080PA00X+060030Y+110325X0160Y         S0      
317GND              VIA   -    MD0080PA00X+060404Y+110325X0160Y         S0      
317GND              VIA   -    MD0080PA00X+060404Y+109203X0160Y    R180 S0      
317GND              VIA   -    MD0080PA00X+060404Y+108455X0160Y    R180 S0      
317GND              VIA   -    MD0080PA00X+060404Y+108081X0160Y         S0      
317GND              VIA   -    MD0080PA00X+060404Y+107707X0160Y    R180 S0      
317GND              VIA   -    MD0080PA00X+060030Y+109203X0160Y    R180 S0      
317GND              VIA   -    MD0080PA00X+060030Y+108455X0160Y    R180 S0      
317GND              VIA   -    MD0080PA00X+075925Y+108642X0160Y    R180 S0      
317GND              VIA   -    MD0080PA00X+068819Y+109390X0160Y         S0      
317GND              VIA   -    MD0080PA00X+068445Y+110512X0160Y         S0      
317GND              VIA   -    MD0080PA00X+068445Y+110138X0160Y         S0      
317GND              VIA   -    MD0080PA00X+067697Y+110512X0160Y         S0      
317GND              VIA   -    MD0080PA00X+059780Y+117805X0160Y         S0      
317GND              VIA   -    MD0080PA00X+068071Y+109016X0160Y         S0      
317GND              VIA   -    MD0080PA00X+060403Y+117431X0160Y         S0      
317GND              VIA   -    MD0080PA00X+061900Y+110699X0160Y         S0      
317GND              VIA   -    MD0080PA00X+061900Y+107707X0160Y    R180 S0      
317GND              VIA   -    MD0080PA00X+061152Y+109203X0160Y    R180 S0      
317GND              VIA   -    MD0080PA00X+060778Y+108829X0160Y    R180 S0      
317GND              VIA   -    MD0080PA00X+061152Y+108829X0160Y    R180 S0      
317GND              VIA   -    MD0080PA00X+061526Y+108829X0160Y    R180 S0      
317GND              VIA   -    MD0080PA00X+060778Y+108455X0160Y    R180 S0      
317GND              VIA   -    MD0080PA00X+061526Y+108455X0160Y    R180 S0      
317GND              VIA   -    MD0080PA00X+060778Y+108081X0160Y    R180 S0      
317GND              VIA   -    MD0080PA00X+061526Y+108081X0160Y    R180 S0      
317GND              VIA   -    MD0080PA00X+061152Y+107707X0160Y    R180 S0      
317GND              VIA   -    MD0080PA00X+060778Y+107707X0160Y         S0      
317GND              VIA   -    MD0080PA00X+061900Y+109203X0160Y    R180 S0      
317GND              VIA   -    MD0080PA00X+061900Y+108829X0160Y    R180 S0      
317GND              VIA   -    MD0080PA00X+061900Y+107333X0160Y    R180 S0      
317GND              VIA   -    MD0080PA00X+061152Y+107333X0160Y    R180 S0      
317GND              VIA   -    MD0080PA00X+076299Y+109016X0160Y    R270 S0      
317GND              VIA   -    MD0080PA00X+075925Y+109016X0160Y    R270 S0      
317GND              VIA   -    MD0080PA00X+061526Y+117431X0160Y         S0      
317GND              VIA   -    MD0080PA00X+061152Y+117431X0160Y         S0      
317GND              VIA   -    MD0080PA00X+060778Y+117805X0160Y         S0      
317GND              VIA   -    MD0080PA00X+060778Y+117431X0160Y         S0      
317GND              VIA   -    MD0080PA00X+061900Y+117805X0160Y         S0      
317GND              VIA   -    MD0080PA00X+061900Y+117431X0160Y         S0      
317GND              VIA   -    MD0080PA00X+061900Y+115935X0160Y         S0      
317GND              VIA   -    MD0080PA00X+060778Y+117057X0160Y         S0      
317GND              VIA   -    MD0080PA00X+061152Y+117057X0160Y         S0      
317GND              VIA   -    MD0080PA00X+060778Y+116683X0160Y         S0      
317GND              VIA   -    MD0080PA00X+061152Y+116683X0160Y    R270 S0      
317GND              VIA   -    MD0080PA00X+061526Y+116683X0160Y         S0      
317GND              VIA   -    MD0080PA00X+060778Y+115935X0160Y         S0      
317GND              VIA   -    MD0080PA00X+060778Y+115561X0160Y         S0      
317GND              VIA   -    MD0080PA00X+061152Y+115561X0160Y         S0      
317GND              VIA   -    MD0080PA00X+061526Y+115561X0160Y         S0      
317GND              VIA   -    MD0080PA00X+060778Y+115187X0160Y         S0      
317GND              VIA   -    MD0080PA00X+060778Y+114813X0160Y         S0      
317GND              VIA   -    MD0080PA00X+061152Y+115187X0160Y    R270 S0      
317GND              VIA   -    MD0080PA00X+061526Y+115187X0160Y    R270 S0      
317GND              VIA   -    MD0080PA00X+060778Y+114439X0160Y         S0      
317GND              VIA   -    MD0080PA00X+061900Y+115561X0160Y         S0      
317GND              VIA   -    MD0080PA00X+061900Y+115187X0160Y         S0      
317GND              VIA   -    MD0080PA00X+061900Y+114813X0160Y         S0      
317GND              VIA   -    MD0080PA00X+061900Y+114439X0160Y         S0      
317GND              VIA   -    MD0080PA00X+061900Y+113317X0160Y    R270 S0      
317GND              VIA   -    MD0080PA00X+061900Y+112943X0160Y    R090 S0      
317GND              VIA   -    MD0080PA00X+061900Y+112569X0160Y    R270 S0      
317GND              VIA   -    MD0080PA00X+061900Y+114065X0160Y         S0      
317GND              VIA   -    MD0080PA00X+060778Y+114065X0160Y         S0      
317GND              VIA   -    MD0080PA00X+061152Y+114065X0160Y         S0      
317GND              VIA   -    MD0080PA00X+061526Y+114065X0160Y         S0      
317GND              VIA   -    MD0080PA00X+060778Y+113691X0160Y         S0      
317GND              VIA   -    MD0080PA00X+060778Y+112943X0160Y         S0      
317GND              VIA   -    MD0080PA00X+061152Y+112943X0160Y         S0      
317GND              VIA   -    MD0080PA00X+061526Y+112943X0160Y    R180 S0      
317GND              VIA   -    MD0080PA00X+061526Y+112569X0160Y         S0      
317GND              VIA   -    MD0080PA00X+061900Y+111447X0160Y         S0      
317GND              VIA   -    MD0080PA00X+060778Y+112195X0160Y         S0      
317GND              VIA   -    MD0080PA00X+061152Y+112195X0160Y         S0      
317GND              VIA   -    MD0080PA00X+061526Y+112195X0160Y         S0      
317GND              VIA   -    MD0080PA00X+061526Y+111821X0160Y         S0      
317GND              VIA   -    MD0080PA00X+060778Y+111447X0160Y    R180 S0      
317GND              VIA   -    MD0080PA00X+061152Y+111447X0160Y    R180 S0      
317GND              VIA   -    MD0080PA00X+061526Y+111447X0160Y    R180 S0      
317GND              VIA   -    MD0080PA00X+061526Y+111073X0160Y    R180 S0      
317GND              VIA   -    MD0080PA00X+061900Y+109577X0160Y    R180 S0      
317GND              VIA   -    MD0080PA00X+061526Y+110699X0160Y         S0      
317GND              VIA   -    MD0080PA00X+060778Y+110325X0160Y    R180 S0      
317GND              VIA   -    MD0080PA00X+061526Y+110325X0160Y    R180 S0      
317GND              VIA   -    MD0080PA00X+060778Y+109951X0160Y    R180 S0      
317GND              VIA   -    MD0080PA00X+061526Y+109951X0160Y    R180 S0      
317GND              VIA   -    MD0080PA00X+061152Y+109577X0160Y    R180 S0      
317GND              VIA   -    MD0080PA00X+060778Y+110699X0160Y    R180 S0      
317GND              VIA   -    MD0080PA00X+061152Y+110699X0160Y    R180 S0      
317GND              VIA   -    MD0080PA00X+076299Y+107520X0160Y         S0      
317GND              VIA   -    MD0080PA00X+075551Y+107520X0160Y         S0      
317GND              VIA   -    MD0080PA00X+062274Y+108829X0160Y    R180 S0      
317GND              VIA   -    MD0080PA00X+062274Y+108455X0160Y    R180 S0      
317GND              VIA   -    MD0080PA00X+062274Y+108081X0160Y    R180 S0      
317GND              VIA   -    MD0080PA00X+062648Y+107333X0160Y    R270 S0      
317GND              VIA   -    MD0080PA00X+063396Y+117057X0160Y         S0      
317GND              VIA   -    MD0080PA00X+063022Y+117057X0160Y         S0      
317GND              VIA   -    MD0080PA00X+063022Y+116683X0160Y         S0      
317GND              VIA   -    MD0080PA00X+063022Y+115935X0160Y         S0      
317GND              VIA   -    MD0080PA00X+062274Y+117057X0160Y    R180 S0      
317GND              VIA   -    MD0080PA00X+062274Y+116683X0160Y    R180 S0      
317GND              VIA   -    MD0080PA00X+063022Y+115187X0160Y         S0      
317GND              VIA   -    MD0080PA00X+063022Y+115561X0160Y         S0      
317GND              VIA   -    MD0080PA00X+063022Y+114813X0160Y         S0      
317GND              VIA   -    MD0080PA00X+062648Y+114439X0160Y         S0      
317GND              VIA   -    MD0080PA00X+063022Y+114439X0160Y         S0      
317GND              VIA   -    MD0080PA00X+062648Y+113691X0160Y    R270 S0      
317GND              VIA   -    MD0080PA00X+063022Y+113691X0160Y    R270 S0      
317GND              VIA   -    MD0080PA00X+062274Y+112943X0160Y         S0      
317GND              VIA   -    MD0080PA00X+062648Y+112943X0160Y    R270 S0      
317GND              VIA   -    MD0080PA00X+063022Y+112943X0160Y    R270 S0      
317GND              VIA   -    MD0080PA00X+062274Y+114065X0160Y         S0      
317GND              VIA   -    MD0080PA00X+062648Y+114065X0160Y         S0      
317GND              VIA   -    MD0080PA00X+063022Y+114065X0160Y         S0      
317GND              VIA   -    MD0080PA00X+063396Y+113691X0160Y         S0      
317GND              VIA   -    MD0080PA00X+063396Y+113317X0160Y         S0      
317GND              VIA   -    MD0080PA00X+063396Y+112943X0160Y         S0      
317GND              VIA   -    MD0080PA00X+063396Y+112569X0160Y         S0      
317GND              VIA   -    MD0080PA00X+063396Y+114065X0160Y         S0      
317GND              VIA   -    MD0080PA00X+063396Y+112195X0160Y         S0      
317GND              VIA   -    MD0080PA00X+063396Y+111821X0160Y         S0      
317GND              VIA   -    MD0080PA00X+063396Y+111447X0160Y         S0      
317GND              VIA   -    MD0080PA00X+062648Y+112195X0160Y    R090 S0      
317GND              VIA   -    MD0080PA00X+062648Y+111821X0160Y         S0      
317GND              VIA   -    MD0080PA00X+063022Y+111821X0160Y         S0      
317GND              VIA   -    MD0080PA00X+062274Y+111447X0160Y         S0      
317GND              VIA   -    MD0080PA00X+062648Y+111073X0160Y         S0      
317GND              VIA   -    MD0080PA00X+063022Y+111073X0160Y         S0      
317GND              VIA   -    MD0080PA00X+063396Y+111073X0160Y         S0      
317GND              VIA   -    MD0080PA00X+063022Y+110325X0160Y         S0      
317GND              VIA   -    MD0080PA00X+062648Y+109951X0160Y    R270 S0      
317GND              VIA   -    MD0080PA00X+062648Y+109577X0160Y         S0      
317GND              VIA   -    MD0080PA00X+062274Y+110699X0160Y         S0      
317GND              VIA   -    MD0080PA00X+062648Y+110699X0160Y         S0      
317GND              VIA   -    MD0080PA00X+062274Y+110325X0160Y    R180 S0      
317GND              VIA   -    MD0080PA00X+062274Y+109951X0160Y    R180 S0      
317GND              VIA   -    MD0080PA00X+063022Y+109951X0160Y         S0      
317GND              VIA   -    MD0080PA00X+062648Y+109203X0160Y         S0      
317GND              VIA   -    MD0080PA00X+062648Y+108829X0160Y    R180 S0      
317GND              VIA   -    MD0080PA00X+062648Y+107707X0160Y    R270 S0      
317GND              VIA   -    MD0080PA00X+062274Y+117805X0160Y    R180 S0      
317GND              VIA   -    MD0080PA00X+063022Y+118179X0160Y         S0      
317GND              VIA   -    MD0080PA00X+063022Y+117805X0160Y         S0      
317GND              VIA   -    MD0080PA00X+063022Y+117431X0160Y         S0      
317GND              VIA   -    MD0080PA00X+062835Y+118366X0160Y         S0      
317GND              VIA   -    MD0080PA00X+063396Y+118553X0160Y         S0      
317GND              VIA   -    MD0080PA00X+062274Y+117431X0160Y    R180 S0      
317GND              VIA   -    MD0080PA00X+064518Y+113317X0160Y         S0      
317GND              VIA   -    MD0080PA00X+063770Y+112943X0160Y         S0      
317GND              VIA   -    MD0080PA00X+064144Y+112943X0160Y         S0      
317GND              VIA   -    MD0080PA00X+064518Y+112943X0160Y         S0      
317GND              VIA   -    MD0080PA00X+063770Y+112569X0160Y         S0      
317GND              VIA   -    MD0080PA00X+064144Y+112569X0160Y         S0      
317GND              VIA   -    MD0080PA00X+064518Y+112569X0160Y         S0      
317GND              VIA   -    MD0080PA00X+064892Y+112569X0160Y         S0      
317GND              VIA   -    MD0080PA00X+063770Y+114065X0160Y         S0      
317GND              VIA   -    MD0080PA00X+065266Y+113691X0160Y         S0      
317GND              VIA   -    MD0080PA00X+065266Y+112569X0160Y         S0      
317GND              VIA   -    MD0080PA00X+065266Y+112943X0160Y         S0      
317GND              VIA   -    MD0080PA00X+065266Y+113317X0160Y         S0      
317GND              VIA   -    MD0080PA00X+064144Y+114065X0160Y         S0      
317GND              VIA   -    MD0080PA00X+064518Y+114065X0160Y         S0      
317GND              VIA   -    MD0080PA00X+063770Y+113691X0160Y         S0      
317GND              VIA   -    MD0080PA00X+065266Y+112195X0160Y         S0      
317GND              VIA   -    MD0080PA00X+065266Y+111821X0160Y         S0      
317GND              VIA   -    MD0080PA00X+063770Y+111073X0160Y         S0      
317GND              VIA   -    MD0080PA00X+063770Y+112195X0160Y         S0      
317GND              VIA   -    MD0080PA00X+064144Y+112195X0160Y         S0      
317GND              VIA   -    MD0080PA00X+064518Y+112195X0160Y         S0      
317GND              VIA   -    MD0080PA00X+064892Y+112195X0160Y         S0      
317GND              VIA   -    MD0080PA00X+063770Y+111821X0160Y         S0      
317GND              VIA   -    MD0080PA00X+064144Y+111821X0160Y         S0      
317GND              VIA   -    MD0080PA00X+064518Y+111821X0160Y         S0      
317GND              VIA   -    MD0080PA00X+064892Y+111821X0160Y         S0      
317GND              VIA   -    MD0080PA00X+063770Y+111447X0160Y         S0      
317GND              VIA   -    MD0080PA00X+065266Y+120797X0160Y         S0      
317GND              VIA   -    MD0080PA00X+064144Y+120797X0160Y         S0      
317GND              VIA   -    MD0080PA00X+064518Y+120797X0160Y         S0      
317GND              VIA   -    MD0080PA00X+064892Y+120797X0160Y         S0      
317GND              VIA   -    MD0080PA00X+064892Y+121171X0160Y         S0      
317GND              VIA   -    MD0080PA00X+064518Y+121171X0160Y         S0      
317GND              VIA   -    MD0080PA00X+065266Y+119675X0160Y         S0      
317GND              VIA   -    MD0080PA00X+065266Y+120049X0160Y         S0      
317GND              VIA   -    MD0080PA00X+064144Y+119675X0160Y         S0      
317GND              VIA   -    MD0080PA00X+064144Y+119301X0160Y         S0      
317GND              VIA   -    MD0080PA00X+064892Y+120049X0160Y         S0      
317GND              VIA   -    MD0080PA00X+064892Y+119675X0160Y         S0      
317GND              VIA   -    MD0080PA00X+064892Y+120423X0160Y         S0      
317GND              VIA   -    MD0080PA00X+064518Y+120423X0160Y         S0      
317GND              VIA   -    MD0080PA00X+064144Y+120423X0160Y         S0      
317GND              VIA   -    MD0080PA00X+064144Y+120049X0160Y         S0      
317GND              VIA   -    MD0080PA00X+064518Y+120049X0160Y         S0      
317GND              VIA   -    MD0080PA00X+064518Y+119675X0160Y         S0      
317GND              VIA   -    MD0080PA00X+064518Y+119301X0160Y    R270 S0      
317GND              VIA   -    MD0080PA00X+063770Y+119301X0160Y         S0      
317GND              VIA   -    MD0080PA00X+065266Y+120423X0160Y         S0      
317GND              VIA   -    MD0080PA00X+065266Y+119301X0160Y         S0      
317GND              VIA   -    MD0080PA00X+065266Y+117805X0160Y         S0      
317GND              VIA   -    MD0080PA00X+065266Y+118553X0160Y         S0      
317GND              VIA   -    MD0080PA00X+064892Y+117431X0160Y         S0      
317GND              VIA   -    MD0080PA00X+064892Y+118179X0160Y         S0      
317GND              VIA   -    MD0080PA00X+065266Y+118927X0160Y         S0      
317GND              VIA   -    MD0080PA00X+063770Y+118179X0160Y         S0      
317GND              VIA   -    MD0080PA00X+064518Y+117805X0160Y    R270 S0      
317GND              VIA   -    MD0080PA00X+063770Y+117431X0160Y         S0      
317GND              VIA   -    MD0080PA00X+063770Y+117805X0160Y         S0      
317GND              VIA   -    MD0080PA00X+063770Y+118553X0160Y         S0      
317GND              VIA   -    MD0080PA00X+064518Y+118553X0160Y         S0      
317GND              VIA   -    MD0080PA00X+063770Y+118927X0160Y         S0      
317GND              VIA   -    MD0080PA00X+065266Y+117057X0160Y         S0      
317GND              VIA   -    MD0080PA00X+065266Y+115935X0160Y         S0      
317GND              VIA   -    MD0080PA00X+064892Y+116683X0160Y         S0      
317GND              VIA   -    MD0080PA00X+063770Y+117057X0160Y    R270 S0      
317GND              VIA   -    MD0080PA00X+063770Y+115935X0160Y         S0      
317GND              VIA   -    MD0080PA00X+064518Y+115935X0160Y         S0      
317GND              VIA   -    MD0080PA00X+063770Y+116683X0160Y         S0      
317GND              VIA   -    MD0080PA00X+064518Y+117057X0160Y         S0      
317GND              VIA   -    MD0080PA00X+065266Y+114439X0160Y         S0      
317GND              VIA   -    MD0080PA00X+065266Y+115187X0160Y         S0      
317GND              VIA   -    MD0080PA00X+064892Y+114813X0160Y         S0      
317GND              VIA   -    MD0080PA00X+064892Y+115561X0160Y         S0      
317GND              VIA   -    MD0080PA00X+064518Y+115187X0160Y         S0      
317GND              VIA   -    MD0080PA00X+063770Y+114813X0160Y         S0      
317GND              VIA   -    MD0080PA00X+063770Y+114439X0160Y         S0      
317GND              VIA   -    MD0080PA00X+064518Y+114439X0160Y         S0      
317GND              VIA   -    MD0080PA00X+063770Y+115187X0160Y         S0      
317GND              VIA   -    MD0080PA00X+063770Y+115561X0160Y         S0      
317GND              VIA   -    MD0080PA00X+064518Y+113691X0160Y         S0      
317GND              VIA   -    MD0080PA00X+063770Y+113317X0160Y         S0      
317GND              VIA   -    MD0080PA00X+064144Y+113317X0160Y         S0      
317GND              VIA   -    MD0080PA00X+064144Y+121171X0160Y         S0      
317GND              VIA   -    MD0080PA00X+064144Y+121919X0160Y         S0      
317GND              VIA   -    MD0080PA00X+064892Y+121919X0160Y         S0      
317GND              VIA   -    MD0080PA00X+065266Y+121171X0160Y         S0      
317GND              VIA   -    MD0080PA00X+066762Y+117057X0160Y         S0      
317GND              VIA   -    MD0080PA00X+066762Y+115935X0160Y         S0      
317GND              VIA   -    MD0080PA00X+066014Y+117057X0160Y         S0      
317GND              VIA   -    MD0080PA00X+065640Y+116683X0160Y         S0      
317GND              VIA   -    MD0080PA00X+066014Y+115935X0160Y         S0      
317GND              VIA   -    MD0080PA00X+066388Y+116683X0160Y         S0      
317GND              VIA   -    MD0080PA00X+066388Y+115561X0160Y         S0      
317GND              VIA   -    MD0080PA00X+065640Y+115561X0160Y         S0      
317GND              VIA   -    MD0080PA00X+066388Y+114813X0160Y         S0      
317GND              VIA   -    MD0080PA00X+065640Y+114813X0160Y         S0      
317GND              VIA   -    MD0080PA00X+066014Y+114813X0160Y         S0      
317GND              VIA   -    MD0080PA00X+066762Y+114813X0160Y         S0      
317GND              VIA   -    MD0080PA00X+066762Y+112569X0160Y         S0      
317GND              VIA   -    MD0080PA00X+066762Y+114065X0160Y         S0      
317GND              VIA   -    MD0080PA00X+066762Y+113317X0160Y         S0      
317GND              VIA   -    MD0080PA00X+065640Y+113317X0160Y         S0      
317GND              VIA   -    MD0080PA00X+066014Y+113317X0160Y         S0      
317GND              VIA   -    MD0080PA00X+066388Y+113317X0160Y         S0      
317GND              VIA   -    MD0080PA00X+066388Y+112569X0160Y         S0      
317GND              VIA   -    MD0080PA00X+066014Y+112569X0160Y         S0      
317GND              VIA   -    MD0080PA00X+065640Y+112569X0160Y         S0      
317GND              VIA   -    MD0080PA00X+066388Y+114065X0160Y         S0      
317GND              VIA   -    MD0080PA00X+066014Y+114065X0160Y         S0      
317GND              VIA   -    MD0080PA00X+065640Y+114065X0160Y         S0      
317GND              VIA   -    MD0080PA00X+066762Y+112195X0160Y         S0      
317GND              VIA   -    MD0080PA00X+066762Y+111821X0160Y         S0      
317GND              VIA   -    MD0080PA00X+066388Y+112195X0160Y         S0      
317GND              VIA   -    MD0080PA00X+066014Y+112195X0160Y         S0      
317GND              VIA   -    MD0080PA00X+066014Y+111821X0160Y         S0      
317GND              VIA   -    MD0080PA00X+066388Y+111821X0160Y         S0      
317GND              VIA   -    MD0080PA00X+065640Y+112195X0160Y         S0      
317GND              VIA   -    MD0080PA00X+065640Y+111821X0160Y         S0      
317GND              VIA   -    MD0080PA00X+066762Y+121171X0160Y    R090 S0      
317GND              VIA   -    MD0080PA00X+066762Y+120797X0160Y         S0      
317GND              VIA   -    MD0080PA00X+065640Y+120797X0160Y         S0      
317GND              VIA   -    MD0080PA00X+066014Y+120797X0160Y         S0      
317GND              VIA   -    MD0080PA00X+066388Y+120797X0160Y         S0      
317GND              VIA   -    MD0080PA00X+066762Y+120423X0160Y         S0      
317GND              VIA   -    MD0080PA00X+066762Y+119675X0160Y         S0      
317GND              VIA   -    MD0080PA00X+066388Y+120423X0160Y         S0      
317GND              VIA   -    MD0080PA00X+066014Y+120423X0160Y         S0      
317GND              VIA   -    MD0080PA00X+065640Y+120423X0160Y         S0      
317GND              VIA   -    MD0080PA00X+065640Y+119675X0160Y         S0      
317GND              VIA   -    MD0080PA00X+066014Y+119675X0160Y         S0      
317GND              VIA   -    MD0080PA00X+066388Y+119675X0160Y         S0      
317GND              VIA   -    MD0080PA00X+066388Y+117431X0160Y         S0      
317GND              VIA   -    MD0080PA00X+065640Y+117431X0160Y         S0      
317GND              VIA   -    MD0080PA00X+066762Y+118927X0160Y         S0      
317GND              VIA   -    MD0080PA00X+066762Y+118179X0160Y         S0      
317GND              VIA   -    MD0080PA00X+065640Y+118927X0160Y         S0      
317GND              VIA   -    MD0080PA00X+066014Y+118927X0160Y         S0      
317GND              VIA   -    MD0080PA00X+066388Y+118927X0160Y         S0      
317GND              VIA   -    MD0080PA00X+065640Y+118179X0160Y         S0      
317GND              VIA   -    MD0080PA00X+066014Y+118179X0160Y         S0      
317GND              VIA   -    MD0080PA00X+066388Y+118179X0160Y         S0      
317GND              VIA   -    MD0080PA00X+074429Y+110512X0160Y         S0      
317GND              VIA   -    MD0080PA00X+067884Y+115561X0160Y         S0      
317GND              VIA   -    MD0080PA00X+067136Y+115561X0160Y         S0      
317GND              VIA   -    MD0080PA00X+068632Y+115561X0160Y         S0      
317GND              VIA   -    MD0080PA00X+067136Y+114813X0160Y         S0      
317GND              VIA   -    MD0080PA00X+067510Y+114813X0160Y         S0      
317GND              VIA   -    MD0080PA00X+067884Y+114813X0160Y         S0      
317GND              VIA   -    MD0080PA00X+068258Y+114813X0160Y         S0      
317GND              VIA   -    MD0080PA00X+068632Y+114813X0160Y         S0      
317GND              VIA   -    MD0080PA00X+068632Y+112569X0160Y         S0      
317GND              VIA   -    MD0080PA00X+068632Y+114065X0160Y         S0      
317GND              VIA   -    MD0080PA00X+067136Y+113317X0160Y         S0      
317GND              VIA   -    MD0080PA00X+067510Y+113317X0160Y         S0      
317GND              VIA   -    MD0080PA00X+067884Y+113317X0160Y         S0      
317GND              VIA   -    MD0080PA00X+067884Y+112569X0160Y         S0      
317GND              VIA   -    MD0080PA00X+067136Y+112569X0160Y         S0      
317GND              VIA   -    MD0080PA00X+067510Y+112569X0160Y         S0      
317GND              VIA   -    MD0080PA00X+067884Y+114065X0160Y         S0      
317GND              VIA   -    MD0080PA00X+067510Y+114065X0160Y         S0      
317GND              VIA   -    MD0080PA00X+067136Y+114065X0160Y         S0      
317GND              VIA   -    MD0080PA00X+068258Y+112569X0160Y         S0      
317GND              VIA   -    MD0080PA00X+068258Y+114065X0160Y         S0      
317GND              VIA   -    MD0080PA00X+068258Y+113317X0160Y         S0      
317GND              VIA   -    MD0080PA00X+068632Y+111447X0160Y         S0      
317GND              VIA   -    MD0080PA00X+068632Y+111821X0160Y         S0      
317GND              VIA   -    MD0080PA00X+068632Y+112195X0160Y         S0      
317GND              VIA   -    MD0080PA00X+067136Y+112195X0160Y         S0      
317GND              VIA   -    MD0080PA00X+067884Y+112195X0160Y         S0      
317GND              VIA   -    MD0080PA00X+067510Y+112195X0160Y         S0      
317GND              VIA   -    MD0080PA00X+067884Y+111821X0160Y         S0      
317GND              VIA   -    MD0080PA00X+067510Y+111821X0160Y         S0      
317GND              VIA   -    MD0080PA00X+067136Y+111821X0160Y         S0      
317GND              VIA   -    MD0080PA00X+067136Y+111447X0160Y    R180 S0      
317GND              VIA   -    MD0080PA00X+068258Y+112195X0160Y         S0      
317GND              VIA   -    MD0080PA00X+068258Y+111821X0160Y         S0      
317GND              VIA   -    MD0080PA00X+068632Y+120797X0160Y         S0      
317GND              VIA   -    MD0080PA00X+067136Y+120797X0160Y         S0      
317GND              VIA   -    MD0080PA00X+067510Y+120797X0160Y         S0      
317GND              VIA   -    MD0080PA00X+067884Y+120797X0160Y         S0      
317GND              VIA   -    MD0080PA00X+067884Y+121919X0160Y         S0      
317GND              VIA   -    MD0080PA00X+067510Y+121171X0160Y    R090 S0      
317GND              VIA   -    MD0080PA00X+068258Y+120797X0160Y         S0      
317GND              VIA   -    MD0080PA00X+068632Y+120423X0160Y         S0      
317GND              VIA   -    MD0080PA00X+068632Y+119675X0160Y         S0      
317GND              VIA   -    MD0080PA00X+067510Y+120423X0160Y         S0      
317GND              VIA   -    MD0080PA00X+067136Y+120423X0160Y         S0      
317GND              VIA   -    MD0080PA00X+067136Y+119675X0160Y         S0      
317GND              VIA   -    MD0080PA00X+067510Y+119675X0160Y         S0      
317GND              VIA   -    MD0080PA00X+067884Y+119675X0160Y         S0      
317GND              VIA   -    MD0080PA00X+067884Y+120423X0160Y         S0      
317GND              VIA   -    MD0080PA00X+068258Y+120423X0160Y         S0      
317GND              VIA   -    MD0080PA00X+068258Y+119675X0160Y         S0      
317GND              VIA   -    MD0080PA00X+068632Y+117431X0160Y         S0      
317GND              VIA   -    MD0080PA00X+067884Y+117431X0160Y         S0      
317GND              VIA   -    MD0080PA00X+067136Y+117431X0160Y         S0      
317GND              VIA   -    MD0080PA00X+067884Y+118179X0160Y         S0      
317GND              VIA   -    MD0080PA00X+068258Y+118927X0160Y         S0      
317GND              VIA   -    MD0080PA00X+068258Y+118179X0160Y         S0      
317GND              VIA   -    MD0080PA00X+068632Y+118927X0160Y         S0      
317GND              VIA   -    MD0080PA00X+068632Y+118179X0160Y         S0      
317GND              VIA   -    MD0080PA00X+067136Y+118927X0160Y         S0      
317GND              VIA   -    MD0080PA00X+067510Y+118927X0160Y         S0      
317GND              VIA   -    MD0080PA00X+067884Y+118927X0160Y         S0      
317GND              VIA   -    MD0080PA00X+067136Y+118179X0160Y         S0      
317GND              VIA   -    MD0080PA00X+067510Y+118179X0160Y         S0      
317GND              VIA   -    MD0080PA00X+068632Y+116683X0160Y         S0      
317GND              VIA   -    MD0080PA00X+067510Y+115935X0160Y         S0      
317GND              VIA   -    MD0080PA00X+067136Y+116683X0160Y         S0      
317GND              VIA   -    MD0080PA00X+067884Y+116683X0160Y         S0      
317GND              VIA   -    MD0080PA00X+067510Y+117057X0160Y         S0      
317GND              VIA   -    MD0080PA00X+068258Y+115935X0160Y         S0      
317GND              VIA   -    MD0080PA00X+068258Y+117057X0160Y         S0      
317GND              VIA   -    MD0080PA00X+075177Y+110512X0160Y         S0      
317GND              VIA   -    MD0080PA00X+074055Y+109390X0160Y    R180 S0      
317GND              VIA   -    MD0080PA00X+070128Y+121171X0160Y         S0      
317GND              VIA   -    MD0080PA00X+070128Y+120797X0160Y         S0      
317GND              VIA   -    MD0080PA00X+069754Y+121171X0160Y         S0      
317GND              VIA   -    MD0080PA00X+069754Y+120797X0160Y         S0      
317GND              VIA   -    MD0080PA00X+069380Y+120797X0160Y         S0      
317GND              VIA   -    MD0080PA00X+070128Y+120423X0160Y         S0      
317GND              VIA   -    MD0080PA00X+070128Y+119675X0160Y         S0      
317GND              VIA   -    MD0080PA00X+069754Y+119675X0160Y         S0      
317GND              VIA   -    MD0080PA00X+069380Y+119675X0160Y         S0      
317GND              VIA   -    MD0080PA00X+069380Y+120423X0160Y         S0      
317GND              VIA   -    MD0080PA00X+069754Y+120423X0160Y         S0      
317GND              VIA   -    MD0080PA00X+069754Y+117431X0160Y         S0      
317GND              VIA   -    MD0080PA00X+069754Y+118179X0160Y         S0      
317GND              VIA   -    MD0080PA00X+070128Y+118179X0160Y         S0      
317GND              VIA   -    MD0080PA00X+070128Y+118927X0160Y         S0      
317GND              VIA   -    MD0080PA00X+069754Y+118927X0160Y         S0      
317GND              VIA   -    MD0080PA00X+069380Y+118927X0160Y         S0      
317GND              VIA   -    MD0080PA00X+069380Y+118179X0160Y         S0      
317GND              VIA   -    MD0080PA00X+070128Y+117057X0160Y         S0      
317GND              VIA   -    MD0080PA00X+070128Y+115935X0160Y         S0      
317GND              VIA   -    MD0080PA00X+069380Y+115935X0160Y         S0      
317GND              VIA   -    MD0080PA00X+069380Y+117057X0160Y         S0      
317GND              VIA   -    MD0080PA00X+069754Y+116683X0160Y         S0      
317GND              VIA   -    MD0080PA00X+069754Y+115561X0160Y         S0      
317GND              VIA   -    MD0080PA00X+069380Y+114813X0160Y         S0      
317GND              VIA   -    MD0080PA00X+070128Y+114813X0160Y         S0      
317GND              VIA   -    MD0080PA00X+069754Y+114813X0160Y         S0      
317GND              VIA   -    MD0080PA00X+070128Y+113317X0160Y         S0      
317GND              VIA   -    MD0080PA00X+070128Y+114065X0160Y         S0      
317GND              VIA   -    MD0080PA00X+070128Y+112569X0160Y         S0      
317GND              VIA   -    MD0080PA00X+069754Y+112569X0160Y         S0      
317GND              VIA   -    MD0080PA00X+069380Y+112569X0160Y         S0      
317GND              VIA   -    MD0080PA00X+069754Y+114065X0160Y         S0      
317GND              VIA   -    MD0080PA00X+069380Y+114065X0160Y         S0      
317GND              VIA   -    MD0080PA00X+068642Y+113268X0160Y         S0      
317GND              VIA   -    MD0080PA00X+069754Y+113317X0160Y         S0      
317GND              VIA   -    MD0080PA00X+069380Y+113346X0160Y         S0      
317GND              VIA   -    MD0080PA00X+070128Y+112195X0160Y         S0      
317GND              VIA   -    MD0080PA00X+069754Y+112195X0160Y         S0      
317GND              VIA   -    MD0080PA00X+069380Y+112195X0160Y         S0      
317GND              VIA   -    MD0080PA00X+074803Y+109764X0160Y    R180 S0      
317GND              VIA   -    MD0080PA00X+074803Y+109390X0160Y         S0      
317GND              VIA   -    MD0080PA00X+071250Y+112195X0160Y         S0      
317GND              VIA   -    MD0080PA00X+070876Y+112195X0160Y         S0      
317GND              VIA   -    MD0080PA00X+070502Y+112195X0160Y         S0      
317GND              VIA   -    MD0080PA00X+071624Y+112195X0160Y         S0      
317GND              VIA   -    MD0080PA00X+070502Y+120797X0160Y         S0      
317GND              VIA   -    MD0080PA00X+070876Y+120797X0160Y         S0      
317GND              VIA   -    MD0080PA00X+071250Y+121171X0160Y         S0      
317GND              VIA   -    MD0080PA00X+071250Y+120797X0160Y         S0      
317GND              VIA   -    MD0080PA00X+071624Y+120797X0160Y         S0      
317GND              VIA   -    MD0080PA00X+071624Y+121171X0160Y         S0      
317GND              VIA   -    MD0080PA00X+070502Y+120423X0160Y         S0      
317GND              VIA   -    MD0080PA00X+071250Y+120423X0160Y         S0      
317GND              VIA   -    MD0080PA00X+070876Y+120423X0160Y         S0      
317GND              VIA   -    MD0080PA00X+070502Y+119675X0160Y         S0      
317GND              VIA   -    MD0080PA00X+070876Y+119675X0160Y         S0      
317GND              VIA   -    MD0080PA00X+071250Y+119675X0160Y         S0      
317GND              VIA   -    MD0080PA00X+071624Y+120423X0160Y         S0      
317GND              VIA   -    MD0080PA00X+071624Y+119675X0160Y         S0      
317GND              VIA   -    MD0080PA00X+071250Y+117431X0160Y         S0      
317GND              VIA   -    MD0080PA00X+070502Y+117431X0160Y         S0      
317GND              VIA   -    MD0080PA00X+070502Y+118179X0160Y         S0      
317GND              VIA   -    MD0080PA00X+070876Y+118179X0160Y         S0      
317GND              VIA   -    MD0080PA00X+071250Y+118179X0160Y         S0      
317GND              VIA   -    MD0080PA00X+070502Y+118927X0160Y         S0      
317GND              VIA   -    MD0080PA00X+070876Y+118927X0160Y         S0      
317GND              VIA   -    MD0080PA00X+071250Y+118927X0160Y         S0      
317GND              VIA   -    MD0080PA00X+071624Y+118179X0160Y         S0      
317GND              VIA   -    MD0080PA00X+071624Y+118927X0160Y         S0      
317GND              VIA   -    MD0080PA00X+070876Y+117057X0160Y         S0      
317GND              VIA   -    MD0080PA00X+071250Y+116683X0160Y         S0      
317GND              VIA   -    MD0080PA00X+070502Y+116683X0160Y         S0      
317GND              VIA   -    MD0080PA00X+070876Y+115935X0160Y         S0      
317GND              VIA   -    MD0080PA00X+071624Y+115935X0160Y         S0      
317GND              VIA   -    MD0080PA00X+071624Y+117057X0160Y         S0      
317GND              VIA   -    MD0080PA00X+070502Y+115561X0160Y         S0      
317GND              VIA   -    MD0080PA00X+071250Y+115561X0160Y         S0      
317GND              VIA   -    MD0080PA00X+070502Y+114813X0160Y         S0      
317GND              VIA   -    MD0080PA00X+070876Y+114813X0160Y         S0      
317GND              VIA   -    MD0080PA00X+071250Y+114813X0160Y         S0      
317GND              VIA   -    MD0080PA00X+071624Y+114813X0160Y         S0      
317GND              VIA   -    MD0080PA00X+070502Y+113317X0160Y         S0      
317GND              VIA   -    MD0080PA00X+070876Y+113317X0160Y         S0      
317GND              VIA   -    MD0080PA00X+071250Y+113317X0160Y         S0      
317GND              VIA   -    MD0080PA00X+070502Y+114065X0160Y         S0      
317GND              VIA   -    MD0080PA00X+070876Y+114065X0160Y         S0      
317GND              VIA   -    MD0080PA00X+071250Y+114065X0160Y         S0      
317GND              VIA   -    MD0080PA00X+070502Y+112569X0160Y         S0      
317GND              VIA   -    MD0080PA00X+070876Y+112569X0160Y         S0      
317GND              VIA   -    MD0080PA00X+071250Y+112569X0160Y         S0      
317GND              VIA   -    MD0080PA00X+071624Y+113317X0160Y         S0      
317GND              VIA   -    MD0080PA00X+071624Y+112569X0160Y         S0      
317GND              VIA   -    MD0080PA00X+071624Y+114065X0160Y         S0      
317GND              VIA   -    MD0080PA00X+075177Y+110138X0160Y    R270 S0      
317GND              VIA   -    MD0080PA00X+072746Y+117431X0160Y         S0      
317GND              VIA   -    MD0080PA00X+073120Y+118179X0160Y         S0      
317GND              VIA   -    MD0080PA00X+073120Y+117431X0160Y         S0      
317GND              VIA   -    MD0080PA00X+071998Y+118927X0160Y         S0      
317GND              VIA   -    MD0080PA00X+072372Y+118927X0160Y         S0      
317GND              VIA   -    MD0080PA00X+072746Y+117805X0160Y         S0      
317GND              VIA   -    MD0080PA00X+071998Y+117431X0160Y         S0      
317GND              VIA   -    MD0080PA00X+071998Y+118179X0160Y         S0      
317GND              VIA   -    MD0080PA00X+072372Y+118179X0160Y         S0      
317GND              VIA   -    MD0080PA00X+072746Y+118927X0160Y         S0      
317GND              VIA   -    MD0080PA00X+073494Y+117805X0160Y         S0      
317GND              VIA   -    MD0080PA00X+073494Y+118927X0160Y         S0      
317GND              VIA   -    MD0080PA00X+073494Y+118553X0160Y         S0      
317GND              VIA   -    MD0080PA00X+073494Y+118179X0160Y         S0      
317GND              VIA   -    MD0080PA00X+072746Y+118553X0160Y         S0      
317GND              VIA   -    MD0080PA00X+073120Y+116683X0160Y         S0      
317GND              VIA   -    MD0080PA00X+073120Y+115935X0160Y         S0      
317GND              VIA   -    MD0080PA00X+071998Y+116683X0160Y         S0      
317GND              VIA   -    MD0080PA00X+073120Y+117057X0160Y         S0      
317GND              VIA   -    MD0080PA00X+072746Y+115561X0160Y         S0      
317GND              VIA   -    MD0080PA00X+071998Y+115561X0160Y         S0      
317GND              VIA   -    MD0080PA00X+073494Y+114439X0160Y         S0      
317GND              VIA   -    MD0080PA00X+073494Y+114813X0160Y         S0      
317GND              VIA   -    MD0080PA00X+073494Y+115187X0160Y         S0      
317GND              VIA   -    MD0080PA00X+073120Y+115561X0160Y         S0      
317GND              VIA   -    MD0080PA00X+073120Y+115187X0160Y         S0      
317GND              VIA   -    MD0080PA00X+073120Y+114813X0160Y         S0      
317GND              VIA   -    MD0080PA00X+071998Y+114813X0160Y         S0      
317GND              VIA   -    MD0080PA00X+072372Y+114813X0160Y         S0      
317GND              VIA   -    MD0080PA00X+072746Y+114439X0160Y         S0      
317GND              VIA   -    MD0080PA00X+072746Y+114813X0160Y         S0      
317GND              VIA   -    MD0080PA00X+072746Y+115187X0160Y         S0      
317GND              VIA   -    MD0080PA00X+073120Y+112569X0160Y         S0      
317GND              VIA   -    MD0080PA00X+072746Y+113691X0160Y         S0      
317GND              VIA   -    MD0080PA00X+071998Y+113317X0160Y         S0      
317GND              VIA   -    MD0080PA00X+072372Y+113317X0160Y         S0      
317GND              VIA   -    MD0080PA00X+072746Y+113317X0160Y         S0      
317GND              VIA   -    MD0080PA00X+071998Y+114065X0160Y         S0      
317GND              VIA   -    MD0080PA00X+072372Y+114065X0160Y         S0      
317GND              VIA   -    MD0080PA00X+072746Y+112569X0160Y         S0      
317GND              VIA   -    MD0080PA00X+072746Y+112943X0160Y         S0      
317GND              VIA   -    MD0080PA00X+071998Y+112569X0160Y         S0      
317GND              VIA   -    MD0080PA00X+072372Y+112569X0160Y         S0      
317GND              VIA   -    MD0080PA00X+072746Y+114065X0160Y         S0      
317GND              VIA   -    MD0080PA00X+073494Y+113691X0160Y         S0      
317GND              VIA   -    MD0080PA00X+073494Y+113317X0160Y    R180 S0      
317GND              VIA   -    MD0080PA00X+073494Y+114065X0160Y         S0      
317GND              VIA   -    MD0080PA00X+073494Y+112569X0160Y    R180 S0      
317GND              VIA   -    MD0080PA00X+073494Y+112943X0160Y    R270 S0      
317GND              VIA   -    MD0080PA00X+073120Y+111821X0160Y         S0      
317GND              VIA   -    MD0080PA00X+073120Y+112195X0160Y    R180 S0      
317GND              VIA   -    MD0080PA00X+072746Y+111821X0160Y         S0      
317GND              VIA   -    MD0080PA00X+072372Y+112195X0160Y         S0      
317GND              VIA   -    MD0080PA00X+071998Y+112195X0160Y         S0      
317GND              VIA   -    MD0080PA00X+072746Y+112195X0160Y         S0      
317GND              VIA   -    MD0080PA00X+073494Y+111821X0160Y         S0      
317GND              VIA   -    MD0080PA00X+073494Y+112195X0160Y    R270 S0      
317GND              VIA   -    MD0080PA00X+073120Y+120797X0160Y         S0      
317GND              VIA   -    MD0080PA00X+072746Y+121171X0160Y         S0      
317GND              VIA   -    MD0080PA00X+071998Y+120797X0160Y         S0      
317GND              VIA   -    MD0080PA00X+071998Y+121171X0160Y         S0      
317GND              VIA   -    MD0080PA00X+072372Y+120797X0160Y         S0      
317GND              VIA   -    MD0080PA00X+072372Y+121171X0160Y         S0      
317GND              VIA   -    MD0080PA00X+072746Y+120797X0160Y         S0      
317GND              VIA   -    MD0080PA00X+073494Y+121171X0160Y         S0      
317GND              VIA   -    MD0080PA00X+072372Y+120423X0160Y         S0      
317GND              VIA   -    MD0080PA00X+072746Y+120049X0160Y         S0      
317GND              VIA   -    MD0080PA00X+071998Y+119675X0160Y         S0      
317GND              VIA   -    MD0080PA00X+072372Y+119675X0160Y         S0      
317GND              VIA   -    MD0080PA00X+072746Y+119301X0160Y         S0      
317GND              VIA   -    MD0080PA00X+073494Y+119301X0160Y         S0      
317GND              VIA   -    MD0080PA00X+073120Y+120423X0160Y    R180 S0      
317GND              VIA   -    MD0080PA00X+073120Y+119675X0160Y         S0      
317GND              VIA   -    MD0080PA00X+072748Y+119673X0160Y         S0      
317GND              VIA   -    MD0080PA00X+072746Y+120423X0160Y         S0      
317GND              VIA   -    MD0080PA00X+071998Y+120423X0160Y         S0      
317GND              VIA   -    MD0080PA00X+073868Y+115187X0160Y         S0      
317GND              VIA   -    MD0080PA00X+074242Y+115187X0160Y         S0      
317GND              VIA   -    MD0080PA00X+074616Y+115187X0160Y         S0      
317GND              VIA   -    MD0080PA00X+074616Y+115561X0160Y         S0      
317GND              VIA   -    MD0080PA00X+074616Y+114439X0160Y    R270 S0      
317GND              VIA   -    MD0080PA00X+073868Y+114065X0160Y         S0      
317GND              VIA   -    MD0080PA00X+073868Y+113691X0160Y         S0      
317GND              VIA   -    MD0080PA00X+074242Y+119301X0160Y         S0      
317GND              VIA   -    MD0080PA00X+073868Y+119675X0160Y         S0      
317GND              VIA   -    MD0080PA00X+073868Y+119301X0160Y         S0      
317GND              VIA   -    MD0080PA00X+074803Y+119488X0160Y    R090 S0      
317GND              VIA   -    MD0080PA00X+075177Y+119488X0160Y         S0      
317GND              VIA   -    MD0080PA00X+073868Y+120423X0160Y         S0      
317GND              VIA   -    MD0080PA00X+074242Y+118553X0160Y         S0      
317GND              VIA   -    MD0080PA00X+074616Y+117431X0160Y         S0      
317GND              VIA   -    MD0080PA00X+074616Y+117805X0160Y         S0      
317GND              VIA   -    MD0080PA00X+074616Y+118553X0160Y         S0      
317GND              VIA   -    MD0080PA00X+073868Y+118927X0160Y         S0      
317GND              VIA   -    MD0080PA00X+073868Y+118553X0160Y         S0      
317GND              VIA   -    MD0080PA00X+074242Y+118179X0160Y         S0      
317GND              VIA   -    MD0080PA00X+073868Y+117805X0160Y         S0      
317GND              VIA   -    MD0080PA00X+073868Y+117431X0160Y         S0      
317GND              VIA   -    MD0080PA00X+074990Y+117431X0160Y         S0      
317GND              VIA   -    MD0080PA00X+074803Y+119114X0160Y         S0      
317GND              VIA   -    MD0080PA00X+074990Y+118179X0160Y         S0      
317GND              VIA   -    MD0080PA00X+074616Y+115935X0160Y         S0      
317GND              VIA   -    MD0080PA00X+073868Y+117057X0160Y         S0      
317GND              VIA   -    MD0080PA00X+074990Y+115935X0160Y         S0      
317GND              VIA   -    MD0080PA00X+074990Y+116683X0160Y         S0      
317GND              VIA   -    MD0080PA00X+073868Y+115935X0160Y         S0      
317GND              VIA   -    MD0080PA00X+074616Y+116683X0160Y         S0      
317GND              VIA   -    MD0080PA00X+074616Y+117057X0160Y         S0      
317GND              VIA   -    MD0080PA00X+073868Y+116683X0160Y         S0      
317GND              VIA   -    MD0080PA00X+074990Y+115187X0160Y         S0      
317GND              VIA   -    MD0080PA00X+074990Y+114439X0160Y         S0      
317GND              VIA   -    MD0080PA00X+073868Y+114813X0160Y         S0      
317GND              VIA   -    MD0080PA00X+073868Y+115561X0160Y         S0      
317GND              VIA   -    MD0080PA00X+074055Y+109016X0160Y         S0      
317GND              VIA   -    MD0080PA00X+074055Y+107894X0160Y         S0      
317GND              VIA   -    MD0080PA00X+075364Y+115935X0160Y    R090 S0      
317GND              VIA   -    MD0080PA00X+075738Y+115935X0160Y         S0      
317GND              VIA   -    MD0080PA00X+075364Y+116683X0160Y    R090 S0      
317GND              VIA   -    MD0080PA00X+076112Y+117057X0160Y    R090 S0      
317GND              VIA   -    MD0080PA00X+075738Y+117057X0160Y    R090 S0      
317GND              VIA   -    MD0080PA00X+075738Y+116683X0160Y         S0      
317GND              VIA   -    MD0080PA00X+076486Y+117057X0160Y         S0      
317GND              VIA   -    MD0080PA00X+076486Y+115935X0160Y    R270 S0      
317GND              VIA   -    MD0080PA00X+075364Y+115187X0160Y    R090 S0      
317GND              VIA   -    MD0080PA00X+076112Y+115561X0160Y    R090 S0      
317GND              VIA   -    MD0080PA00X+076112Y+114813X0160Y    R090 S0      
317GND              VIA   -    MD0080PA00X+075738Y+115561X0160Y    R180 S0      
317GND              VIA   -    MD0080PA00X+075738Y+115187X0160Y    R270 S0      
317GND              VIA   -    MD0080PA00X+075738Y+114813X0160Y         S0      
317GND              VIA   -    MD0080PA00X+075738Y+114439X0160Y    R270 S0      
317GND              VIA   -    MD0080PA00X+075364Y+114439X0160Y    R090 S0      
317GND              VIA   -    MD0080PA00X+076486Y+114813X0160Y    R270 S0      
317GND              VIA   -    MD0080PA00X+076486Y+115561X0160Y    R270 S0      
317GND              VIA   -    MD0080PA00X+076486Y+114065X0160Y    R270 S0      
317GND              VIA   -    MD0080PA00X+076112Y+114065X0160Y    R090 S0      
317GND              VIA   -    MD0080PA00X+075738Y+114065X0160Y         S0      
317GND              VIA   -    MD0080PA00X+075551Y+119488X0160Y    R090 S0      
317GND              VIA   -    MD0080PA00X+076299Y+119114X0160Y    R090 S0      
317GND              VIA   -    MD0080PA00X+075925Y+119114X0160Y    R090 S0      
317GND              VIA   -    MD0080PA00X+075364Y+118927X0160Y    R090 S0      
317GND              VIA   -    MD0080PA00X+076112Y+118553X0160Y    R090 S0      
317GND              VIA   -    MD0080PA00X+076112Y+117805X0160Y    R090 S0      
317GND              VIA   -    MD0080PA00X+075551Y+118740X0160Y         S0      
317GND              VIA   -    MD0080PA00X+076486Y+117805X0160Y         S0      
317GND              VIA   -    MD0080PA00X+076486Y+118553X0160Y         S0      
317GND              VIA   -    MD0080PA00X+075738Y+118553X0160Y    R090 S0      
317GND              VIA   -    MD0080PA00X+075738Y+118179X0160Y         S0      
317GND              VIA   -    MD0080PA00X+075738Y+117805X0160Y    R090 S0      
317GND              VIA   -    MD0080PA00X+075738Y+117431X0160Y         S0      
317GND              VIA   -    MD0080PA00X+075364Y+117431X0160Y    R090 S0      
317GND              VIA   -    MD0080PA00X+075364Y+118179X0160Y    R090 S0      
317GND              VIA   -    MD0080PA00X+074429Y+108642X0160Y    R270 S0      
317GND              VIA   -    MD0080PA00X+074429Y+109016X0160Y         S0      
317GND              VIA   -    MD0080PA00X+077982Y+114065X0160Y    R180 S0      
317GND              VIA   -    MD0080PA00X+077608Y+114065X0160Y         S0      
317GND              VIA   -    MD0080PA00X+076860Y+117431X0160Y         S0      
317GND              VIA   -    MD0080PA00X+076860Y+118179X0160Y         S0      
317GND              VIA   -    MD0080PA00X+078356Y+117805X0160Y    R180 S0      
317GND              VIA   -    MD0080PA00X+078356Y+118553X0160Y    R180 S0      
317GND              VIA   -    MD0080PA00X+077982Y+117805X0160Y         S0      
317GND              VIA   -    MD0080PA00X+077982Y+118553X0160Y         S0      
317GND              VIA   -    MD0080PA00X+077234Y+118179X0160Y    R090 S0      
317GND              VIA   -    MD0080PA00X+077608Y+118553X0160Y         S0      
317GND              VIA   -    MD0080PA00X+077608Y+118179X0160Y    R270 S0      
317GND              VIA   -    MD0080PA00X+077608Y+117805X0160Y         S0      
317GND              VIA   -    MD0080PA00X+077234Y+117431X0160Y    R090 S0      
317GND              VIA   -    MD0080PA00X+077608Y+117431X0160Y    R270 S0      
317GND              VIA   -    MD0080PA00X+077982Y+117057X0160Y         S0      
317GND              VIA   -    MD0080PA00X+077982Y+116683X0160Y    R270 S0      
317GND              VIA   -    MD0080PA00X+076860Y+116683X0160Y         S0      
317GND              VIA   -    MD0080PA00X+077234Y+115935X0160Y    R090 S0      
317GND              VIA   -    MD0080PA00X+077608Y+115935X0160Y    R270 S0      
317GND              VIA   -    MD0080PA00X+076860Y+115935X0160Y    R090 S0      
317GND              VIA   -    MD0080PA00X+077234Y+116683X0160Y    R090 S0      
317GND              VIA   -    MD0080PA00X+077608Y+117057X0160Y         S0      
317GND              VIA   -    MD0080PA00X+077608Y+116683X0160Y    R270 S0      
317GND              VIA   -    MD0080PA00X+078356Y+116683X0160Y    R270 S0      
317GND              VIA   -    MD0080PA00X+078356Y+117057X0160Y    R180 S0      
317GND              VIA   -    MD0080PA00X+077982Y+114813X0160Y    R180 S0      
317GND              VIA   -    MD0080PA00X+077982Y+115561X0160Y    R180 S0      
317GND              VIA   -    MD0080PA00X+077608Y+114439X0160Y    R270 S0      
317GND              VIA   -    MD0080PA00X+076860Y+114439X0160Y    R090 S0      
317GND              VIA   -    MD0080PA00X+076860Y+115187X0160Y    R090 S0      
317GND              VIA   -    MD0080PA00X+077234Y+114439X0160Y    R090 S0      
317GND              VIA   -    MD0080PA00X+077608Y+115561X0160Y         S0      
317GND              VIA   -    MD0080PA00X+077234Y+115187X0160Y    R090 S0      
317GND              VIA   -    MD0080PA00X+077608Y+115187X0160Y    R270 S0      
317GND              VIA   -    MD0080PA00X+077608Y+114813X0160Y         S0      
317GND              VIA   -    MD0080PA00X+078356Y+114813X0160Y    R180 S0      
317GND              VIA   -    MD0080PA00X+078356Y+115561X0160Y    R180 S0      
317GND              VIA   -    MD0080PA00X+078356Y+114065X0160Y    R180 S0      
317GND              VIA   -    MD0080PA00X+077982Y+119301X0160Y         S0      
317GND              VIA   -    MD0080PA00X+077608Y+119301X0160Y         S0      
317GND              VIA   -    MD0080PA00X+076673Y+119488X0160Y         S0      
317GND              VIA   -    MD0080PA00X+077234Y+119675X0160Y    R090 S0      
317GND              VIA   -    MD0080PA00X+077608Y+119675X0160Y    R270 S0      
317GND              VIA   -    MD0080PA00X+078350Y+119301X0160Y         S0      
317GND              VIA   -    MD0080PA00X+075177Y+108268X0160Y    R180 S0      
317GND              VIA   -    MD0080PA00X+074803Y+107894X0160Y    R180 S0      
317GND              VIA   -    MD0080PA00X+074429Y+108268X0160Y    R180 S0      
317GND              VIA   -    MD0080PA00X+075177Y+109016X0160Y    R180 S0      
317GND              VIA   -    MD0080PA00X+074803Y+109016X0160Y         S0      
317GND              VIA   -    MD0080PA00X+075177Y+108642X0160Y    R180 S0      
317GND              VIA   -    MD0080PA00X+066949Y+108268X0160Y    R270 S0      
317GND              VIA   -    MD0080PA00X+066575Y+107894X0160Y    R270 S0      
317GND              VIA   -    MD0080PA00X+066949Y+108642X0160Y    R270 S0      
317GND              VIA   -    MD0080PA00X+066949Y+109016X0160Y         S0      
317GND              VIA   -    MD0080PA00X+105488Y+117805X0160Y         S0      
317GND              VIA   -    MD0080PA00X+105488Y+117057X0160Y         S0      
317GND              VIA   -    MD0080PA00X+069567Y+109390X0160Y         S0      
317GND              VIA   -    MD0080PA00X+020866Y+125098X0160Y    R270 S0      
317GND              VIA   -    MD0080PA00X+023484Y+109016X0160Y         S0      
317GND              VIA   -    MD0080PA00X+076673Y+109016X0160Y    R270 S0      
317GND              VIA   -    MD0080PA00X+075925Y+108268X0160Y    R180 S0      
317GND              VIA   -    MD0080PA00X+068819Y+109764X0160Y         S0      
317GND              VIA   -    MD0080PA00X+074055Y+109764X0160Y    R270 S0      
317GND              VIA   -    MD0080PA00X+074429Y+110138X0160Y         S0      
317GND              VIA   -    MD0080PA00X+065827Y+109390X0160Y         S0      
317GND              VIA   -    MD0080PA00X+066575Y+109390X0160Y         S0      
317GND              VIA   -    MD0080PA00X+066201Y+110138X0160Y         S0      
317GND              VIA   -    MD0080PA00X+107234Y+108081X0160Y    R180 S0      
317GND              VIA   -    MD0080PA00X+107234Y+108455X0160Y    R180 S0      
317GND              VIA   -    MD0080PA00X+107234Y+108829X0160Y    R180 S0      
317GND              VIA   -    MD0080PA00X+107234Y+116683X0160Y         S0      
317GND              VIA   -    MD0080PA00X+107234Y+115187X0160Y    R270 S0      
317GND              VIA   -    MD0080PA00X+107234Y+115561X0160Y         S0      
317GND              VIA   -    MD0080PA00X+107234Y+112569X0160Y         S0      
317GND              VIA   -    MD0080PA00X+107234Y+112943X0160Y    R180 S0      
317GND              VIA   -    MD0080PA00X+107234Y+114065X0160Y         S0      
317GND              VIA   -    MD0080PA00X+107234Y+111073X0160Y    R180 S0      
317GND              VIA   -    MD0080PA00X+107234Y+111447X0160Y    R180 S0      
317GND              VIA   -    MD0080PA00X+107234Y+111821X0160Y         S0      
317GND              VIA   -    MD0080PA00X+107234Y+112195X0160Y         S0      
317GND              VIA   -    MD0080PA00X+107234Y+110325X0160Y    R180 S0      
317GND              VIA   -    MD0080PA00X+107234Y+110699X0160Y         S0      
317GND              VIA   -    MD0080PA00X+107234Y+109951X0160Y    R180 S0      
317GND              VIA   -    MD0080PA00X+107234Y+117431X0160Y         S0      
317GND              VIA   -    MD0080PA00X+107234Y+118179X0160Y         S0      
327GND              PEX0  -A2         A01X+014882Y+125472X0180Y         S1      
317GND              VIA   -    MD0080PA00X+014882Y+125472X0160Y         S0      
327GND              PEX0  -AB1        A01X+014508Y+117618X0180Y         S1      
327GND              PEX0  -AA3        A01X+015256Y+117992X0180Y         S1      
327GND              PEX0  -AB3 M      A01X+015256Y+117618X0180Y         S1      
327GND              PEX0  -AB2 M      A01X+014882Y+117618X0180Y         S1      
327GND              PEX0  -AA5        A01X+016004Y+117992X0180Y         S1      
327GND              PEX0  -AC4 M      A01X+015630Y+117244X0180Y         S1      
327GND              PEX0  -AC3 M      A01X+015256Y+117244X0180Y         S1      
327GND              PEX0  -AA4        A01X+015630Y+117992X0180Y         S1      
327GND              PEX1  -Y6         A01X+062087Y+118366X0180Y         S1      
327GND              PEX1  -AA4        A01X+061339Y+117992X0180Y         S1      
327GND              PEX1  -Y5         A01X+061713Y+118366X0180Y         S1      
327GND              PEX1  -AY41       A01X+075177Y+110886X0180Y         S1      
327GND              PEX1  -T40        A01X+074803Y+119862X0180Y         S1      
327GND              PEX1  -R40        A01X+074803Y+120236X0180Y         S1      
327GND              PEX1  -P40        A01X+074803Y+120610X0180Y         S1      
327GND              PEX1  -N40        A01X+074803Y+120984X0180Y         S1      
327GND              PEX1  -L40        A01X+074803Y+121732X0180Y         S1      
327GND              PEX1  -K39        A01X+074429Y+122106X0180Y         S1      
327GND              PEX1  -K40        A01X+074803Y+122106X0180Y         S1      
327GND              PEX1  -K38        A01X+074055Y+122106X0180Y         S1      
327GND              PEX1  -K37        A01X+073681Y+122106X0180Y         S1      
327GND              PEX1  -K36        A01X+073307Y+122106X0180Y         S1      
327GND              PEX1  -K35        A01X+072933Y+122106X0180Y         S1      
327GND              PEX1  -K34        A01X+072559Y+122106X0180Y         S1      
327GND              PEX1  -K33        A01X+072185Y+122106X0180Y         S1      
327GND              PEX1  -K32        A01X+071811Y+122106X0180Y         S1      
327GND              PEX1  -K31        A01X+071437Y+122106X0180Y         S1      
327GND              PEX1  -K30        A01X+071063Y+122106X0180Y         S1      
327GND              PEX1  -K29        A01X+070689Y+122106X0180Y         S1      
327GND              PEX1  -K28        A01X+070315Y+122106X0180Y         S1      
327GND              PEX1  -K27        A01X+069941Y+122106X0180Y         S1      
327GND              PEX1  -K26        A01X+069567Y+122106X0180Y         S1      
327GND              PEX1  -K25        A01X+069193Y+122106X0180Y         S1      
327GND              PEX1  -K24        A01X+068819Y+122106X0180Y         S1      
327GND              PEX1  -K23        A01X+068445Y+122106X0180Y         S1      
327GND              PEX1  -K22        A01X+068071Y+122106X0180Y         S1      
327GND              PEX1  -K21        A01X+067697Y+122106X0180Y         S1      
327GND              PEX1  -K20        A01X+067323Y+122106X0180Y         S1      
327GND              PEX1  -K19        A01X+066949Y+122106X0180Y         S1      
327GND              PEX1  -K18        A01X+066575Y+122106X0180Y         S1      
327GND              PEX1  -K17        A01X+066201Y+122106X0180Y         S1      
327GND              PEX1  -K16        A01X+065827Y+122106X0180Y         S1      
327GND              PEX1  -K15        A01X+065453Y+122106X0180Y         S1      
327GND              PEX1  -K14        A01X+065079Y+122106X0180Y         S1      
327GND              PEX1  -K12        A01X+064331Y+122106X0180Y         S1      
327GND              PEX1  -K13        A01X+064705Y+122106X0180Y         S1      
327GND              PEX1  -K11        A01X+063957Y+122106X0180Y         S1      
327GND              PEX1  -K10        A01X+063583Y+122106X0180Y         S1      
327GND              PEX2  -W8         A01X+108543Y+118740X0180Y         S1      
327GND              PEX2  -W9         A01X+108917Y+118740X0180Y         S1      
327GND              PEX2  -Y8         A01X+108543Y+118366X0180Y         S1      
327GND              PEX2  -Y7         A01X+108169Y+118366X0180Y         S1      
327GND              PEX2  -Y6         A01X+107795Y+118366X0180Y         S1      
327GND              PEX2  -Y5         A01X+107421Y+118366X0180Y         S1      
327GND              PEX2  -Y4         A01X+107047Y+118366X0180Y         S1      
327GND              PEX2  -Y3         A01X+106673Y+118366X0180Y         S1      
327GND              PEX2  -Y2         A01X+106299Y+118366X0180Y         S1      
327GND              PEX2  -Y1         A01X+105925Y+118366X0180Y         S1      
327GND              PEX2  -K25        A01X+114902Y+122106X0180Y         S1      
327GND              PEX2  -BA9        A01X+108917Y+110512X0180Y         S1      
327GND              PEX3  -Y1         A01X+151634Y+118366X0180Y         S1      
327GND              PEX3  -Y2         A01X+152008Y+118366X0180Y         S1      
327GND              PEX3  -Y3         A01X+152382Y+118366X0180Y         S1      
327GND              PEX3  -Y4         A01X+152756Y+118366X0180Y         S1      
327GND              PEX3  -Y5         A01X+153130Y+118366X0180Y         S1      
327GND              PEX3  -Y6         A01X+153504Y+118366X0180Y         S1      
327GND              PEX3  -Y7         A01X+153878Y+118366X0180Y         S1      
327GND              PEX3  -Y8         A01X+154252Y+118366X0180Y         S1      
327GND              PEX3  -W8         A01X+154252Y+118740X0180Y         S1      
327GND              PEX3  -W9         A01X+154626Y+118740X0180Y         S1      
327GND              PEX3  -K19        A01X+158366Y+122106X0180Y         S1      
327GND              PEX3  -K18        A01X+157992Y+122106X0180Y         S1      
327GND              PEX3  -K17        A01X+157618Y+122106X0180Y         S1      
327GND              PEX3  -K16        A01X+157244Y+122106X0180Y         S1      
327GND              PEX3  -K15        A01X+156870Y+122106X0180Y         S1      
327GND              PEX3  -K14        A01X+156496Y+122106X0180Y         S1      
327GND              PEX3  -K13        A01X+156122Y+122106X0180Y         S1      
327GND              PEX3  -K12        A01X+155748Y+122106X0180Y         S1      
327GND              PEX3  -K11        A01X+155374Y+122106X0180Y         S1      
327GND              PEX3  -K10        A01X+155000Y+122106X0180Y         S1      
327GND              PEX3  -K20        A01X+158740Y+122106X0180Y         S1      
327GND              PEX3  -K21        A01X+159114Y+122106X0180Y         S1      
327GND              PEX3  -K22        A01X+159488Y+122106X0180Y         S1      
327GND              PEX3  -K23        A01X+159862Y+122106X0180Y         S1      
327GND              PEX3  -K24        A01X+160236Y+122106X0180Y         S1      
327GND              PEX3  -K25        A01X+160610Y+122106X0180Y         S1      
327GND              PEX3  -K26        A01X+160984Y+122106X0180Y         S1      
327GND              PEX3  -K27        A01X+161358Y+122106X0180Y         S1      
327GND              PEX3  -K28        A01X+161732Y+122106X0180Y         S1      
327GND              PEX3  -K29        A01X+162106Y+122106X0180Y         S1      
327GND              PEX3  -K30        A01X+162480Y+122106X0180Y         S1      
327GND              PEX3  -K31        A01X+162854Y+122106X0180Y         S1      
327GND              PEX3  -K32        A01X+163228Y+122106X0180Y         S1      
327GND              PEX3  -K33        A01X+163602Y+122106X0180Y         S1      
327GND              PEX3  -K34        A01X+163976Y+122106X0180Y         S1      
327GND              PEX3  -K35        A01X+164350Y+122106X0180Y         S1      
327GND              PEX3  -K36        A01X+164724Y+122106X0180Y         S1      
327GND              PEX3  -K37        A01X+165098Y+122106X0180Y         S1      
327GND              PEX3  -K38        A01X+165472Y+122106X0180Y         S1      
327GND              PEX3  -K39        A01X+165846Y+122106X0180Y         S1      
327GND              PEX3  -K40        A01X+166220Y+122106X0180Y         S1      
327GND              PEX3  -BA9        A01X+154626Y+110512X0180Y         S1      
327GND              PEX3  -AN41       A01X+166594Y+113504X0180Y         S1      
327GND              PEX3  -AN42       A01X+166968Y+113504X0180Y         S1      
327GND              PEX3  -AN49       A01X+169587Y+113504X0180Y         S1      
327GND              PEX3  -AN48       A01X+169213Y+113504X0180Y         S1      
327GND              PEX3  -AN45       A01X+168090Y+113504X0180Y         S1      
327GND              PEX3  -AP46       A01X+168464Y+113130X0180Y         S1      
327GND              PEX3  -AP47       A01X+168838Y+113130X0180Y         S1      
327GND              PEX3  -AR48       A01X+169213Y+112756X0180Y         S1      
327GND              PEX3  -AR49       A01X+169587Y+112756X0180Y         S1      
327GND              PEX3  -AU49       A01X+169587Y+112008X0180Y         S1      
327GND              PEX3  -AU48       A01X+169213Y+112008X0180Y         S1      
327GND              PEX3  -AT47       A01X+168838Y+112382X0180Y         S1      
327GND              PEX3  -AT46       A01X+168464Y+112382X0180Y         S1      
327GND              PEX3  -AW49       A01X+169587Y+111260X0180Y         S1      
327GND              PEX3  -AW48       A01X+169213Y+111260X0180Y         S1      
327GND              PEX3  -AV47       A01X+168838Y+111634X0180Y         S1      
327GND              PEX3  -AV46       A01X+168464Y+111634X0180Y         S1      
327GND              PEX3  -AY47       A01X+168838Y+110886X0180Y         S1      
327GND              PEX3  -AY46       A01X+168464Y+110886X0180Y         S1      
327GND              PEX3  -BA49       A01X+169587Y+110512X0180Y         S1      
327GND              PEX3  -BA48       A01X+169213Y+110512X0180Y         S1      
327GND              PEX3  -AP44       A01X+167716Y+113130X0180Y         S1      
327GND              PEX3  -AP45       A01X+168090Y+113130X0180Y         S1      
327GND              PEX3  -AR45       A01X+168090Y+112756X0180Y         S1      
327GND              PEX3  -AR41       A01X+166594Y+112756X0180Y         S1      
327GND              PEX3  -AP43       A01X+167342Y+113130X0180Y         S1      
327GND              PEX3  -AR42       A01X+166968Y+112756X0180Y         S1      
327GND              PEX3  -AU45       A01X+168090Y+112008X0180Y         S1      
327GND              PEX3  -AT44       A01X+167716Y+112382X0180Y         S1      
327GND              PEX3  -AT45       A01X+168090Y+112382X0180Y         S1      
327GND              PEX3  -AW45       A01X+168090Y+111260X0180Y         S1      
327GND              PEX3  -AV44       A01X+167716Y+111634X0180Y         S1      
327GND              PEX3  -AV45       A01X+168090Y+111634X0180Y         S1      
327GND              PEX3  -AY45       A01X+168090Y+110886X0180Y         S1      
327GND              PEX3  -AY44       A01X+167716Y+110886X0180Y         S1      
327GND              PEX3  -AU41       A01X+166594Y+112008X0180Y         S1      
327GND              PEX3  -AW41M      A01X+166594Y+111260X0180Y         S1      
327GND              PEX3  -AT43       A01X+167342Y+112382X0180Y         S1      
327GND              PEX3  -AU42       A01X+166968Y+112008X0180Y         S1      
327GND              PEX3  -AW42       A01X+166968Y+111260X0180Y         S1      
327GND              PEX3  -AV43       A01X+167342Y+111634X0180Y         S1      
327GND              PEX3  -AY43       A01X+167342Y+110886X0180Y         S1      
327GND              PEX3  -AY42       A01X+166968Y+110886X0180Y         S1      
327GND              PEX3  -BA47       A01X+168838Y+110512X0180Y         S1      
327GND              PEX3  -BA41       A01X+166594Y+110512X0180Y         S1      
327GND              PEX3  -BA45       A01X+168090Y+110512X0180Y         S1      
327GND              PEX3  -BA43       A01X+167342Y+110512X0180Y         S1      
327GND              PEX3  -BA37       A01X+165098Y+110512X0180Y         S1      
327GND              PEX3  -BA39       A01X+165846Y+110512X0180Y         S1      
327GND              PEX3  -BA35       A01X+164350Y+110512X0180Y         S1      
327GND              PEX3  -BA33       A01X+163602Y+110512X0180Y         S1      
327GND              PEX3  -BA31       A01X+162854Y+110512X0180Y         S1      
327GND              PEX3  -BA29       A01X+162106Y+110512X0180Y         S1      
327GND              PEX3  -BA27       A01X+161358Y+110512X0180Y         S1      
327GND              PEX3  -BA25       A01X+160610Y+110512X0180Y         S1      
327GND              PEX3  -BA23       A01X+159862Y+110512X0180Y         S1      
327GND              PEX3  -BA21       A01X+159114Y+110512X0180Y         S1      
327GND              PEX3  -BA15       A01X+156870Y+110512X0180Y         S1      
327GND              PEX3  -BA19       A01X+158366Y+110512X0180Y         S1      
327GND              PEX3  -BA17       A01X+157618Y+110512X0180Y         S1      
327GND              PEX3  -BA11       A01X+155374Y+110512X0180Y         S1      
327GND              PEX3  -BA13       A01X+156122Y+110512X0180Y         S1      
327GND              PEX3  -BC48       A01X+169213Y+109764X0180Y         S1      
327GND              PEX3  -BC49       A01X+169587Y+109764X0180Y         S1      
327GND              PEX3  -BD49       A01X+169587Y+109390X0180Y         S1      
327GND              PEX3  -BD48       A01X+169213Y+109390X0180Y         S1      
327GND              PEX3  -BB47       A01X+168838Y+110138X0180Y         S1      
327GND              PEX3  -BC46       A01X+168464Y+109764X0180Y         S1      
327GND              PEX3  -BD46       A01X+168464Y+109390X0180Y         S1      
327GND              PEX3  -BH49       A01X+169587Y+107894X0180Y         S1      
327GND              PEX3  -BE47       A01X+168838Y+109016X0180Y         S1      
327GND              PEX3  -BE46       A01X+168464Y+109016X0180Y         S1      
327GND              PEX3  -BF47       A01X+168838Y+108642X0180Y         S1      
327GND              PEX3  -BF48       A01X+169213Y+108642X0180Y         S1      
327GND              PEX3  -BF49       A01X+169587Y+108642X0180Y         S1      
327GND              PEX3  -BG47       A01X+168838Y+108268X0180Y         S1      
327GND              PEX3  -BH46       A01X+168464Y+107894X0180Y         S1      
327GND              PEX3  -BH48       A01X+169213Y+107894X0180Y         S1      
327GND              PEX3  -BJ48       A01X+169213Y+107520X0180Y         S1      
327GND              PEX3  -BJ46       A01X+168464Y+107520X0180Y         S1      
327GND              PEX3  -BB41       A01X+166594Y+110138X0180Y         S1      
327GND              PEX3  -BB43       A01X+167342Y+110138X0180Y         S1      
327GND              PEX3  -BB45       A01X+168090Y+110138X0180Y         S1      
327GND              PEX3  -BC44       A01X+167716Y+109764X0180Y         S1      
327GND              PEX3  -BC42       A01X+166968Y+109764X0180Y         S1      
327GND              PEX3  -BD44       A01X+167716Y+109390X0180Y         S1      
327GND              PEX3  -BD42       A01X+166968Y+109390X0180Y         S1      
327GND              PEX3  -BE41       A01X+166594Y+109016X0180Y         S1      
327GND              PEX3  -BF41       A01X+166594Y+108642X0180Y         S1      
327GND              PEX3  -BG41       A01X+166594Y+108268X0180Y         S1      
327GND              PEX3  -BE45       A01X+168090Y+109016X0180Y         S1      
327GND              PEX3  -BE44       A01X+167716Y+109016X0180Y         S1      
327GND              PEX3  -BE43       A01X+167342Y+109016X0180Y         S1      
327GND              PEX3  -BE42       A01X+166968Y+109016X0180Y         S1      
327GND              PEX3  -BF45       A01X+168090Y+108642X0180Y         S1      
327GND              PEX3  -BF43       A01X+167342Y+108642X0180Y         S1      
327GND              PEX3  -BG43       A01X+167342Y+108268X0180Y         S1      
327GND              PEX3  -BG45       A01X+168090Y+108268X0180Y         S1      
327GND              PEX3  -BH42       A01X+166968Y+107894X0180Y         S1      
327GND              PEX3  -BH44       A01X+167716Y+107894X0180Y         S1      
327GND              PEX3  -BJ44       A01X+167716Y+107520X0180Y         S1      
327GND              PEX3  -BJ42       A01X+166968Y+107520X0180Y         S1      
327GND              PEX3  -BB37       A01X+165098Y+110138X0180Y         S1      
327GND              PEX3  -BC40       A01X+166220Y+109764X0180Y         S1      
327GND              PEX3  -BD40       A01X+166220Y+109390X0180Y         S1      
327GND              PEX3  -BD38       A01X+165472Y+109390X0180Y         S1      
327GND              PEX3  -BB39       A01X+165846Y+110138X0180Y         S1      
327GND              PEX3  -BC38       A01X+165472Y+109764X0180Y         S1      
327GND              PEX3  -BE37       A01X+165098Y+109016X0180Y         S1      
327GND              PEX3  -BF37       A01X+165098Y+108642X0180Y         S1      
327GND              PEX3  -BG37       A01X+165098Y+108268X0180Y         S1      
327GND              PEX3  -BE40       A01X+166220Y+109016X0180Y         S1      
327GND              PEX3  -BH40       A01X+166220Y+107894X0180Y         S1      
327GND              PEX3  -BG39       A01X+165846Y+108268X0180Y         S1      
327GND              PEX3  -BF39       A01X+165846Y+108642X0180Y         S1      
327GND              PEX3  -BE39       A01X+165846Y+109016X0180Y         S1      
327GND              PEX3  -BE38       A01X+165472Y+109016X0180Y         S1      
327GND              PEX3  -BH38       A01X+165472Y+107894X0180Y         S1      
327GND              PEX3  -BJ40       A01X+166220Y+107520X0180Y         S1      
327GND              PEX3  -BJ38       A01X+165472Y+107520X0180Y         S1      
327GND              PEX3  -BC36       A01X+164724Y+109764X0180Y         S1      
327GND              PEX3  -BD36       A01X+164724Y+109390X0180Y         S1      
327GND              PEX3  -BD34       A01X+163976Y+109390X0180Y         S1      
327GND              PEX3  -BC34       A01X+163976Y+109764X0180Y         S1      
327GND              PEX3  -BB35       A01X+164350Y+110138X0180Y         S1      
327GND              PEX3  -BB33       A01X+163602Y+110138X0180Y         S1      
327GND              PEX3  -BE36       A01X+164724Y+109016X0180Y         S1      
327GND              PEX3  -BH36       A01X+164724Y+107894X0180Y         S1      
327GND              PEX3  -BG35       A01X+164350Y+108268X0180Y         S1      
327GND              PEX3  -BF35       A01X+164350Y+108642X0180Y         S1      
327GND              PEX3  -BE35       A01X+164350Y+109016X0180Y         S1      
327GND              PEX3  -BE34       A01X+163976Y+109016X0180Y         S1      
327GND              PEX3  -BF33       A01X+163602Y+108642X0180Y         S1      
327GND              PEX3  -BG33       A01X+163602Y+108268X0180Y         S1      
327GND              PEX3  -BH34       A01X+163976Y+107894X0180Y         S1      
327GND              PEX3  -BE33       A01X+163602Y+109016X0180Y         S1      
327GND              PEX3  -BJ36       A01X+164724Y+107520X0180Y         S1      
327GND              PEX3  -BJ34       A01X+163976Y+107520X0180Y         S1      
327GND              PEX3  -BC28       A01X+161732Y+109764X0180Y         S1      
327GND              PEX3  -BD28       A01X+161732Y+109390X0180Y         S1      
327GND              PEX3  -BD32       A01X+163228Y+109390X0180Y         S1      
327GND              PEX3  -BC32       A01X+163228Y+109764X0180Y         S1      
327GND              PEX3  -BD30       A01X+162480Y+109390X0180Y         S1      
327GND              PEX3  -BC30       A01X+162480Y+109764X0180Y         S1      
327GND              PEX3  -BB31       A01X+162854Y+110138X0180Y         S1      
327GND              PEX3  -BB29       A01X+162106Y+110138X0180Y         S1      
327GND              PEX3  -BE28       A01X+161732Y+109016X0180Y         S1      
327GND              PEX3  -BH28       A01X+161732Y+107894X0180Y         S1      
327GND              PEX3  -BE32       A01X+163228Y+109016X0180Y         S1      
327GND              PEX3  -BE30       A01X+162480Y+109016X0180Y         S1      
327GND              PEX3  -BE31       A01X+162854Y+109016X0180Y         S1      
327GND              PEX3  -BF31       A01X+162854Y+108642X0180Y         S1      
327GND              PEX3  -BG31       A01X+162854Y+108268X0180Y         S1      
327GND              PEX3  -BH32       A01X+163228Y+107894X0180Y         S1      
327GND              PEX3  -BE29       A01X+162106Y+109016X0180Y         S1      
327GND              PEX3  -BF29       A01X+162106Y+108642X0180Y         S1      
327GND              PEX3  -BG29       A01X+162106Y+108268X0180Y         S1      
327GND              PEX3  -BH30       A01X+162480Y+107894X0180Y         S1      
327GND              PEX3  -BJ28       A01X+161732Y+107520X0180Y         S1      
327GND              PEX3  -BJ32       A01X+163228Y+107520X0180Y         S1      
327GND              PEX3  -BJ30       A01X+162480Y+107520X0180Y         S1      
327GND              PEX3  -BC24       A01X+160236Y+109764X0180Y         S1      
327GND              PEX3  -BD24       A01X+160236Y+109390X0180Y         S1      
327GND              PEX3  -BB27       A01X+161358Y+110138X0180Y         S1      
327GND              PEX3  -BC26       A01X+160984Y+109764X0180Y         S1      
327GND              PEX3  -BD26       A01X+160984Y+109390X0180Y         S1      
327GND              PEX3  -BB25       A01X+160610Y+110138X0180Y         S1      
327GND              PEX3  -BH24       A01X+160236Y+107894X0180Y         S1      
327GND              PEX3  -BE24       A01X+160236Y+109016X0180Y         S1      
327GND              PEX3  -BG27       A01X+161358Y+108268X0180Y         S1      
327GND              PEX3  -BH26       A01X+160984Y+107894X0180Y         S1      
327GND              PEX3  -BE25       A01X+160610Y+109016X0180Y         S1      
327GND              PEX3  -BF27       A01X+161358Y+108642X0180Y         S1      
327GND              PEX3  -BE27       A01X+161358Y+109016X0180Y         S1      
327GND              PEX3  -BE26       A01X+160984Y+109016X0180Y         S1      
327GND              PEX3  -BF25       A01X+160610Y+108642X0180Y         S1      
327GND              PEX3  -BG25       A01X+160610Y+108268X0180Y         S1      
327GND              PEX3  -BJ24       A01X+160236Y+107520X0180Y         S1      
327GND              PEX3  -BJ26       A01X+160984Y+107520X0180Y         S1      
327GND              PEX3  -BB23       A01X+159862Y+110138X0180Y         S1      
327GND              PEX3  -BB21       A01X+159114Y+110138X0180Y         S1      
327GND              PEX3  -BC22       A01X+159488Y+109764X0180Y         S1      
327GND              PEX3  -BD22       A01X+159488Y+109390X0180Y         S1      
327GND              PEX3  -BD20       A01X+158740Y+109390X0180Y         S1      
327GND              PEX3  -BC20       A01X+158740Y+109764X0180Y         S1      
327GND              PEX3  -BE23       A01X+159862Y+109016X0180Y         S1      
327GND              PEX3  -BF23       A01X+159862Y+108642X0180Y         S1      
327GND              PEX3  -BG23       A01X+159862Y+108268X0180Y         S1      
327GND              PEX3  -BH22       A01X+159488Y+107894X0180Y         S1      
327GND              PEX3  -BE22       A01X+159488Y+109016X0180Y         S1      
327GND              PEX3  -BE21       A01X+159114Y+109016X0180Y         S1      
327GND              PEX3  -BF21       A01X+159114Y+108642X0180Y         S1      
327GND              PEX3  -BG21       A01X+159114Y+108268X0180Y         S1      
327GND              PEX3  -BH20       A01X+158740Y+107894X0180Y         S1      
327GND              PEX3  -BE20       A01X+158740Y+109016X0180Y         S1      
327GND              PEX3  -BJ22       A01X+159488Y+107520X0180Y         S1      
327GND              PEX3  -BJ20       A01X+158740Y+107520X0180Y         S1      
327GND              PEX3  -BB15       A01X+156870Y+110138X0180Y         S1      
327GND              PEX3  -BB19       A01X+158366Y+110138X0180Y         S1      
327GND              PEX3  -BB17       A01X+157618Y+110138X0180Y         S1      
327GND              PEX3  -BC16       A01X+157244Y+109764X0180Y         S1      
327GND              PEX3  -BC18       A01X+157992Y+109764X0180Y         S1      
327GND              PEX3  -BD16       A01X+157244Y+109390X0180Y         S1      
327GND              PEX3  -BD18       A01X+157992Y+109390X0180Y         S1      
327GND              PEX3  -BE15       A01X+156870Y+109016X0180Y         S1      
327GND              PEX3  -BF15       A01X+156870Y+108642X0180Y         S1      
327GND              PEX3  -BG15       A01X+156870Y+108268X0180Y         S1      
327GND              PEX3  -BH18       A01X+157992Y+107894X0180Y         S1      
327GND              PEX3  -BG19       A01X+158366Y+108268X0180Y         S1      
327GND              PEX3  -BF19       A01X+158366Y+108642X0180Y         S1      
327GND              PEX3  -BE19       A01X+158366Y+109016X0180Y         S1      
327GND              PEX3  -BE18       A01X+157992Y+109016X0180Y         S1      
327GND              PEX3  -BE17       A01X+157618Y+109016X0180Y         S1      
327GND              PEX3  -BF17       A01X+157618Y+108642X0180Y         S1      
327GND              PEX3  -BG17       A01X+157618Y+108268X0180Y         S1      
327GND              PEX3  -BH16       A01X+157244Y+107894X0180Y         S1      
327GND              PEX3  -BE16       A01X+157244Y+109016X0180Y         S1      
327GND              PEX3  -BJ18       A01X+157992Y+107520X0180Y         S1      
327GND              PEX3  -BJ16       A01X+157244Y+107520X0180Y         S1      
327GND              PEX3  -BB11       A01X+155374Y+110138X0180Y         S1      
327GND              PEX3  -BD12       A01X+155748Y+109390X0180Y         S1      
327GND              PEX3  -BC12       A01X+155748Y+109764X0180Y         S1      
327GND              PEX3  -BB13       A01X+156122Y+110138X0180Y         S1      
327GND              PEX3  -BC14       A01X+156496Y+109764X0180Y         S1      
327GND              PEX3  -BD14       A01X+156496Y+109390X0180Y         S1      
327GND              PEX3  -BE11       A01X+155374Y+109016X0180Y         S1      
327GND              PEX3  -BF11       A01X+155374Y+108642X0180Y         S1      
327GND              PEX3  -BG11       A01X+155374Y+108268X0180Y         S1      
327GND              PEX3  -BE12       A01X+155748Y+109016X0180Y         S1      
327GND              PEX3  -BH12       A01X+155748Y+107894X0180Y         S1      
327GND              PEX3  -BH14       A01X+156496Y+107894X0180Y         S1      
327GND              PEX3  -BE14       A01X+156496Y+109016X0180Y         S1      
327GND              PEX3  -BG13       A01X+156122Y+108268X0180Y         S1      
327GND              PEX3  -BE13       A01X+156122Y+109016X0180Y         S1      
327GND              PEX3  -BF13       A01X+156122Y+108642X0180Y         S1      
327GND              PEX3  -BJ12       A01X+155748Y+107520X0180Y         S1      
327GND              PEX3  -BJ14       A01X+156496Y+107520X0180Y         S1      
327GND              PEX3  -BB9        A01X+154626Y+110138X0180Y         S1      
327GND              PEX3  -BC10       A01X+155000Y+109764X0180Y         S1      
327GND              PEX3  -BD10       A01X+155000Y+109390X0180Y         S1      
327GND              PEX3  -BE10       A01X+155000Y+109016X0180Y         S1      
327GND              PEX3  -BE9        A01X+154626Y+109016X0180Y         S1      
327GND              PEX3  -BH10       A01X+155000Y+107894X0180Y         S1      
327GND              PEX3  -BF9        A01X+154626Y+108642X0180Y         S1      
327GND              PEX3  -BG9        A01X+154626Y+108268X0180Y         S1      
327GND              PEX3  -BJ10       A01X+155000Y+107520X0180Y         S1      
327GND              PEX3  -M46        A01X+168464Y+121358X0180Y         S1      
327GND              PEX3  -M47        A01X+168838Y+121358X0180Y         S1      
327GND              PEX3  -N48        A01X+169213Y+120984X0180Y         S1      
327GND              PEX3  -N49        A01X+169587Y+120984X0180Y         S1      
327GND              PEX3  -K46        A01X+168464Y+122106X0180Y         S1      
327GND              PEX3  -K47        A01X+168838Y+122106X0180Y         S1      
327GND              PEX3  -L48        A01X+169213Y+121732X0180Y         S1      
327GND              PEX3  -L49        A01X+169587Y+121732X0180Y         S1      
327GND              PEX3  -P46        A01X+168464Y+120610X0180Y         S1      
327GND              PEX3  -P47        A01X+168838Y+120610X0180Y         S1      
327GND              PEX3  -R48        A01X+169213Y+120236X0180Y         S1      
327GND              PEX3  -R49        A01X+169587Y+120236X0180Y         S1      
327GND              PEX3  -N41        A01X+166594Y+120984X0180Y         S1      
327GND              PEX3  -L41        A01X+166594Y+121732X0180Y         S1      
327GND              PEX3  -K41        A01X+166594Y+122106X0180Y         S1      
327GND              PEX3  -N42        A01X+166968Y+120984X0180Y         S1      
327GND              PEX3  -N45        A01X+168090Y+120984X0180Y         S1      
327GND              PEX3  -M45        A01X+168090Y+121358X0180Y         S1      
327GND              PEX3  -M44        A01X+167716Y+121358X0180Y         S1      
327GND              PEX3  -M43        A01X+167342Y+121358X0180Y         S1      
327GND              PEX3  -L42        A01X+166968Y+121732X0180Y         S1      
327GND              PEX3  -K42        A01X+166968Y+122106X0180Y         S1      
327GND              PEX3  -K43        A01X+167342Y+122106X0180Y         S1      
327GND              PEX3  -K44        A01X+167716Y+122106X0180Y         S1      
327GND              PEX3  -L45        A01X+168090Y+121732X0180Y         S1      
327GND              PEX3  -K45        A01X+168090Y+122106X0180Y         S1      
327GND              PEX3  -R41        A01X+166594Y+120236X0180Y         S1      
327GND              PEX3  -T44        A01X+167716Y+119862X0180Y         S1      
327GND              PEX3  -R45        A01X+168090Y+120236X0180Y         S1      
327GND              PEX3  -R42        A01X+166968Y+120236X0180Y         S1      
327GND              PEX3  -P43        A01X+167342Y+120610X0180Y         S1      
327GND              PEX3  -P44        A01X+167716Y+120610X0180Y         S1      
327GND              PEX3  -P45        A01X+168090Y+120610X0180Y         S1      
327GND              PEX3  -A48        A01X+169213Y+125472X0180Y         S1      
327GND              PEX3  -E47        A01X+168838Y+123976X0180Y         S1      
327GND              PEX3  -E46        A01X+168464Y+123976X0180Y         S1      
327GND              PEX3  -D49        A01X+169587Y+124350X0180Y         S1      
327GND              PEX3  -D48        A01X+169213Y+124350X0180Y         S1      
327GND              PEX3  -D47        A01X+168838Y+124350X0180Y         S1      
327GND              PEX3  -C47        A01X+168838Y+124724X0180Y         S1      
327GND              PEX3  -B48        A01X+169213Y+125098X0180Y         S1      
327GND              PEX3  -B49        A01X+169587Y+125098X0180Y         S1      
327GND              PEX3  -A46        A01X+168464Y+125472X0180Y         S1      
327GND              PEX3  -B46        A01X+168464Y+125098X0180Y         S1      
327GND              PEX3  -F49        A01X+169587Y+123602X0180Y         S1      
327GND              PEX3  -F48        A01X+169213Y+123602X0180Y         S1      
327GND              PEX3  -G48        A01X+169213Y+123228X0180Y         S1      
327GND              PEX3  -G49        A01X+169587Y+123228X0180Y         S1      
327GND              PEX3  -G46        A01X+168464Y+123228X0180Y         S1      
327GND              PEX3  -F46        A01X+168464Y+123602X0180Y         S1      
327GND              PEX3  -H47        A01X+168838Y+122854X0180Y         S1      
327GND              PEX3  -J47        A01X+168838Y+122480X0180Y         S1      
327GND              PEX3  -J48        A01X+169213Y+122480X0180Y         S1      
327GND              PEX3  -J49        A01X+169587Y+122480X0180Y         S1      
327GND              PEX3  -E41        A01X+166594Y+123976X0180Y         S1      
327GND              PEX3  -D41        A01X+166594Y+124350X0180Y         S1      
327GND              PEX3  -C41        A01X+166594Y+124724X0180Y         S1      
327GND              PEX3  -E45        A01X+168090Y+123976X0180Y         S1      
327GND              PEX3  -E44        A01X+167716Y+123976X0180Y         S1      
327GND              PEX3  -E43        A01X+167342Y+123976X0180Y         S1      
327GND              PEX3  -E42        A01X+166968Y+123976X0180Y         S1      
327GND              PEX3  -D45        A01X+168090Y+124350X0180Y         S1      
327GND              PEX3  -C45        A01X+168090Y+124724X0180Y         S1      
327GND              PEX3  -A44        A01X+167716Y+125472X0180Y         S1      
327GND              PEX3  -B44        A01X+167716Y+125098X0180Y         S1      
327GND              PEX3  -D43        A01X+167342Y+124350X0180Y         S1      
327GND              PEX3  -C43        A01X+167342Y+124724X0180Y         S1      
327GND              PEX3  -A42        A01X+166968Y+125472X0180Y         S1      
327GND              PEX3  -B42        A01X+166968Y+125098X0180Y         S1      
327GND              PEX3  -H41        A01X+166594Y+122854X0180Y         S1      
327GND              PEX3  -J41        A01X+166594Y+122480X0180Y         S1      
327GND              PEX3  -F44        A01X+167716Y+123602X0180Y         S1      
327GND              PEX3  -G44        A01X+167716Y+123228X0180Y         S1      
327GND              PEX3  -H45        A01X+168090Y+122854X0180Y         S1      
327GND              PEX3  -J45        A01X+168090Y+122480X0180Y         S1      
327GND              PEX3  -F42        A01X+166968Y+123602X0180Y         S1      
327GND              PEX3  -G42        A01X+166968Y+123228X0180Y         S1      
327GND              PEX3  -H43        A01X+167342Y+122854X0180Y         S1      
327GND              PEX3  -J43        A01X+167342Y+122480X0180Y         S1      
327GND              PEX3  -D37        A01X+165098Y+124350X0180Y         S1      
327GND              PEX3  -E37        A01X+165098Y+123976X0180Y         S1      
327GND              PEX3  -C37        A01X+165098Y+124724X0180Y         S1      
327GND              PEX3  -E40        A01X+166220Y+123976X0180Y         S1      
327GND              PEX3  -D39        A01X+165846Y+124350X0180Y         S1      
327GND              PEX3  -E39        A01X+165846Y+123976X0180Y         S1      
327GND              PEX3  -E38        A01X+165472Y+123976X0180Y         S1      
327GND              PEX3  -A40        A01X+166220Y+125472X0180Y         S1      
327GND              PEX3  -B40        A01X+166220Y+125098X0180Y         S1      
327GND              PEX3  -C39        A01X+165846Y+124724X0180Y         S1      
327GND              PEX3  -A38        A01X+165472Y+125472X0180Y         S1      
327GND              PEX3  -B38        A01X+165472Y+125098X0180Y         S1      
327GND              PEX3  -J37        A01X+165098Y+122480X0180Y         S1      
327GND              PEX3  -H37        A01X+165098Y+122854X0180Y         S1      
327GND              PEX3  -F40        A01X+166220Y+123602X0180Y         S1      
327GND              PEX3  -G40        A01X+166220Y+123228X0180Y         S1      
327GND              PEX3  -J39        A01X+165846Y+122480X0180Y         S1      
327GND              PEX3  -F38        A01X+165472Y+123602X0180Y         S1      
327GND              PEX3  -H39        A01X+165846Y+122854X0180Y         S1      
327GND              PEX3  -G38        A01X+165472Y+123228X0180Y         S1      
327GND              PEX3  -E36        A01X+164724Y+123976X0180Y         S1      
327GND              PEX3  -D35        A01X+164350Y+124350X0180Y         S1      
327GND              PEX3  -D33        A01X+163602Y+124350X0180Y         S1      
327GND              PEX3  -E34        A01X+163976Y+123976X0180Y         S1      
327GND              PEX3  -E35        A01X+164350Y+123976X0180Y         S1      
327GND              PEX3  -E33        A01X+163602Y+123976X0180Y         S1      
327GND              PEX3  -C35        A01X+164350Y+124724X0180Y         S1      
327GND              PEX3  -B36        A01X+164724Y+125098X0180Y         S1      
327GND              PEX3  -A36        A01X+164724Y+125472X0180Y         S1      
327GND              PEX3  -A34        A01X+163976Y+125472X0180Y         S1      
327GND              PEX3  -B34        A01X+163976Y+125098X0180Y         S1      
327GND              PEX3  -C33        A01X+163602Y+124724X0180Y         S1      
327GND              PEX3  -J35        A01X+164350Y+122480X0180Y         S1      
327GND              PEX3  -H35        A01X+164350Y+122854X0180Y         S1      
327GND              PEX3  -F36        A01X+164724Y+123602X0180Y         S1      
327GND              PEX3  -G36        A01X+164724Y+123228X0180Y         S1      
327GND              PEX3  -F34        A01X+163976Y+123602X0180Y         S1      
327GND              PEX3  -G34        A01X+163976Y+123228X0180Y         S1      
327GND              PEX3  -J33        A01X+163602Y+122480X0180Y         S1      
327GND              PEX3  -H33        A01X+163602Y+122854X0180Y         S1      
327GND              PEX3  -A28        A01X+161732Y+125472X0180Y         S1      
327GND              PEX3  -B28        A01X+161732Y+125098X0180Y         S1      
327GND              PEX3  -E28        A01X+161732Y+123976X0180Y         S1      
327GND              PEX3  -E31        A01X+162854Y+123976X0180Y         S1      
327GND              PEX3  -B32        A01X+163228Y+125098X0180Y         S1      
327GND              PEX3  -E32        A01X+163228Y+123976X0180Y         S1      
327GND              PEX3  -D31        A01X+162854Y+124350X0180Y         S1      
327GND              PEX3  -C31        A01X+162854Y+124724X0180Y         S1      
327GND              PEX3  -A30        A01X+162480Y+125472X0180Y         S1      
327GND              PEX3  -B30        A01X+162480Y+125098X0180Y         S1      
327GND              PEX3  -E30        A01X+162480Y+123976X0180Y         S1      
327GND              PEX3  -C29        A01X+162106Y+124724X0180Y         S1      
327GND              PEX3  -D29        A01X+162106Y+124350X0180Y         S1      
327GND              PEX3  -E29        A01X+162106Y+123976X0180Y         S1      
327GND              PEX3  -A32        A01X+163228Y+125472X0180Y         S1      
327GND              PEX3  -F28        A01X+161732Y+123602X0180Y         S1      
327GND              PEX3  -G28        A01X+161732Y+123228X0180Y         S1      
327GND              PEX3  -F30        A01X+162480Y+123602X0180Y         S1      
327GND              PEX3  -F32        A01X+163228Y+123602X0180Y         S1      
327GND              PEX3  -G32        A01X+163228Y+123228X0180Y         S1      
327GND              PEX3  -G30        A01X+162480Y+123228X0180Y         S1      
327GND              PEX3  -J31        A01X+162854Y+122480X0180Y         S1      
327GND              PEX3  -H31        A01X+162854Y+122854X0180Y         S1      
327GND              PEX3  -J29        A01X+162106Y+122480X0180Y         S1      
327GND              PEX3  -H29        A01X+162106Y+122854X0180Y         S1      
327GND              PEX3  -A24        A01X+160236Y+125472X0180Y         S1      
327GND              PEX3  -B24        A01X+160236Y+125098X0180Y         S1      
327GND              PEX3  -E24        A01X+160236Y+123976X0180Y         S1      
327GND              PEX3  -C27        A01X+161358Y+124724X0180Y         S1      
327GND              PEX3  -D27        A01X+161358Y+124350X0180Y         S1      
327GND              PEX3  -E27        A01X+161358Y+123976X0180Y         S1      
327GND              PEX3  -E26        A01X+160984Y+123976X0180Y         S1      
327GND              PEX3  -E25        A01X+160610Y+123976X0180Y         S1      
327GND              PEX3  -D25        A01X+160610Y+124350X0180Y         S1      
327GND              PEX3  -C25        A01X+160610Y+124724X0180Y         S1      
327GND              PEX3  -B26        A01X+160984Y+125098X0180Y         S1      
327GND              PEX3  -A26        A01X+160984Y+125472X0180Y         S1      
327GND              PEX3  -F24        A01X+160236Y+123602X0180Y         S1      
327GND              PEX3  -G24        A01X+160236Y+123228X0180Y         S1      
327GND              PEX3  -J25        A01X+160610Y+122480X0180Y         S1      
327GND              PEX3  -H25        A01X+160610Y+122854X0180Y         S1      
327GND              PEX3  -J27        A01X+161358Y+122480X0180Y         S1      
327GND              PEX3  -H27        A01X+161358Y+122854X0180Y         S1      
327GND              PEX3  -F26        A01X+160984Y+123602X0180Y         S1      
327GND              PEX3  -G26        A01X+160984Y+123228X0180Y         S1      
327GND              PEX3  -E20        A01X+158740Y+123976X0180Y         S1      
327GND              PEX3  -E21        A01X+159114Y+123976X0180Y         S1      
327GND              PEX3  -E22        A01X+159488Y+123976X0180Y         S1      
327GND              PEX3  -A22        A01X+159488Y+125472X0180Y         S1      
327GND              PEX3  -B22        A01X+159488Y+125098X0180Y         S1      
327GND              PEX3  -D21        A01X+159114Y+124350X0180Y         S1      
327GND              PEX3  -C21        A01X+159114Y+124724X0180Y         S1      
327GND              PEX3  -A20        A01X+158740Y+125472X0180Y         S1      
327GND              PEX3  -B20        A01X+158740Y+125098X0180Y         S1      
327GND              PEX3  -C23        A01X+159862Y+124724X0180Y         S1      
327GND              PEX3  -D23        A01X+159862Y+124350X0180Y         S1      
327GND              PEX3  -E23        A01X+159862Y+123976X0180Y         S1      
327GND              PEX3  -F20        A01X+158740Y+123602X0180Y         S1      
327GND              PEX3  -G20        A01X+158740Y+123228X0180Y         S1      
327GND              PEX3  -J21        A01X+159114Y+122480X0180Y         S1      
327GND              PEX3  -H21        A01X+159114Y+122854X0180Y         S1      
327GND              PEX3  -F22        A01X+159488Y+123602X0180Y         S1      
327GND              PEX3  -G22        A01X+159488Y+123228X0180Y         S1      
327GND              PEX3  -J23        A01X+159862Y+122480X0180Y         S1      
327GND              PEX3  -H23        A01X+159862Y+122854X0180Y         S1      
327GND              PEX3  -E15        A01X+156870Y+123976X0180Y         S1      
327GND              PEX3  -D15        A01X+156870Y+124350X0180Y         S1      
327GND              PEX3  -C15        A01X+156870Y+124724X0180Y         S1      
327GND              PEX3  -E17        A01X+157618Y+123976X0180Y         S1      
327GND              PEX3  -E16        A01X+157244Y+123976X0180Y         S1      
327GND              PEX3  -E19        A01X+158366Y+123976X0180Y         S1      
327GND              PEX3  -E18        A01X+157992Y+123976X0180Y         S1      
327GND              PEX3  -B18        A01X+157992Y+125098X0180Y         S1      
327GND              PEX3  -A18        A01X+157992Y+125472X0180Y         S1      
327GND              PEX3  -C19        A01X+158366Y+124724X0180Y         S1      
327GND              PEX3  -D19        A01X+158366Y+124350X0180Y         S1      
327GND              PEX3  -D17        A01X+157618Y+124350X0180Y         S1      
327GND              PEX3  -C17        A01X+157618Y+124724X0180Y         S1      
327GND              PEX3  -A16        A01X+157244Y+125472X0180Y         S1      
327GND              PEX3  -B16        A01X+157244Y+125098X0180Y         S1      
327GND              PEX3  -J15        A01X+156870Y+122480X0180Y         S1      
327GND              PEX3  -H15        A01X+156870Y+122854X0180Y         S1      
327GND              PEX3  -F16        A01X+157244Y+123602X0180Y         S1      
327GND              PEX3  -G16        A01X+157244Y+123228X0180Y         S1      
327GND              PEX3  -H17        A01X+157618Y+122854X0180Y         S1      
327GND              PEX3  -J17        A01X+157618Y+122480X0180Y         S1      
327GND              PEX3  -F18        A01X+157992Y+123602X0180Y         S1      
327GND              PEX3  -G18        A01X+157992Y+123228X0180Y         S1      
327GND              PEX3  -H19        A01X+158366Y+122854X0180Y         S1      
327GND              PEX3  -J19        A01X+158366Y+122480X0180Y         S1      
327GND              PEX3  -D11        A01X+155374Y+124350X0180Y         S1      
327GND              PEX3  -E11        A01X+155374Y+123976X0180Y         S1      
327GND              PEX3  -C11        A01X+155374Y+124724X0180Y         S1      
327GND              PEX3  -D13        A01X+156122Y+124350X0180Y         S1      
327GND              PEX3  -E14        A01X+156496Y+123976X0180Y         S1      
327GND              PEX3  -E13        A01X+156122Y+123976X0180Y         S1      
327GND              PEX3  -E12        A01X+155748Y+123976X0180Y         S1      
327GND              PEX3  -A14        A01X+156496Y+125472X0180Y         S1      
327GND              PEX3  -B14        A01X+156496Y+125098X0180Y         S1      
327GND              PEX3  -C13        A01X+156122Y+124724X0180Y         S1      
327GND              PEX3  -A12        A01X+155748Y+125472X0180Y         S1      
327GND              PEX3  -B12        A01X+155748Y+125098X0180Y         S1      
327GND              PEX3  -J11        A01X+155374Y+122480X0180Y         S1      
327GND              PEX3  -H11        A01X+155374Y+122854X0180Y         S1      
327GND              PEX3  -F12        A01X+155748Y+123602X0180Y         S1      
327GND              PEX3  -G12        A01X+155748Y+123228X0180Y         S1      
327GND              PEX3  -F14        A01X+156496Y+123602X0180Y         S1      
327GND              PEX3  -H13        A01X+156122Y+122854X0180Y         S1      
327GND              PEX3  -J13        A01X+156122Y+122480X0180Y         S1      
327GND              PEX3  -G14        A01X+156496Y+123228X0180Y         S1      
327GND              PEX3  -E10        A01X+155000Y+123976X0180Y         S1      
327GND              PEX3  -A10        A01X+155000Y+125472X0180Y         S1      
327GND              PEX3  -B10        A01X+155000Y+125098X0180Y         S1      
327GND              PEX3  -F10        A01X+155000Y+123602X0180Y         S1      
327GND              PEX3  -G10        A01X+155000Y+123228X0180Y         S1      
327GND              PEX3  -C9         A01X+154626Y+124724X0180Y         S1      
327GND              PEX3  -D9         A01X+154626Y+124350X0180Y         S1      
327GND              PEX3  -E9         A01X+154626Y+123976X0180Y         S1      
327GND              PEX3  -E8         A01X+154252Y+123976X0180Y         S1      
327GND              PEX3  -B8         A01X+154252Y+125098X0180Y         S1      
327GND              PEX3  -D7         A01X+153878Y+124350X0180Y         S1      
327GND              PEX3  -E7         A01X+153878Y+123976X0180Y         S1      
327GND              PEX3  -A8         A01X+154252Y+125472X0180Y         S1      
327GND              PEX3  -C7         A01X+153878Y+124724X0180Y         S1      
327GND              PEX3  -H9         A01X+154626Y+122854X0180Y         S1      
327GND              PEX3  -J9         A01X+154626Y+122480X0180Y         S1      
327GND              PEX3  -J7         A01X+153878Y+122480X0180Y         S1      
327GND              PEX3  -H7         A01X+153878Y+122854X0180Y         S1      
327GND              PEX3  -F8         A01X+154252Y+123602X0180Y         S1      
327GND              PEX3  -G8         A01X+154252Y+123228X0180Y         S1      
327GND              PEX3  -L8         A01X+154252Y+121732X0180Y         S1      
327GND              PEX3  -K8         A01X+154252Y+122106X0180Y         S1      
327GND              PEX3  -K7         A01X+153878Y+122106X0180Y         S1      
327GND              PEX3  -K9         A01X+154626Y+122106X0180Y         S1      
327GND              PEX3  -L9         A01X+154626Y+121732X0180Y         S1      
327GND              PEX3  -D2         A01X+152008Y+124350X0180Y         S1      
327GND              PEX3  -A2         A01X+152008Y+125472X0180Y         S1      
327GND              PEX3  -B2         A01X+152008Y+125098X0180Y         S1      
327GND              PEX3  -D5         A01X+153130Y+124350X0180Y         S1      
327GND              PEX3  -E5         A01X+153130Y+123976X0180Y         S1      
327GND              PEX3  -E6         A01X+153504Y+123976X0180Y         S1      
327GND              PEX3  -E4         A01X+152756Y+123976X0180Y         S1      
327GND              PEX3  -D3         A01X+152382Y+124350X0180Y         S1      
327GND              PEX3  -E3         A01X+152382Y+123976X0180Y         S1      
327GND              PEX3  -A6         A01X+153504Y+125472X0180Y         S1      
327GND              PEX3  -B6         A01X+153504Y+125098X0180Y         S1      
327GND              PEX3  -C5         A01X+153130Y+124724X0180Y         S1      
327GND              PEX3  -C3         A01X+152382Y+124724X0180Y         S1      
327GND              PEX3  -A4         A01X+152756Y+125472X0180Y         S1      
327GND              PEX3  -B4         A01X+152756Y+125098X0180Y         S1      
327GND              PEX3  -J2         A01X+152008Y+122480X0180Y         S1      
327GND              PEX3  -G2         A01X+152008Y+123228X0180Y         S1      
327GND              PEX3  -F2         A01X+152008Y+123602X0180Y         S1      
327GND              PEX3  -F6         A01X+153504Y+123602X0180Y         S1      
327GND              PEX3  -G6         A01X+153504Y+123228X0180Y         S1      
327GND              PEX3  -H5         A01X+153130Y+122854X0180Y         S1      
327GND              PEX3  -J5         A01X+153130Y+122480X0180Y         S1      
327GND              PEX3  -J3         A01X+152382Y+122480X0180Y         S1      
327GND              PEX3  -H3         A01X+152382Y+122854X0180Y         S1      
327GND              PEX3  -G4         A01X+152756Y+123228X0180Y         S1      
327GND              PEX3  -F4         A01X+152756Y+123602X0180Y         S1      
327GND              PEX3  -K4         A01X+152756Y+122106X0180Y         S1      
327GND              PEX3  -K3         A01X+152382Y+122106X0180Y         S1      
327GND              PEX3  -K6         A01X+153504Y+122106X0180Y         S1      
327GND              PEX3  -K5         A01X+153130Y+122106X0180Y         S1      
327GND              PEX3  -B1         A01X+151634Y+125098X0180Y         S1      
327GND              PEX3  -D1         A01X+151634Y+124350X0180Y         S1      
327GND              PEX3  -J1         A01X+151634Y+122480X0180Y         S1      
327GND              PEX3  -F1         A01X+151634Y+123602X0180Y         S1      
327GND              PEX3  -G1         A01X+151634Y+123228X0180Y         S1      
327GND              PEX3  -N9         A01X+154626Y+120984X0180Y         S1      
327GND              PEX3  -N8         A01X+154252Y+120984X0180Y         S1      
327GND              PEX3  -R9         A01X+154626Y+120236X0180Y         S1      
327GND              PEX3  -R8         A01X+154252Y+120236X0180Y         S1      
327GND              PEX3  -U9         A01X+154626Y+119488X0180Y         S1      
327GND              PEX3  -U8         A01X+154252Y+119488X0180Y         S1      
327GND              PEX3  -M7         A01X+153878Y+121358X0180Y         S1      
327GND              PEX3  -V7         A01X+153878Y+119114X0180Y         S1      
327GND              PEX3  -P7         A01X+153878Y+120610X0180Y         S1      
327GND              PEX3  -T7         A01X+153878Y+119862X0180Y         S1      
327GND              PEX3  -L2         A01X+152008Y+121732X0180Y         S1      
327GND              PEX3  -N2         A01X+152008Y+120984X0180Y         S1      
327GND              PEX3  -M3         A01X+152382Y+121358X0180Y         S1      
327GND              PEX3  -M4         A01X+152756Y+121358X0180Y         S1      
327GND              PEX3  -M5         A01X+153130Y+121358X0180Y         S1      
327GND              PEX3  -N5         A01X+153130Y+120984X0180Y         S1      
327GND              PEX3  -M6         A01X+153504Y+121358X0180Y         S1      
327GND              PEX3  -L5         A01X+153130Y+121732X0180Y         S1      
327GND              PEX3  -R2         A01X+152008Y+120236X0180Y         S1      
327GND              PEX3  -U2         A01X+152008Y+119488X0180Y         S1      
327GND              PEX3  -P4         A01X+152756Y+120610X0180Y         S1      
327GND              PEX3  -P3         A01X+152382Y+120610X0180Y         S1      
327GND              PEX3  -T3         A01X+152382Y+119862X0180Y         S1      
327GND              PEX3  -T4         A01X+152756Y+119862X0180Y         S1      
327GND              PEX3  -V3         A01X+152382Y+119114X0180Y         S1      
327GND              PEX3  -V4         A01X+152756Y+119114X0180Y         S1      
327GND              PEX3  -R5         A01X+153130Y+120236X0180Y         S1      
327GND              PEX3  -P6         A01X+153504Y+120610X0180Y         S1      
327GND              PEX3  -P5         A01X+153130Y+120610X0180Y         S1      
327GND              PEX3  -U5         A01X+153130Y+119488X0180Y         S1      
327GND              PEX3  -T5         A01X+153130Y+119862X0180Y         S1      
327GND              PEX3  -T6         A01X+153504Y+119862X0180Y         S1      
327GND              PEX3  -V5         A01X+153130Y+119114X0180Y         S1      
327GND              PEX3  -V6         A01X+153504Y+119114X0180Y         S1      
327GND              PEX3  -W2         A01X+152008Y+118740X0180Y         S1      
327GND              PEX3  -W5         A01X+153130Y+118740X0180Y         S1      
327GND              PEX3  -L1         A01X+151634Y+121732X0180Y         S1      
327GND              PEX3  -N1         A01X+151634Y+120984X0180Y         S1      
327GND              PEX3  -R1         A01X+151634Y+120236X0180Y         S1      
327GND              PEX3  -U1         A01X+151634Y+119488X0180Y         S1      
327GND              PEX3  -W1         A01X+151634Y+118740X0180Y         S1      
327GND              PEX2  -AN49       A01X+123878Y+113504X0180Y         S1      
327GND              PEX2  -AP46       A01X+122756Y+113130X0180Y         S1      
327GND              PEX2  -AP47       A01X+123130Y+113130X0180Y         S1      
327GND              PEX2  -AR48       A01X+123504Y+112756X0180Y         S1      
327GND              PEX2  -AR49       A01X+123878Y+112756X0180Y         S1      
327GND              PEX2  -AU49       A01X+123878Y+112008X0180Y         S1      
327GND              PEX2  -AU48       A01X+123504Y+112008X0180Y         S1      
327GND              PEX2  -AT47       A01X+123130Y+112382X0180Y         S1      
327GND              PEX2  -AT46       A01X+122756Y+112382X0180Y         S1      
327GND              PEX2  -AW49       A01X+123878Y+111260X0180Y         S1      
327GND              PEX2  -AW48       A01X+123504Y+111260X0180Y         S1      
327GND              PEX2  -AV47       A01X+123130Y+111634X0180Y         S1      
327GND              PEX2  -AV46       A01X+122756Y+111634X0180Y         S1      
327GND              PEX2  -AY47       A01X+123130Y+110886X0180Y         S1      
327GND              PEX2  -AY46       A01X+122756Y+110886X0180Y         S1      
327GND              PEX2  -BA49       A01X+123878Y+110512X0180Y         S1      
327GND              PEX2  -BA48       A01X+123504Y+110512X0180Y         S1      
327GND              PEX2  -AP44       A01X+122008Y+113130X0180Y         S1      
327GND              PEX2  -AP45       A01X+122382Y+113130X0180Y         S1      
327GND              PEX2  -AR45       A01X+122382Y+112756X0180Y         S1      
327GND              PEX2  -AR41       A01X+120886Y+112756X0180Y         S1      
327GND              PEX2  -AP43       A01X+121634Y+113130X0180Y         S1      
327GND              PEX2  -AR42       A01X+121260Y+112756X0180Y         S1      
327GND              PEX2  -AU45       A01X+122382Y+112008X0180Y         S1      
327GND              PEX2  -AT44       A01X+122008Y+112382X0180Y         S1      
327GND              PEX2  -AT45       A01X+122382Y+112382X0180Y         S1      
327GND              PEX2  -AW45       A01X+122382Y+111260X0180Y         S1      
327GND              PEX2  -AV44       A01X+122008Y+111634X0180Y         S1      
327GND              PEX2  -AV45       A01X+122382Y+111634X0180Y         S1      
327GND              PEX2  -AY45       A01X+122382Y+110886X0180Y         S1      
327GND              PEX2  -AY44       A01X+122008Y+110886X0180Y         S1      
327GND              PEX2  -AU41       A01X+120886Y+112008X0180Y         S1      
327GND              PEX2  -AW41M      A01X+120886Y+111260X0180Y         S1      
327GND              PEX2  -AT43       A01X+121634Y+112382X0180Y         S1      
327GND              PEX2  -AU42       A01X+121260Y+112008X0180Y         S1      
327GND              PEX2  -AV43       A01X+121634Y+111634X0180Y         S1      
327GND              PEX2  -AY43       A01X+121634Y+110886X0180Y         S1      
327GND              PEX2  -AY42       A01X+121260Y+110886X0180Y         S1      
327GND              PEX2  -BA47       A01X+123130Y+110512X0180Y         S1      
327GND              PEX2  -BA41       A01X+120886Y+110512X0180Y         S1      
327GND              PEX2  -BA45       A01X+122382Y+110512X0180Y         S1      
327GND              PEX2  -BA43       A01X+121634Y+110512X0180Y         S1      
327GND              PEX2  -BA37       A01X+119390Y+110512X0180Y         S1      
327GND              PEX2  -BA39       A01X+120138Y+110512X0180Y         S1      
327GND              PEX2  -BA35       A01X+118642Y+110512X0180Y         S1      
327GND              PEX2  -BA33       A01X+117894Y+110512X0180Y         S1      
327GND              PEX2  -BA31       A01X+117146Y+110512X0180Y         S1      
327GND              PEX2  -BA29       A01X+116398Y+110512X0180Y         S1      
327GND              PEX2  -BA27       A01X+115650Y+110512X0180Y         S1      
327GND              PEX2  -BA25       A01X+114902Y+110512X0180Y         S1      
327GND              PEX2  -BA23       A01X+114154Y+110512X0180Y         S1      
327GND              PEX2  -BA21       A01X+113405Y+110512X0180Y         S1      
327GND              PEX2  -BA15       A01X+111161Y+110512X0180Y         S1      
327GND              PEX2  -BA19       A01X+112657Y+110512X0180Y         S1      
327GND              PEX2  -BA17       A01X+111909Y+110512X0180Y         S1      
327GND              PEX2  -BA11       A01X+109665Y+110512X0180Y         S1      
327GND              PEX2  -BA13       A01X+110413Y+110512X0180Y         S1      
327GND              PEX2  -BC48       A01X+123504Y+109764X0180Y         S1      
327GND              PEX2  -BC49       A01X+123878Y+109764X0180Y         S1      
327GND              PEX2  -BD49       A01X+123878Y+109390X0180Y         S1      
327GND              PEX2  -BD48       A01X+123504Y+109390X0180Y         S1      
327GND              PEX2  -BB47       A01X+123130Y+110138X0180Y         S1      
327GND              PEX2  -BC46       A01X+122756Y+109764X0180Y         S1      
327GND              PEX2  -BD46       A01X+122756Y+109390X0180Y         S1      
327GND              PEX2  -BH49       A01X+123878Y+107894X0180Y         S1      
327GND              PEX2  -BE47       A01X+123130Y+109016X0180Y         S1      
327GND              PEX2  -BE46       A01X+122756Y+109016X0180Y         S1      
327GND              PEX2  -BF47       A01X+123130Y+108642X0180Y         S1      
327GND              PEX2  -BF48       A01X+123504Y+108642X0180Y         S1      
327GND              PEX2  -BF49       A01X+123878Y+108642X0180Y         S1      
327GND              PEX2  -BG47       A01X+123130Y+108268X0180Y         S1      
327GND              PEX2  -BH46       A01X+122756Y+107894X0180Y         S1      
327GND              PEX2  -BH48       A01X+123504Y+107894X0180Y         S1      
327GND              PEX2  -BJ48       A01X+123504Y+107520X0180Y         S1      
327GND              PEX2  -BJ46       A01X+122756Y+107520X0180Y         S1      
327GND              PEX2  -BB41       A01X+120886Y+110138X0180Y         S1      
327GND              PEX2  -BB43       A01X+121634Y+110138X0180Y         S1      
327GND              PEX2  -BB45       A01X+122382Y+110138X0180Y         S1      
327GND              PEX2  -BC44       A01X+122008Y+109764X0180Y         S1      
327GND              PEX2  -BC42       A01X+121260Y+109764X0180Y         S1      
327GND              PEX2  -BD44       A01X+122008Y+109390X0180Y         S1      
327GND              PEX2  -BD42       A01X+121260Y+109390X0180Y         S1      
327GND              PEX2  -BE41       A01X+120886Y+109016X0180Y         S1      
327GND              PEX2  -BF41       A01X+120886Y+108642X0180Y         S1      
327GND              PEX2  -BG41       A01X+120886Y+108268X0180Y         S1      
327GND              PEX2  -BE45       A01X+122382Y+109016X0180Y         S1      
327GND              PEX2  -BE44       A01X+122008Y+109016X0180Y         S1      
327GND              PEX2  -BE43       A01X+121634Y+109016X0180Y         S1      
327GND              PEX2  -BE42       A01X+121260Y+109016X0180Y         S1      
327GND              PEX2  -BF45       A01X+122382Y+108642X0180Y         S1      
327GND              PEX2  -BF43       A01X+121634Y+108642X0180Y         S1      
327GND              PEX2  -BG43       A01X+121634Y+108268X0180Y         S1      
327GND              PEX2  -BG45       A01X+122382Y+108268X0180Y         S1      
327GND              PEX2  -BH42       A01X+121260Y+107894X0180Y         S1      
327GND              PEX2  -BH44       A01X+122008Y+107894X0180Y         S1      
327GND              PEX2  -BJ44       A01X+122008Y+107520X0180Y         S1      
327GND              PEX2  -BJ42       A01X+121260Y+107520X0180Y         S1      
327GND              PEX2  -BB37       A01X+119390Y+110138X0180Y         S1      
327GND              PEX2  -BC40       A01X+120512Y+109764X0180Y         S1      
327GND              PEX2  -BD40       A01X+120512Y+109390X0180Y         S1      
327GND              PEX2  -BD38       A01X+119764Y+109390X0180Y         S1      
327GND              PEX2  -BB39       A01X+120138Y+110138X0180Y         S1      
327GND              PEX2  -BC38       A01X+119764Y+109764X0180Y         S1      
327GND              PEX2  -BE37       A01X+119390Y+109016X0180Y         S1      
327GND              PEX2  -BF37       A01X+119390Y+108642X0180Y         S1      
327GND              PEX2  -BG37       A01X+119390Y+108268X0180Y         S1      
327GND              PEX2  -BE40       A01X+120512Y+109016X0180Y         S1      
327GND              PEX2  -BH40       A01X+120512Y+107894X0180Y         S1      
327GND              PEX2  -BG39       A01X+120138Y+108268X0180Y         S1      
327GND              PEX2  -BF39       A01X+120138Y+108642X0180Y         S1      
327GND              PEX2  -BE39       A01X+120138Y+109016X0180Y         S1      
327GND              PEX2  -BE38       A01X+119764Y+109016X0180Y         S1      
327GND              PEX2  -BH38       A01X+119764Y+107894X0180Y         S1      
327GND              PEX2  -BJ40       A01X+120512Y+107520X0180Y         S1      
327GND              PEX2  -BJ38       A01X+119764Y+107520X0180Y         S1      
327GND              PEX2  -BC36       A01X+119016Y+109764X0180Y         S1      
327GND              PEX2  -BD36       A01X+119016Y+109390X0180Y         S1      
327GND              PEX2  -BD34       A01X+118268Y+109390X0180Y         S1      
327GND              PEX2  -BC34       A01X+118268Y+109764X0180Y         S1      
327GND              PEX2  -BB35       A01X+118642Y+110138X0180Y         S1      
327GND              PEX2  -BB33       A01X+117894Y+110138X0180Y         S1      
327GND              PEX2  -BE36       A01X+119016Y+109016X0180Y         S1      
327GND              PEX2  -BH36       A01X+119016Y+107894X0180Y         S1      
327GND              PEX2  -BG35       A01X+118642Y+108268X0180Y         S1      
327GND              PEX2  -BF35       A01X+118642Y+108642X0180Y         S1      
327GND              PEX2  -BE35       A01X+118642Y+109016X0180Y         S1      
327GND              PEX2  -BE34       A01X+118268Y+109016X0180Y         S1      
327GND              PEX2  -BF33       A01X+117894Y+108642X0180Y         S1      
327GND              PEX2  -BG33       A01X+117894Y+108268X0180Y         S1      
327GND              PEX2  -BH34       A01X+118268Y+107894X0180Y         S1      
327GND              PEX2  -BE33       A01X+117894Y+109016X0180Y         S1      
327GND              PEX2  -BJ36       A01X+119016Y+107520X0180Y         S1      
327GND              PEX2  -BJ34       A01X+118268Y+107520X0180Y         S1      
327GND              PEX2  -BC28       A01X+116024Y+109764X0180Y         S1      
327GND              PEX2  -BD28       A01X+116024Y+109390X0180Y         S1      
327GND              PEX2  -BD32       A01X+117520Y+109390X0180Y         S1      
327GND              PEX2  -BC32       A01X+117520Y+109764X0180Y         S1      
327GND              PEX2  -BD30       A01X+116772Y+109390X0180Y         S1      
327GND              PEX2  -BC30       A01X+116772Y+109764X0180Y         S1      
327GND              PEX2  -BB31       A01X+117146Y+110138X0180Y         S1      
327GND              PEX2  -BB29       A01X+116398Y+110138X0180Y         S1      
327GND              PEX2  -BE28       A01X+116024Y+109016X0180Y         S1      
327GND              PEX2  -BH28       A01X+116024Y+107894X0180Y         S1      
327GND              PEX2  -BE32       A01X+117520Y+109016X0180Y         S1      
327GND              PEX2  -BE30       A01X+116772Y+109016X0180Y         S1      
327GND              PEX2  -BE31       A01X+117146Y+109016X0180Y         S1      
327GND              PEX2  -BF31       A01X+117146Y+108642X0180Y         S1      
327GND              PEX2  -BG31       A01X+117146Y+108268X0180Y         S1      
327GND              PEX2  -BH32       A01X+117520Y+107894X0180Y         S1      
327GND              PEX2  -BE29       A01X+116398Y+109016X0180Y         S1      
327GND              PEX2  -BF29       A01X+116398Y+108642X0180Y         S1      
327GND              PEX2  -BG29       A01X+116398Y+108268X0180Y         S1      
327GND              PEX2  -BH30       A01X+116772Y+107894X0180Y         S1      
327GND              PEX2  -BJ28       A01X+116024Y+107520X0180Y         S1      
327GND              PEX2  -BJ32       A01X+117520Y+107520X0180Y         S1      
327GND              PEX2  -BJ30       A01X+116772Y+107520X0180Y         S1      
327GND              PEX2  -BC24       A01X+114528Y+109764X0180Y         S1      
327GND              PEX2  -BD24       A01X+114528Y+109390X0180Y         S1      
327GND              PEX2  -BB27       A01X+115650Y+110138X0180Y         S1      
327GND              PEX2  -BC26       A01X+115276Y+109764X0180Y         S1      
327GND              PEX2  -BD26       A01X+115276Y+109390X0180Y         S1      
327GND              PEX2  -BB25       A01X+114902Y+110138X0180Y         S1      
327GND              PEX2  -BH24       A01X+114528Y+107894X0180Y         S1      
327GND              PEX2  -BE24       A01X+114528Y+109016X0180Y         S1      
327GND              PEX2  -BG27       A01X+115650Y+108268X0180Y         S1      
327GND              PEX2  -BH26       A01X+115276Y+107894X0180Y         S1      
327GND              PEX2  -BE25       A01X+114902Y+109016X0180Y         S1      
327GND              PEX2  -BF27       A01X+115650Y+108642X0180Y         S1      
327GND              PEX2  -BE27       A01X+115650Y+109016X0180Y         S1      
327GND              PEX2  -BE26       A01X+115276Y+109016X0180Y         S1      
327GND              PEX2  -BF25       A01X+114902Y+108642X0180Y         S1      
327GND              PEX2  -BG25       A01X+114902Y+108268X0180Y         S1      
327GND              PEX2  -BJ24       A01X+114528Y+107520X0180Y         S1      
327GND              PEX2  -BJ26       A01X+115276Y+107520X0180Y         S1      
327GND              PEX2  -BB23       A01X+114154Y+110138X0180Y         S1      
327GND              PEX2  -BB21       A01X+113405Y+110138X0180Y         S1      
327GND              PEX2  -BC22       A01X+113780Y+109764X0180Y         S1      
327GND              PEX2  -BD22       A01X+113780Y+109390X0180Y         S1      
327GND              PEX2  -BD20       A01X+113031Y+109390X0180Y         S1      
327GND              PEX2  -BC20       A01X+113031Y+109764X0180Y         S1      
327GND              PEX2  -BE23       A01X+114154Y+109016X0180Y         S1      
327GND              PEX2  -BF23       A01X+114154Y+108642X0180Y         S1      
327GND              PEX2  -BG23       A01X+114154Y+108268X0180Y         S1      
327GND              PEX2  -BH22       A01X+113780Y+107894X0180Y         S1      
327GND              PEX2  -BE22       A01X+113780Y+109016X0180Y         S1      
327GND              PEX2  -BE21       A01X+113405Y+109016X0180Y         S1      
327GND              PEX2  -BF21       A01X+113405Y+108642X0180Y         S1      
327GND              PEX2  -BG21       A01X+113405Y+108268X0180Y         S1      
327GND              PEX2  -BH20       A01X+113031Y+107894X0180Y         S1      
327GND              PEX2  -BE20       A01X+113031Y+109016X0180Y         S1      
327GND              PEX2  -BJ22       A01X+113780Y+107520X0180Y         S1      
327GND              PEX2  -BJ20       A01X+113031Y+107520X0180Y         S1      
327GND              PEX2  -BB15       A01X+111161Y+110138X0180Y         S1      
327GND              PEX2  -BB19       A01X+112657Y+110138X0180Y         S1      
327GND              PEX2  -BB17       A01X+111909Y+110138X0180Y         S1      
327GND              PEX2  -BC16       A01X+111535Y+109764X0180Y         S1      
327GND              PEX2  -BC18       A01X+112283Y+109764X0180Y         S1      
327GND              PEX2  -BD16       A01X+111535Y+109390X0180Y         S1      
327GND              PEX2  -BD18       A01X+112283Y+109390X0180Y         S1      
327GND              PEX2  -BE15       A01X+111161Y+109016X0180Y         S1      
327GND              PEX2  -BF15       A01X+111161Y+108642X0180Y         S1      
327GND              PEX2  -BG15       A01X+111161Y+108268X0180Y         S1      
327GND              PEX2  -BH18       A01X+112283Y+107894X0180Y         S1      
327GND              PEX2  -BG19       A01X+112657Y+108268X0180Y         S1      
327GND              PEX2  -BF19       A01X+112657Y+108642X0180Y         S1      
327GND              PEX2  -BE19       A01X+112657Y+109016X0180Y         S1      
327GND              PEX2  -BE18       A01X+112283Y+109016X0180Y         S1      
327GND              PEX2  -BE17       A01X+111909Y+109016X0180Y         S1      
327GND              PEX2  -BF17       A01X+111909Y+108642X0180Y         S1      
327GND              PEX2  -BG17       A01X+111909Y+108268X0180Y         S1      
327GND              PEX2  -BH16       A01X+111535Y+107894X0180Y         S1      
327GND              PEX2  -BE16       A01X+111535Y+109016X0180Y         S1      
327GND              PEX2  -BJ18       A01X+112283Y+107520X0180Y         S1      
327GND              PEX2  -BJ16       A01X+111535Y+107520X0180Y         S1      
327GND              PEX2  -BB11       A01X+109665Y+110138X0180Y         S1      
327GND              PEX2  -BD12       A01X+110039Y+109390X0180Y         S1      
327GND              PEX2  -BC12       A01X+110039Y+109764X0180Y         S1      
327GND              PEX2  -BB13       A01X+110413Y+110138X0180Y         S1      
327GND              PEX2  -BC14       A01X+110787Y+109764X0180Y         S1      
327GND              PEX2  -BD14       A01X+110787Y+109390X0180Y         S1      
327GND              PEX2  -BE11       A01X+109665Y+109016X0180Y         S1      
327GND              PEX2  -BF11       A01X+109665Y+108642X0180Y         S1      
327GND              PEX2  -BG11       A01X+109665Y+108268X0180Y         S1      
327GND              PEX2  -BE12       A01X+110039Y+109016X0180Y         S1      
327GND              PEX2  -BH12       A01X+110039Y+107894X0180Y         S1      
327GND              PEX2  -BH14       A01X+110787Y+107894X0180Y         S1      
327GND              PEX2  -BE14       A01X+110787Y+109016X0180Y         S1      
327GND              PEX2  -BG13       A01X+110413Y+108268X0180Y         S1      
327GND              PEX2  -BE13       A01X+110413Y+109016X0180Y         S1      
327GND              PEX2  -BF13       A01X+110413Y+108642X0180Y         S1      
327GND              PEX2  -BJ12       A01X+110039Y+107520X0180Y         S1      
327GND              PEX2  -BJ14       A01X+110787Y+107520X0180Y         S1      
327GND              PEX2  -BB9        A01X+108917Y+110138X0180Y         S1      
327GND              PEX2  -BC10       A01X+109291Y+109764X0180Y         S1      
327GND              PEX2  -BD10       A01X+109291Y+109390X0180Y         S1      
327GND              PEX2  -BE10       A01X+109291Y+109016X0180Y         S1      
327GND              PEX2  -BE9        A01X+108917Y+109016X0180Y         S1      
327GND              PEX2  -BH10       A01X+109291Y+107894X0180Y         S1      
327GND              PEX2  -BF9        A01X+108917Y+108642X0180Y         S1      
327GND              PEX2  -BG9        A01X+108917Y+108268X0180Y         S1      
327GND              PEX2  -BJ10       A01X+109291Y+107520X0180Y         S1      
327GND              PEX2  -M46        A01X+122756Y+121358X0180Y         S1      
327GND              PEX2  -M47        A01X+123130Y+121358X0180Y         S1      
327GND              PEX2  -N48        A01X+123504Y+120984X0180Y         S1      
327GND              PEX2  -N49        A01X+123878Y+120984X0180Y         S1      
327GND              PEX2  -K46        A01X+122756Y+122106X0180Y         S1      
327GND              PEX2  -K47        A01X+123130Y+122106X0180Y         S1      
327GND              PEX2  -L48        A01X+123504Y+121732X0180Y         S1      
327GND              PEX2  -L49        A01X+123878Y+121732X0180Y         S1      
327GND              PEX2  -T46        A01X+122756Y+119862X0180Y         S1      
327GND              PEX2  -T47        A01X+123130Y+119862X0180Y         S1      
327GND              PEX2  -P46        A01X+122756Y+120610X0180Y         S1      
327GND              PEX2  -P47        A01X+123130Y+120610X0180Y         S1      
327GND              PEX2  -R48        A01X+123504Y+120236X0180Y         S1      
327GND              PEX2  -R49        A01X+123878Y+120236X0180Y         S1      
327GND              PEX2  -N41        A01X+120886Y+120984X0180Y         S1      
327GND              PEX2  -L41        A01X+120886Y+121732X0180Y         S1      
327GND              PEX2  -K41        A01X+120886Y+122106X0180Y         S1      
327GND              PEX2  -N42        A01X+121260Y+120984X0180Y         S1      
327GND              PEX2  -N45        A01X+122382Y+120984X0180Y         S1      
327GND              PEX2  -M45        A01X+122382Y+121358X0180Y         S1      
327GND              PEX2  -M44        A01X+122008Y+121358X0180Y         S1      
327GND              PEX2  -M43        A01X+121634Y+121358X0180Y         S1      
327GND              PEX2  -L42        A01X+121260Y+121732X0180Y         S1      
327GND              PEX2  -K42        A01X+121260Y+122106X0180Y         S1      
327GND              PEX2  -K43        A01X+121634Y+122106X0180Y         S1      
327GND              PEX2  -K44        A01X+122008Y+122106X0180Y         S1      
327GND              PEX2  -L45        A01X+122382Y+121732X0180Y         S1      
327GND              PEX2  -K45        A01X+122382Y+122106X0180Y         S1      
327GND              PEX2  -R41        A01X+120886Y+120236X0180Y         S1      
327GND              PEX2  -T43        A01X+121634Y+119862X0180Y         S1      
327GND              PEX2  -T44        A01X+122008Y+119862X0180Y         S1      
327GND              PEX2  -T45        A01X+122382Y+119862X0180Y         S1      
327GND              PEX2  -R45        A01X+122382Y+120236X0180Y         S1      
327GND              PEX2  -R42        A01X+121260Y+120236X0180Y         S1      
327GND              PEX2  -P43        A01X+121634Y+120610X0180Y         S1      
327GND              PEX2  -P44        A01X+122008Y+120610X0180Y         S1      
327GND              PEX2  -P45        A01X+122382Y+120610X0180Y         S1      
327GND              PEX2  -A48        A01X+123504Y+125472X0180Y         S1      
327GND              PEX2  -E47        A01X+123130Y+123976X0180Y         S1      
327GND              PEX2  -E46        A01X+122756Y+123976X0180Y         S1      
327GND              PEX2  -D49        A01X+123878Y+124350X0180Y         S1      
327GND              PEX2  -D48        A01X+123504Y+124350X0180Y         S1      
327GND              PEX2  -D47        A01X+123130Y+124350X0180Y         S1      
327GND              PEX2  -C47        A01X+123130Y+124724X0180Y         S1      
327GND              PEX2  -B48        A01X+123504Y+125098X0180Y         S1      
327GND              PEX2  -B49        A01X+123878Y+125098X0180Y         S1      
327GND              PEX2  -A46        A01X+122756Y+125472X0180Y         S1      
327GND              PEX2  -B46        A01X+122756Y+125098X0180Y         S1      
327GND              PEX2  -F49        A01X+123878Y+123602X0180Y         S1      
327GND              PEX2  -F48        A01X+123504Y+123602X0180Y         S1      
327GND              PEX2  -G48        A01X+123504Y+123228X0180Y         S1      
327GND              PEX2  -G49        A01X+123878Y+123228X0180Y         S1      
327GND              PEX2  -G46        A01X+122756Y+123228X0180Y         S1      
327GND              PEX2  -F46        A01X+122756Y+123602X0180Y         S1      
327GND              PEX2  -H47        A01X+123130Y+122854X0180Y         S1      
327GND              PEX2  -J47        A01X+123130Y+122480X0180Y         S1      
327GND              PEX2  -J48        A01X+123504Y+122480X0180Y         S1      
327GND              PEX2  -J49        A01X+123878Y+122480X0180Y         S1      
327GND              PEX2  -E41        A01X+120886Y+123976X0180Y         S1      
327GND              PEX2  -D41        A01X+120886Y+124350X0180Y         S1      
327GND              PEX2  -C41        A01X+120886Y+124724X0180Y         S1      
327GND              PEX2  -E45        A01X+122382Y+123976X0180Y         S1      
327GND              PEX2  -E44        A01X+122008Y+123976X0180Y         S1      
327GND              PEX2  -E43        A01X+121634Y+123976X0180Y         S1      
327GND              PEX2  -E42        A01X+121260Y+123976X0180Y         S1      
327GND              PEX2  -D45        A01X+122382Y+124350X0180Y         S1      
327GND              PEX2  -C45        A01X+122382Y+124724X0180Y         S1      
327GND              PEX2  -A44        A01X+122008Y+125472X0180Y         S1      
327GND              PEX2  -B44        A01X+122008Y+125098X0180Y         S1      
327GND              PEX2  -D43        A01X+121634Y+124350X0180Y         S1      
327GND              PEX2  -C43        A01X+121634Y+124724X0180Y         S1      
327GND              PEX2  -A42        A01X+121260Y+125472X0180Y         S1      
327GND              PEX2  -B42        A01X+121260Y+125098X0180Y         S1      
327GND              PEX2  -H41        A01X+120886Y+122854X0180Y         S1      
327GND              PEX2  -J41        A01X+120886Y+122480X0180Y         S1      
327GND              PEX2  -F44        A01X+122008Y+123602X0180Y         S1      
327GND              PEX2  -G44        A01X+122008Y+123228X0180Y         S1      
327GND              PEX2  -H45        A01X+122382Y+122854X0180Y         S1      
327GND              PEX2  -J45        A01X+122382Y+122480X0180Y         S1      
327GND              PEX2  -F42        A01X+121260Y+123602X0180Y         S1      
327GND              PEX2  -G42        A01X+121260Y+123228X0180Y         S1      
327GND              PEX2  -H43        A01X+121634Y+122854X0180Y         S1      
327GND              PEX2  -J43        A01X+121634Y+122480X0180Y         S1      
327GND              PEX2  -D37        A01X+119390Y+124350X0180Y         S1      
327GND              PEX2  -E37        A01X+119390Y+123976X0180Y         S1      
327GND              PEX2  -C37        A01X+119390Y+124724X0180Y         S1      
327GND              PEX2  -E40        A01X+120512Y+123976X0180Y         S1      
327GND              PEX2  -D39        A01X+120138Y+124350X0180Y         S1      
327GND              PEX2  -E39        A01X+120138Y+123976X0180Y         S1      
327GND              PEX2  -E38        A01X+119764Y+123976X0180Y         S1      
327GND              PEX2  -A40        A01X+120512Y+125472X0180Y         S1      
327GND              PEX2  -B40        A01X+120512Y+125098X0180Y         S1      
327GND              PEX2  -C39        A01X+120138Y+124724X0180Y         S1      
327GND              PEX2  -A38        A01X+119764Y+125472X0180Y         S1      
327GND              PEX2  -B38        A01X+119764Y+125098X0180Y         S1      
327GND              PEX2  -J37        A01X+119390Y+122480X0180Y         S1      
327GND              PEX2  -H37        A01X+119390Y+122854X0180Y         S1      
327GND              PEX2  -F40        A01X+120512Y+123602X0180Y         S1      
327GND              PEX2  -G40        A01X+120512Y+123228X0180Y         S1      
327GND              PEX2  -J39        A01X+120138Y+122480X0180Y         S1      
327GND              PEX2  -F38        A01X+119764Y+123602X0180Y         S1      
327GND              PEX2  -H39        A01X+120138Y+122854X0180Y         S1      
327GND              PEX2  -G38        A01X+119764Y+123228X0180Y         S1      
327GND              PEX2  -E36        A01X+119016Y+123976X0180Y         S1      
327GND              PEX2  -D35        A01X+118642Y+124350X0180Y         S1      
327GND              PEX2  -D33        A01X+117894Y+124350X0180Y         S1      
327GND              PEX2  -E34        A01X+118268Y+123976X0180Y         S1      
327GND              PEX2  -E35        A01X+118642Y+123976X0180Y         S1      
327GND              PEX2  -E33        A01X+117894Y+123976X0180Y         S1      
327GND              PEX2  -C35        A01X+118642Y+124724X0180Y         S1      
327GND              PEX2  -B36        A01X+119016Y+125098X0180Y         S1      
327GND              PEX2  -A36        A01X+119016Y+125472X0180Y         S1      
327GND              PEX2  -A34        A01X+118268Y+125472X0180Y         S1      
327GND              PEX2  -B34        A01X+118268Y+125098X0180Y         S1      
327GND              PEX2  -C33        A01X+117894Y+124724X0180Y         S1      
327GND              PEX2  -J35        A01X+118642Y+122480X0180Y         S1      
327GND              PEX2  -H35        A01X+118642Y+122854X0180Y         S1      
327GND              PEX2  -F36        A01X+119016Y+123602X0180Y         S1      
327GND              PEX2  -G36        A01X+119016Y+123228X0180Y         S1      
327GND              PEX2  -F34        A01X+118268Y+123602X0180Y         S1      
327GND              PEX2  -G34        A01X+118268Y+123228X0180Y         S1      
327GND              PEX2  -J33        A01X+117894Y+122480X0180Y         S1      
327GND              PEX2  -H33        A01X+117894Y+122854X0180Y         S1      
327GND              PEX2  -A28        A01X+116024Y+125472X0180Y         S1      
327GND              PEX2  -B28        A01X+116024Y+125098X0180Y         S1      
327GND              PEX2  -E28        A01X+116024Y+123976X0180Y         S1      
327GND              PEX2  -E31        A01X+117146Y+123976X0180Y         S1      
327GND              PEX2  -B32        A01X+117520Y+125098X0180Y         S1      
327GND              PEX2  -E32        A01X+117520Y+123976X0180Y         S1      
327GND              PEX2  -D31        A01X+117146Y+124350X0180Y         S1      
327GND              PEX2  -C31        A01X+117146Y+124724X0180Y         S1      
327GND              PEX2  -A30        A01X+116772Y+125472X0180Y         S1      
327GND              PEX2  -B30        A01X+116772Y+125098X0180Y         S1      
327GND              PEX2  -E30        A01X+116772Y+123976X0180Y         S1      
327GND              PEX2  -C29        A01X+116398Y+124724X0180Y         S1      
327GND              PEX2  -D29        A01X+116398Y+124350X0180Y         S1      
327GND              PEX2  -E29        A01X+116398Y+123976X0180Y         S1      
327GND              PEX2  -A32        A01X+117520Y+125472X0180Y         S1      
327GND              PEX2  -F28        A01X+116024Y+123602X0180Y         S1      
327GND              PEX2  -G28        A01X+116024Y+123228X0180Y         S1      
327GND              PEX2  -F30        A01X+116772Y+123602X0180Y         S1      
327GND              PEX2  -F32        A01X+117520Y+123602X0180Y         S1      
327GND              PEX2  -G32        A01X+117520Y+123228X0180Y         S1      
327GND              PEX2  -G30        A01X+116772Y+123228X0180Y         S1      
327GND              PEX2  -J31        A01X+117146Y+122480X0180Y         S1      
327GND              PEX2  -H31        A01X+117146Y+122854X0180Y         S1      
327GND              PEX2  -J29        A01X+116398Y+122480X0180Y         S1      
327GND              PEX2  -H29        A01X+116398Y+122854X0180Y         S1      
327GND              PEX2  -A24        A01X+114528Y+125472X0180Y         S1      
327GND              PEX2  -B24        A01X+114528Y+125098X0180Y         S1      
327GND              PEX2  -E24        A01X+114528Y+123976X0180Y         S1      
327GND              PEX2  -C27        A01X+115650Y+124724X0180Y         S1      
327GND              PEX2  -D27        A01X+115650Y+124350X0180Y         S1      
327GND              PEX2  -E27        A01X+115650Y+123976X0180Y         S1      
327GND              PEX2  -E26        A01X+115276Y+123976X0180Y         S1      
327GND              PEX2  -E25        A01X+114902Y+123976X0180Y         S1      
327GND              PEX2  -D25        A01X+114902Y+124350X0180Y         S1      
327GND              PEX2  -C25        A01X+114902Y+124724X0180Y         S1      
327GND              PEX2  -B26        A01X+115276Y+125098X0180Y         S1      
327GND              PEX2  -A26        A01X+115276Y+125472X0180Y         S1      
327GND              PEX2  -F24        A01X+114528Y+123602X0180Y         S1      
327GND              PEX2  -G24        A01X+114528Y+123228X0180Y         S1      
327GND              PEX2  -J25        A01X+114902Y+122480X0180Y         S1      
327GND              PEX2  -H25        A01X+114902Y+122854X0180Y         S1      
327GND              PEX2  -J27        A01X+115650Y+122480X0180Y         S1      
327GND              PEX2  -H27        A01X+115650Y+122854X0180Y         S1      
327GND              PEX2  -F26        A01X+115276Y+123602X0180Y         S1      
327GND              PEX2  -G26        A01X+115276Y+123228X0180Y         S1      
327GND              PEX2  -E20        A01X+113031Y+123976X0180Y         S1      
327GND              PEX2  -E21        A01X+113405Y+123976X0180Y         S1      
327GND              PEX2  -E22        A01X+113780Y+123976X0180Y         S1      
327GND              PEX2  -A22        A01X+113780Y+125472X0180Y         S1      
327GND              PEX2  -B22        A01X+113780Y+125098X0180Y         S1      
327GND              PEX2  -D21        A01X+113405Y+124350X0180Y         S1      
327GND              PEX2  -C21        A01X+113405Y+124724X0180Y         S1      
327GND              PEX2  -A20        A01X+113031Y+125472X0180Y         S1      
327GND              PEX2  -B20        A01X+113031Y+125098X0180Y         S1      
327GND              PEX2  -C23        A01X+114154Y+124724X0180Y         S1      
327GND              PEX2  -D23        A01X+114154Y+124350X0180Y         S1      
327GND              PEX2  -E23        A01X+114154Y+123976X0180Y         S1      
327GND              PEX2  -F20        A01X+113031Y+123602X0180Y         S1      
327GND              PEX2  -G20        A01X+113031Y+123228X0180Y         S1      
327GND              PEX2  -J21        A01X+113405Y+122480X0180Y         S1      
327GND              PEX2  -H21        A01X+113405Y+122854X0180Y         S1      
327GND              PEX2  -F22        A01X+113780Y+123602X0180Y         S1      
327GND              PEX2  -G22        A01X+113780Y+123228X0180Y         S1      
327GND              PEX2  -J23        A01X+114154Y+122480X0180Y         S1      
327GND              PEX2  -H23        A01X+114154Y+122854X0180Y         S1      
327GND              PEX2  -E15        A01X+111161Y+123976X0180Y         S1      
327GND              PEX2  -D15        A01X+111161Y+124350X0180Y         S1      
327GND              PEX2  -C15        A01X+111161Y+124724X0180Y         S1      
327GND              PEX2  -E17        A01X+111909Y+123976X0180Y         S1      
327GND              PEX2  -E16        A01X+111535Y+123976X0180Y         S1      
327GND              PEX2  -E19        A01X+112657Y+123976X0180Y         S1      
327GND              PEX2  -E18        A01X+112283Y+123976X0180Y         S1      
327GND              PEX2  -B18        A01X+112283Y+125098X0180Y         S1      
327GND              PEX2  -A18        A01X+112283Y+125472X0180Y         S1      
327GND              PEX2  -C19        A01X+112657Y+124724X0180Y         S1      
327GND              PEX2  -D19        A01X+112657Y+124350X0180Y         S1      
327GND              PEX2  -D17        A01X+111909Y+124350X0180Y         S1      
327GND              PEX2  -C17        A01X+111909Y+124724X0180Y         S1      
327GND              PEX2  -A16        A01X+111535Y+125472X0180Y         S1      
327GND              PEX2  -B16        A01X+111535Y+125098X0180Y         S1      
327GND              PEX2  -J15        A01X+111161Y+122480X0180Y         S1      
327GND              PEX2  -H15        A01X+111161Y+122854X0180Y         S1      
327GND              PEX2  -F16        A01X+111535Y+123602X0180Y         S1      
327GND              PEX2  -G16        A01X+111535Y+123228X0180Y         S1      
327GND              PEX2  -H17        A01X+111909Y+122854X0180Y         S1      
327GND              PEX2  -J17        A01X+111909Y+122480X0180Y         S1      
327GND              PEX2  -F18        A01X+112283Y+123602X0180Y         S1      
327GND              PEX2  -G18        A01X+112283Y+123228X0180Y         S1      
327GND              PEX2  -H19        A01X+112657Y+122854X0180Y         S1      
327GND              PEX2  -J19        A01X+112657Y+122480X0180Y         S1      
327GND              PEX2  -D11        A01X+109665Y+124350X0180Y         S1      
327GND              PEX2  -E11        A01X+109665Y+123976X0180Y         S1      
327GND              PEX2  -C11        A01X+109665Y+124724X0180Y         S1      
327GND              PEX2  -D13        A01X+110413Y+124350X0180Y         S1      
327GND              PEX2  -E14        A01X+110787Y+123976X0180Y         S1      
327GND              PEX2  -E13        A01X+110413Y+123976X0180Y         S1      
327GND              PEX2  -E12        A01X+110039Y+123976X0180Y         S1      
327GND              PEX2  -A14        A01X+110787Y+125472X0180Y         S1      
327GND              PEX2  -B14        A01X+110787Y+125098X0180Y         S1      
327GND              PEX2  -C13        A01X+110413Y+124724X0180Y         S1      
327GND              PEX2  -A12        A01X+110039Y+125472X0180Y         S1      
327GND              PEX2  -B12        A01X+110039Y+125098X0180Y         S1      
327GND              PEX2  -J11        A01X+109665Y+122480X0180Y         S1      
327GND              PEX2  -H11        A01X+109665Y+122854X0180Y         S1      
327GND              PEX2  -F12        A01X+110039Y+123602X0180Y         S1      
327GND              PEX2  -G12        A01X+110039Y+123228X0180Y         S1      
327GND              PEX2  -F14        A01X+110787Y+123602X0180Y         S1      
327GND              PEX2  -H13        A01X+110413Y+122854X0180Y         S1      
327GND              PEX2  -J13        A01X+110413Y+122480X0180Y         S1      
327GND              PEX2  -G14        A01X+110787Y+123228X0180Y         S1      
327GND              PEX2  -E10        A01X+109291Y+123976X0180Y         S1      
327GND              PEX2  -A10        A01X+109291Y+125472X0180Y         S1      
327GND              PEX2  -B10        A01X+109291Y+125098X0180Y         S1      
327GND              PEX2  -F10        A01X+109291Y+123602X0180Y         S1      
327GND              PEX2  -G10        A01X+109291Y+123228X0180Y         S1      
327GND              PEX2  -C9         A01X+108917Y+124724X0180Y         S1      
327GND              PEX2  -D9         A01X+108917Y+124350X0180Y         S1      
327GND              PEX2  -E9         A01X+108917Y+123976X0180Y         S1      
327GND              PEX2  -E8         A01X+108543Y+123976X0180Y         S1      
327GND              PEX2  -B8         A01X+108543Y+125098X0180Y         S1      
327GND              PEX2  -D7         A01X+108169Y+124350X0180Y         S1      
327GND              PEX2  -E7         A01X+108169Y+123976X0180Y         S1      
327GND              PEX2  -A8         A01X+108543Y+125472X0180Y         S1      
327GND              PEX2  -C7         A01X+108169Y+124724X0180Y         S1      
327GND              PEX2  -H9         A01X+108917Y+122854X0180Y         S1      
327GND              PEX2  -J9         A01X+108917Y+122480X0180Y         S1      
327GND              PEX2  -J7         A01X+108169Y+122480X0180Y         S1      
327GND              PEX2  -H7         A01X+108169Y+122854X0180Y         S1      
327GND              PEX2  -F8         A01X+108543Y+123602X0180Y         S1      
327GND              PEX2  -G8         A01X+108543Y+123228X0180Y         S1      
327GND              PEX2  -L8         A01X+108543Y+121732X0180Y         S1      
327GND              PEX2  -K8         A01X+108543Y+122106X0180Y         S1      
327GND              PEX2  -K7         A01X+108169Y+122106X0180Y         S1      
327GND              PEX2  -K9         A01X+108917Y+122106X0180Y         S1      
327GND              PEX2  -L9         A01X+108917Y+121732X0180Y         S1      
327GND              PEX2  -D2         A01X+106299Y+124350X0180Y         S1      
327GND              PEX2  -A2         A01X+106299Y+125472X0180Y         S1      
327GND              PEX2  -B2         A01X+106299Y+125098X0180Y         S1      
327GND              PEX2  -D5         A01X+107421Y+124350X0180Y         S1      
327GND              PEX2  -E5         A01X+107421Y+123976X0180Y         S1      
327GND              PEX2  -E6         A01X+107795Y+123976X0180Y         S1      
327GND              PEX2  -E4         A01X+107047Y+123976X0180Y         S1      
327GND              PEX2  -D3         A01X+106673Y+124350X0180Y         S1      
327GND              PEX2  -E3         A01X+106673Y+123976X0180Y         S1      
327GND              PEX2  -A6         A01X+107795Y+125472X0180Y         S1      
327GND              PEX2  -B6         A01X+107795Y+125098X0180Y         S1      
327GND              PEX2  -C5         A01X+107421Y+124724X0180Y         S1      
327GND              PEX2  -C3         A01X+106673Y+124724X0180Y         S1      
327GND              PEX2  -A4         A01X+107047Y+125472X0180Y         S1      
327GND              PEX2  -B4         A01X+107047Y+125098X0180Y         S1      
327GND              PEX2  -J2         A01X+106299Y+122480X0180Y         S1      
327GND              PEX2  -G2         A01X+106299Y+123228X0180Y         S1      
327GND              PEX2  -F2         A01X+106299Y+123602X0180Y         S1      
327GND              PEX2  -F6         A01X+107795Y+123602X0180Y         S1      
327GND              PEX2  -G6         A01X+107795Y+123228X0180Y         S1      
327GND              PEX2  -H5         A01X+107421Y+122854X0180Y         S1      
327GND              PEX2  -J5         A01X+107421Y+122480X0180Y         S1      
327GND              PEX2  -J3         A01X+106673Y+122480X0180Y         S1      
327GND              PEX2  -H3         A01X+106673Y+122854X0180Y         S1      
327GND              PEX2  -G4         A01X+107047Y+123228X0180Y         S1      
327GND              PEX2  -F4         A01X+107047Y+123602X0180Y         S1      
327GND              PEX2  -K4         A01X+107047Y+122106X0180Y         S1      
327GND              PEX2  -K3         A01X+106673Y+122106X0180Y         S1      
327GND              PEX2  -K6         A01X+107795Y+122106X0180Y         S1      
327GND              PEX2  -K5         A01X+107421Y+122106X0180Y         S1      
327GND              PEX2  -B1         A01X+105925Y+125098X0180Y         S1      
327GND              PEX2  -D1         A01X+105925Y+124350X0180Y         S1      
327GND              PEX2  -J1         A01X+105925Y+122480X0180Y         S1      
327GND              PEX2  -F1         A01X+105925Y+123602X0180Y         S1      
327GND              PEX2  -G1         A01X+105925Y+123228X0180Y         S1      
327GND              PEX2  -N9         A01X+108917Y+120984X0180Y         S1      
327GND              PEX2  -N8         A01X+108543Y+120984X0180Y         S1      
327GND              PEX2  -R9         A01X+108917Y+120236X0180Y         S1      
327GND              PEX2  -R8         A01X+108543Y+120236X0180Y         S1      
327GND              PEX2  -U9         A01X+108917Y+119488X0180Y         S1      
327GND              PEX2  -U8         A01X+108543Y+119488X0180Y         S1      
327GND              PEX2  -M7         A01X+108169Y+121358X0180Y         S1      
327GND              PEX2  -V7         A01X+108169Y+119114X0180Y         S1      
327GND              PEX2  -P7         A01X+108169Y+120610X0180Y         S1      
327GND              PEX2  -T7         A01X+108169Y+119862X0180Y         S1      
327GND              PEX2  -L2         A01X+106299Y+121732X0180Y         S1      
327GND              PEX2  -N2         A01X+106299Y+120984X0180Y         S1      
327GND              PEX2  -M3         A01X+106673Y+121358X0180Y         S1      
327GND              PEX2  -M4         A01X+107047Y+121358X0180Y         S1      
327GND              PEX2  -M5         A01X+107421Y+121358X0180Y         S1      
327GND              PEX2  -N5         A01X+107421Y+120984X0180Y         S1      
327GND              PEX2  -M6         A01X+107795Y+121358X0180Y         S1      
327GND              PEX2  -L5         A01X+107421Y+121732X0180Y         S1      
327GND              PEX2  -R2         A01X+106299Y+120236X0180Y         S1      
327GND              PEX2  -U2         A01X+106299Y+119488X0180Y         S1      
327GND              PEX2  -P4         A01X+107047Y+120610X0180Y         S1      
327GND              PEX2  -P3         A01X+106673Y+120610X0180Y         S1      
327GND              PEX2  -T3         A01X+106673Y+119862X0180Y         S1      
327GND              PEX2  -T4         A01X+107047Y+119862X0180Y         S1      
327GND              PEX2  -V3         A01X+106673Y+119114X0180Y         S1      
327GND              PEX2  -V4         A01X+107047Y+119114X0180Y         S1      
327GND              PEX2  -R5         A01X+107421Y+120236X0180Y         S1      
327GND              PEX2  -P6         A01X+107795Y+120610X0180Y         S1      
327GND              PEX2  -P5         A01X+107421Y+120610X0180Y         S1      
327GND              PEX2  -U5         A01X+107421Y+119488X0180Y         S1      
327GND              PEX2  -T5         A01X+107421Y+119862X0180Y         S1      
327GND              PEX2  -T6         A01X+107795Y+119862X0180Y         S1      
327GND              PEX2  -V5         A01X+107421Y+119114X0180Y         S1      
327GND              PEX2  -V6         A01X+107795Y+119114X0180Y         S1      
327GND              PEX2  -W2         A01X+106299Y+118740X0180Y         S1      
327GND              PEX2  -W5         A01X+107421Y+118740X0180Y         S1      
327GND              PEX2  -L1         A01X+105925Y+121732X0180Y         S1      
327GND              PEX2  -N1         A01X+105925Y+120984X0180Y         S1      
327GND              PEX2  -R1         A01X+105925Y+120236X0180Y         S1      
327GND              PEX2  -U1         A01X+105925Y+119488X0180Y         S1      
327GND              PEX2  -W1         A01X+105925Y+118740X0180Y         S1      
327GND              PEX1  -D1         A01X+060216Y+124350X0180Y         S1      
327GND              PEX1  -B1         A01X+060216Y+125098X0180Y         S1      
327GND              PEX1  -L9         A01X+063209Y+121732X0180Y         S1      
327GND              PEX1  -K9         A01X+063209Y+122106X0180Y         S1      
327GND              PEX1  -K7         A01X+062461Y+122106X0180Y         S1      
327GND              PEX1  -K8         A01X+062835Y+122106X0180Y         S1      
327GND              PEX1  -L8         A01X+062835Y+121732X0180Y         S1      
327GND              PEX1  -L5         A01X+061713Y+121732X0180Y         S1      
327GND              PEX1  -K5         A01X+061713Y+122106X0180Y         S1      
327GND              PEX1  -K6         A01X+062087Y+122106X0180Y         S1      
327GND              PEX1  -N8         A01X+062835Y+120984X0180Y         S1      
327GND              PEX1  -N9         A01X+063209Y+120984X0180Y         S1      
327GND              PEX1  -M7         A01X+062461Y+121358X0180Y         S1      
327GND              PEX1  -U8         A01X+062835Y+119488X0180Y         S1      
327GND              PEX1  -U9         A01X+063209Y+119488X0180Y         S1      
327GND              PEX1  -T7         A01X+062461Y+119862X0180Y         S1      
327GND              PEX1  -P7         A01X+062461Y+120610X0180Y         S1      
327GND              PEX1  -R8         A01X+062835Y+120236X0180Y         S1      
327GND              PEX1  -R9         A01X+063209Y+120236X0180Y         S1      
327GND              PEX1  -V7         A01X+062461Y+119114X0180Y         S1      
327GND              PEX1  -W8         A01X+062835Y+118740X0180Y         S1      
327GND              PEX1  -M6         A01X+062087Y+121358X0180Y         S1      
327GND              PEX1  -N5         A01X+061713Y+120984X0180Y         S1      
327GND              PEX1  -M5         A01X+061713Y+121358X0180Y         S1      
327GND              PEX1  -V6         A01X+062087Y+119114X0180Y         S1      
327GND              PEX1  -V5         A01X+061713Y+119114X0180Y         S1      
327GND              PEX1  -T6         A01X+062087Y+119862X0180Y         S1      
327GND              PEX1  -T5         A01X+061713Y+119862X0180Y         S1      
327GND              PEX1  -U5         A01X+061713Y+119488X0180Y         S1      
327GND              PEX1  -P5         A01X+061713Y+120610X0180Y         S1      
327GND              PEX1  -P6         A01X+062087Y+120610X0180Y         S1      
327GND              PEX1  -R5         A01X+061713Y+120236X0180Y         S1      
327GND              PEX1  -W5         A01X+061713Y+118740X0180Y         S1      
327GND              PEX1  -M4         A01X+061339Y+121358X0180Y         S1      
327GND              PEX1  -M3         A01X+060965Y+121358X0180Y         S1      
327GND              PEX1  -K3         A01X+060965Y+122106X0180Y         S1      
327GND              PEX1  -K4         A01X+061339Y+122106X0180Y         S1      
327GND              PEX1  -V4         A01X+061339Y+119114X0180Y         S1      
327GND              PEX1  -V3         A01X+060965Y+119114X0180Y         S1      
327GND              PEX1  -T4         A01X+061339Y+119862X0180Y         S1      
327GND              PEX1  -T3         A01X+060965Y+119862X0180Y         S1      
327GND              PEX1  -P3         A01X+060965Y+120610X0180Y         S1      
327GND              PEX1  -P4         A01X+061339Y+120610X0180Y         S1      
327GND              PEX1  -Y3         A01X+060965Y+118366X0180Y         S1      
327GND              PEX1  -Y4         A01X+061339Y+118366X0180Y         S1      
327GND              PEX1  -G1         A01X+060216Y+123228X0180Y         S1      
327GND              PEX1  -F1         A01X+060216Y+123602X0180Y         S1      
327GND              PEX1  -J1         A01X+060216Y+122480X0180Y         S1      
327GND              PEX1  -N1         A01X+060216Y+120984X0180Y         S1      
327GND              PEX1  -N2         A01X+060590Y+120984X0180Y         S1      
327GND              PEX1  -L1         A01X+060216Y+121732X0180Y         S1      
327GND              PEX1  -L2         A01X+060590Y+121732X0180Y         S1      
327GND              PEX1  -U2         A01X+060590Y+119488X0180Y         S1      
327GND              PEX1  -U1         A01X+060216Y+119488X0180Y         S1      
327GND              PEX1  -R2         A01X+060590Y+120236X0180Y         S1      
327GND              PEX1  -R1         A01X+060216Y+120236X0180Y         S1      
327GND              PEX1  -W2         A01X+060590Y+118740X0180Y         S1      
327GND              PEX1  -W1         A01X+060216Y+118740X0180Y         S1      
327GND              PEX1  -Y1         A01X+060216Y+118366X0180Y         S1      
327GND              PEX1  -Y2         A01X+060590Y+118366X0180Y         S1      
327GND              PEX1  -B38        A01X+074055Y+125098X0180Y         S1      
327GND              PEX1  -A38        A01X+074055Y+125472X0180Y         S1      
327GND              PEX1  -C39        A01X+074429Y+124724X0180Y         S1      
327GND              PEX1  -B40        A01X+074803Y+125098X0180Y         S1      
327GND              PEX1  -A40        A01X+074803Y+125472X0180Y         S1      
327GND              PEX1  -E38        A01X+074055Y+123976X0180Y         S1      
327GND              PEX1  -E39        A01X+074429Y+123976X0180Y         S1      
327GND              PEX1  -D39        A01X+074429Y+124350X0180Y         S1      
327GND              PEX1  -E40        A01X+074803Y+123976X0180Y         S1      
327GND              PEX1  -G38        A01X+074055Y+123228X0180Y         S1      
327GND              PEX1  -H39        A01X+074429Y+122854X0180Y         S1      
327GND              PEX1  -F38        A01X+074055Y+123602X0180Y         S1      
327GND              PEX1  -G40        A01X+074803Y+123228X0180Y         S1      
327GND              PEX1  -F40        A01X+074803Y+123602X0180Y         S1      
327GND              PEX1  -C33        A01X+072185Y+124724X0180Y         S1      
327GND              PEX1  -B34        A01X+072559Y+125098X0180Y         S1      
327GND              PEX1  -A34        A01X+072559Y+125472X0180Y         S1      
327GND              PEX1  -A36        A01X+073307Y+125472X0180Y         S1      
327GND              PEX1  -B36        A01X+073307Y+125098X0180Y         S1      
327GND              PEX1  -C35        A01X+072933Y+124724X0180Y         S1      
327GND              PEX1  -C37        A01X+073681Y+124724X0180Y         S1      
327GND              PEX1  -E33        A01X+072185Y+123976X0180Y         S1      
327GND              PEX1  -E35        A01X+072933Y+123976X0180Y         S1      
327GND              PEX1  -E34        A01X+072559Y+123976X0180Y         S1      
327GND              PEX1  -D33        A01X+072185Y+124350X0180Y         S1      
327GND              PEX1  -D35        A01X+072933Y+124350X0180Y         S1      
327GND              PEX1  -E36        A01X+073307Y+123976X0180Y         S1      
327GND              PEX1  -E37        A01X+073681Y+123976X0180Y         S1      
327GND              PEX1  -D37        A01X+073681Y+124350X0180Y         S1      
327GND              PEX1  -H33        A01X+072185Y+122854X0180Y         S1      
327GND              PEX1  -J33        A01X+072185Y+122480X0180Y         S1      
327GND              PEX1  -G34        A01X+072559Y+123228X0180Y         S1      
327GND              PEX1  -F34        A01X+072559Y+123602X0180Y         S1      
327GND              PEX1  -G36        A01X+073307Y+123228X0180Y         S1      
327GND              PEX1  -F36        A01X+073307Y+123602X0180Y         S1      
327GND              PEX1  -H35        A01X+072933Y+122854X0180Y         S1      
327GND              PEX1  -J35        A01X+072933Y+122480X0180Y         S1      
327GND              PEX1  -H37        A01X+073681Y+122854X0180Y         S1      
327GND              PEX1  -J37        A01X+073681Y+122480X0180Y         S1      
327GND              PEX1  -A32        A01X+071811Y+125472X0180Y         S1      
327GND              PEX1  -E29        A01X+070689Y+123976X0180Y         S1      
327GND              PEX1  -D29        A01X+070689Y+124350X0180Y         S1      
327GND              PEX1  -C29        A01X+070689Y+124724X0180Y         S1      
327GND              PEX1  -E30        A01X+071063Y+123976X0180Y         S1      
327GND              PEX1  -B30        A01X+071063Y+125098X0180Y         S1      
327GND              PEX1  -A30        A01X+071063Y+125472X0180Y         S1      
327GND              PEX1  -C31        A01X+071437Y+124724X0180Y         S1      
327GND              PEX1  -D31        A01X+071437Y+124350X0180Y         S1      
327GND              PEX1  -E32        A01X+071811Y+123976X0180Y         S1      
327GND              PEX1  -B32        A01X+071811Y+125098X0180Y         S1      
327GND              PEX1  -E31        A01X+071437Y+123976X0180Y         S1      
327GND              PEX1  -H29        A01X+070689Y+122854X0180Y         S1      
327GND              PEX1  -J29        A01X+070689Y+122480X0180Y         S1      
327GND              PEX1  -H31        A01X+071437Y+122854X0180Y         S1      
327GND              PEX1  -J31        A01X+071437Y+122480X0180Y         S1      
327GND              PEX1  -G30        A01X+071063Y+123228X0180Y         S1      
327GND              PEX1  -G32        A01X+071811Y+123228X0180Y         S1      
327GND              PEX1  -F32        A01X+071811Y+123602X0180Y         S1      
327GND              PEX1  -F30        A01X+071063Y+123602X0180Y         S1      
327GND              PEX1  -A26        A01X+069567Y+125472X0180Y         S1      
327GND              PEX1  -B26        A01X+069567Y+125098X0180Y         S1      
327GND              PEX1  -C25        A01X+069193Y+124724X0180Y         S1      
327GND              PEX1  -D25        A01X+069193Y+124350X0180Y         S1      
327GND              PEX1  -E25        A01X+069193Y+123976X0180Y         S1      
327GND              PEX1  -E26        A01X+069567Y+123976X0180Y         S1      
327GND              PEX1  -E28        A01X+070315Y+123976X0180Y         S1      
327GND              PEX1  -E27        A01X+069941Y+123976X0180Y         S1      
327GND              PEX1  -D27        A01X+069941Y+124350X0180Y         S1      
327GND              PEX1  -C27        A01X+069941Y+124724X0180Y         S1      
327GND              PEX1  -B28        A01X+070315Y+125098X0180Y         S1      
327GND              PEX1  -A28        A01X+070315Y+125472X0180Y         S1      
327GND              PEX1  -G26        A01X+069567Y+123228X0180Y         S1      
327GND              PEX1  -F26        A01X+069567Y+123602X0180Y         S1      
327GND              PEX1  -H27        A01X+069941Y+122854X0180Y         S1      
327GND              PEX1  -J27        A01X+069941Y+122480X0180Y         S1      
327GND              PEX1  -G28        A01X+070315Y+123228X0180Y         S1      
327GND              PEX1  -F28        A01X+070315Y+123602X0180Y         S1      
327GND              PEX1  -H25        A01X+069193Y+122854X0180Y         S1      
327GND              PEX1  -J25        A01X+069193Y+122480X0180Y         S1      
327GND              PEX1  -E24        A01X+068819Y+123976X0180Y         S1      
327GND              PEX1  -E23        A01X+068445Y+123976X0180Y         S1      
327GND              PEX1  -D23        A01X+068445Y+124350X0180Y         S1      
327GND              PEX1  -C23        A01X+068445Y+124724X0180Y         S1      
327GND              PEX1  -B24        A01X+068819Y+125098X0180Y         S1      
327GND              PEX1  -A24        A01X+068819Y+125472X0180Y         S1      
327GND              PEX1  -B20        A01X+067323Y+125098X0180Y         S1      
327GND              PEX1  -A20        A01X+067323Y+125472X0180Y         S1      
327GND              PEX1  -C21        A01X+067697Y+124724X0180Y         S1      
327GND              PEX1  -D21        A01X+067697Y+124350X0180Y         S1      
327GND              PEX1  -B22        A01X+068071Y+125098X0180Y         S1      
327GND              PEX1  -A22        A01X+068071Y+125472X0180Y         S1      
327GND              PEX1  -E22        A01X+068071Y+123976X0180Y         S1      
327GND              PEX1  -E21        A01X+067697Y+123976X0180Y         S1      
327GND              PEX1  -E20        A01X+067323Y+123976X0180Y         S1      
327GND              PEX1  -G24        A01X+068819Y+123228X0180Y         S1      
327GND              PEX1  -F24        A01X+068819Y+123602X0180Y         S1      
327GND              PEX1  -H23        A01X+068445Y+122854X0180Y         S1      
327GND              PEX1  -J23        A01X+068445Y+122480X0180Y         S1      
327GND              PEX1  -G22        A01X+068071Y+123228X0180Y         S1      
327GND              PEX1  -F22        A01X+068071Y+123602X0180Y         S1      
327GND              PEX1  -H21        A01X+067697Y+122854X0180Y         S1      
327GND              PEX1  -J21        A01X+067697Y+122480X0180Y         S1      
327GND              PEX1  -G20        A01X+067323Y+123228X0180Y         S1      
327GND              PEX1  -F20        A01X+067323Y+123602X0180Y         S1      
327GND              PEX1  -B16        A01X+065827Y+125098X0180Y         S1      
327GND              PEX1  -A16        A01X+065827Y+125472X0180Y         S1      
327GND              PEX1  -C17        A01X+066201Y+124724X0180Y         S1      
327GND              PEX1  -D17        A01X+066201Y+124350X0180Y         S1      
327GND              PEX1  -D19        A01X+066949Y+124350X0180Y         S1      
327GND              PEX1  -C19        A01X+066949Y+124724X0180Y         S1      
327GND              PEX1  -A18        A01X+066575Y+125472X0180Y         S1      
327GND              PEX1  -B18        A01X+066575Y+125098X0180Y         S1      
327GND              PEX1  -E18        A01X+066575Y+123976X0180Y         S1      
327GND              PEX1  -E19        A01X+066949Y+123976X0180Y         S1      
327GND              PEX1  -E16        A01X+065827Y+123976X0180Y         S1      
327GND              PEX1  -E17        A01X+066201Y+123976X0180Y         S1      
327GND              PEX1  -J19        A01X+066949Y+122480X0180Y         S1      
327GND              PEX1  -H19        A01X+066949Y+122854X0180Y         S1      
327GND              PEX1  -G18        A01X+066575Y+123228X0180Y         S1      
327GND              PEX1  -F18        A01X+066575Y+123602X0180Y         S1      
327GND              PEX1  -J17        A01X+066201Y+122480X0180Y         S1      
327GND              PEX1  -H17        A01X+066201Y+122854X0180Y         S1      
327GND              PEX1  -G16        A01X+065827Y+123228X0180Y         S1      
327GND              PEX1  -F16        A01X+065827Y+123602X0180Y         S1      
327GND              PEX1  -B12        A01X+064331Y+125098X0180Y         S1      
327GND              PEX1  -A12        A01X+064331Y+125472X0180Y         S1      
327GND              PEX1  -C13        A01X+064705Y+124724X0180Y         S1      
327GND              PEX1  -B14        A01X+065079Y+125098X0180Y         S1      
327GND              PEX1  -A14        A01X+065079Y+125472X0180Y         S1      
327GND              PEX1  -C15        A01X+065453Y+124724X0180Y         S1      
327GND              PEX1  -D15        A01X+065453Y+124350X0180Y         S1      
327GND              PEX1  -E12        A01X+064331Y+123976X0180Y         S1      
327GND              PEX1  -E13        A01X+064705Y+123976X0180Y         S1      
327GND              PEX1  -E14        A01X+065079Y+123976X0180Y         S1      
327GND              PEX1  -E15        A01X+065453Y+123976X0180Y         S1      
327GND              PEX1  -D13        A01X+064705Y+124350X0180Y         S1      
327GND              PEX1  -H15        A01X+065453Y+122854X0180Y         S1      
327GND              PEX1  -J15        A01X+065453Y+122480X0180Y         S1      
327GND              PEX1  -G14        A01X+065079Y+123228X0180Y         S1      
327GND              PEX1  -J13        A01X+064705Y+122480X0180Y         S1      
327GND              PEX1  -H13        A01X+064705Y+122854X0180Y         S1      
327GND              PEX1  -F14        A01X+065079Y+123602X0180Y         S1      
327GND              PEX1  -G12        A01X+064331Y+123228X0180Y         S1      
327GND              PEX1  -F12        A01X+064331Y+123602X0180Y         S1      
327GND              PEX1  -C7         A01X+062461Y+124724X0180Y         S1      
327GND              PEX1  -A8         A01X+062835Y+125472X0180Y         S1      
327GND              PEX1  -B10        A01X+063583Y+125098X0180Y         S1      
327GND              PEX1  -A10        A01X+063583Y+125472X0180Y         S1      
327GND              PEX1  -C11        A01X+063957Y+124724X0180Y         S1      
327GND              PEX1  -E7         A01X+062461Y+123976X0180Y         S1      
327GND              PEX1  -D7         A01X+062461Y+124350X0180Y         S1      
327GND              PEX1  -B8         A01X+062835Y+125098X0180Y         S1      
327GND              PEX1  -E8         A01X+062835Y+123976X0180Y         S1      
327GND              PEX1  -E9         A01X+063209Y+123976X0180Y         S1      
327GND              PEX1  -E10        A01X+063583Y+123976X0180Y         S1      
327GND              PEX1  -E11        A01X+063957Y+123976X0180Y         S1      
327GND              PEX1  -D11        A01X+063957Y+124350X0180Y         S1      
327GND              PEX1  -D9         A01X+063209Y+124350X0180Y         S1      
327GND              PEX1  -C9         A01X+063209Y+124724X0180Y         S1      
327GND              PEX1  -H11        A01X+063957Y+122854X0180Y         S1      
327GND              PEX1  -J11        A01X+063957Y+122480X0180Y         S1      
327GND              PEX1  -G10        A01X+063583Y+123228X0180Y         S1      
327GND              PEX1  -F10        A01X+063583Y+123602X0180Y         S1      
327GND              PEX1  -G8         A01X+062835Y+123228X0180Y         S1      
327GND              PEX1  -F8         A01X+062835Y+123602X0180Y         S1      
327GND              PEX1  -H7         A01X+062461Y+122854X0180Y         S1      
327GND              PEX1  -J7         A01X+062461Y+122480X0180Y         S1      
327GND              PEX1  -J9         A01X+063209Y+122480X0180Y         S1      
327GND              PEX1  -H9         A01X+063209Y+122854X0180Y         S1      
327GND              PEX1  -B4         A01X+061339Y+125098X0180Y         S1      
327GND              PEX1  -A4         A01X+061339Y+125472X0180Y         S1      
327GND              PEX1  -C3         A01X+060965Y+124724X0180Y         S1      
327GND              PEX1  -C5         A01X+061713Y+124724X0180Y         S1      
327GND              PEX1  -B6         A01X+062087Y+125098X0180Y         S1      
327GND              PEX1  -A6         A01X+062087Y+125472X0180Y         S1      
327GND              PEX1  -E3         A01X+060965Y+123976X0180Y         S1      
327GND              PEX1  -D3         A01X+060965Y+124350X0180Y         S1      
327GND              PEX1  -E4         A01X+061339Y+123976X0180Y         S1      
327GND              PEX1  -E6         A01X+062087Y+123976X0180Y         S1      
327GND              PEX1  -E5         A01X+061713Y+123976X0180Y         S1      
327GND              PEX1  -D5         A01X+061713Y+124350X0180Y         S1      
327GND              PEX1  -F4         A01X+061339Y+123602X0180Y         S1      
327GND              PEX1  -G4         A01X+061339Y+123228X0180Y         S1      
327GND              PEX1  -H3         A01X+060965Y+122854X0180Y         S1      
327GND              PEX1  -J3         A01X+060965Y+122480X0180Y         S1      
327GND              PEX1  -J5         A01X+061713Y+122480X0180Y         S1      
327GND              PEX1  -H5         A01X+061713Y+122854X0180Y         S1      
327GND              PEX1  -G6         A01X+062087Y+123228X0180Y         S1      
327GND              PEX1  -F6         A01X+062087Y+123602X0180Y         S1      
327GND              PEX1  -B2         A01X+060590Y+125098X0180Y         S1      
327GND              PEX1  -A2         A01X+060590Y+125472X0180Y         S1      
327GND              PEX1  -D2         A01X+060590Y+124350X0180Y         S1      
327GND              PEX1  -F2         A01X+060590Y+123602X0180Y         S1      
327GND              PEX1  -G2         A01X+060590Y+123228X0180Y         S1      
327GND              PEX1  -J2         A01X+060590Y+122480X0180Y         S1      
327GND              PEX1  -B46        A01X+077047Y+125098X0180Y         S1      
327GND              PEX1  -A46        A01X+077047Y+125472X0180Y         S1      
327GND              PEX1  -B49        A01X+078169Y+125098X0180Y         S1      
327GND              PEX1  -B48        A01X+077795Y+125098X0180Y         S1      
327GND              PEX1  -C47        A01X+077421Y+124724X0180Y         S1      
327GND              PEX1  -D47        A01X+077421Y+124350X0180Y         S1      
327GND              PEX1  -D48        A01X+077795Y+124350X0180Y         S1      
327GND              PEX1  -D49        A01X+078169Y+124350X0180Y         S1      
327GND              PEX1  -E46        A01X+077047Y+123976X0180Y         S1      
327GND              PEX1  -E47        A01X+077421Y+123976X0180Y         S1      
327GND              PEX1  -A48        A01X+077795Y+125472X0180Y         S1      
327GND              PEX1  -J49        A01X+078169Y+122480X0180Y         S1      
327GND              PEX1  -J48        A01X+077795Y+122480X0180Y         S1      
327GND              PEX1  -J47        A01X+077421Y+122480X0180Y         S1      
327GND              PEX1  -H47        A01X+077421Y+122854X0180Y         S1      
327GND              PEX1  -F46        A01X+077047Y+123602X0180Y         S1      
327GND              PEX1  -G46        A01X+077047Y+123228X0180Y         S1      
327GND              PEX1  -G49        A01X+078169Y+123228X0180Y         S1      
327GND              PEX1  -G48        A01X+077795Y+123228X0180Y         S1      
327GND              PEX1  -F48        A01X+077795Y+123602X0180Y         S1      
327GND              PEX1  -F49        A01X+078169Y+123602X0180Y         S1      
327GND              PEX1  -L49        A01X+078169Y+121732X0180Y         S1      
327GND              PEX1  -L48        A01X+077795Y+121732X0180Y         S1      
327GND              PEX1  -K47        A01X+077421Y+122106X0180Y         S1      
327GND              PEX1  -K46        A01X+077047Y+122106X0180Y         S1      
327GND              PEX1  -N49        A01X+078169Y+120984X0180Y         S1      
327GND              PEX1  -N48        A01X+077795Y+120984X0180Y         S1      
327GND              PEX1  -M47        A01X+077421Y+121358X0180Y         S1      
327GND              PEX1  -M46        A01X+077047Y+121358X0180Y         S1      
327GND              PEX1  -R49        A01X+078169Y+120236X0180Y         S1      
327GND              PEX1  -R48        A01X+077795Y+120236X0180Y         S1      
327GND              PEX1  -P47        A01X+077421Y+120610X0180Y         S1      
327GND              PEX1  -P46        A01X+077047Y+120610X0180Y         S1      
327GND              PEX1  -T47        A01X+077421Y+119862X0180Y         S1      
327GND              PEX1  -T46        A01X+077047Y+119862X0180Y         S1      
327GND              PEX1  -B42        A01X+075551Y+125098X0180Y         S1      
327GND              PEX1  -A42        A01X+075551Y+125472X0180Y         S1      
327GND              PEX1  -C43        A01X+075925Y+124724X0180Y         S1      
327GND              PEX1  -D43        A01X+075925Y+124350X0180Y         S1      
327GND              PEX1  -B44        A01X+076299Y+125098X0180Y         S1      
327GND              PEX1  -A44        A01X+076299Y+125472X0180Y         S1      
327GND              PEX1  -C45        A01X+076673Y+124724X0180Y         S1      
327GND              PEX1  -D45        A01X+076673Y+124350X0180Y         S1      
327GND              PEX1  -E42        A01X+075551Y+123976X0180Y         S1      
327GND              PEX1  -E43        A01X+075925Y+123976X0180Y         S1      
327GND              PEX1  -E44        A01X+076299Y+123976X0180Y         S1      
327GND              PEX1  -E45        A01X+076673Y+123976X0180Y         S1      
327GND              PEX1  -J43        A01X+075925Y+122480X0180Y         S1      
327GND              PEX1  -H43        A01X+075925Y+122854X0180Y         S1      
327GND              PEX1  -G42        A01X+075551Y+123228X0180Y         S1      
327GND              PEX1  -F42        A01X+075551Y+123602X0180Y         S1      
327GND              PEX1  -J45        A01X+076673Y+122480X0180Y         S1      
327GND              PEX1  -H45        A01X+076673Y+122854X0180Y         S1      
327GND              PEX1  -G44        A01X+076299Y+123228X0180Y         S1      
327GND              PEX1  -F44        A01X+076299Y+123602X0180Y         S1      
327GND              PEX1  -K45        A01X+076673Y+122106X0180Y         S1      
327GND              PEX1  -L45        A01X+076673Y+121732X0180Y         S1      
327GND              PEX1  -K44        A01X+076299Y+122106X0180Y         S1      
327GND              PEX1  -K43        A01X+075925Y+122106X0180Y         S1      
327GND              PEX1  -K42        A01X+075551Y+122106X0180Y         S1      
327GND              PEX1  -L42        A01X+075551Y+121732X0180Y         S1      
327GND              PEX1  -M43        A01X+075925Y+121358X0180Y         S1      
327GND              PEX1  -M44        A01X+076299Y+121358X0180Y         S1      
327GND              PEX1  -M45        A01X+076673Y+121358X0180Y         S1      
327GND              PEX1  -N45        A01X+076673Y+120984X0180Y         S1      
327GND              PEX1  -N42        A01X+075551Y+120984X0180Y         S1      
327GND              PEX1  -P45        A01X+076673Y+120610X0180Y         S1      
327GND              PEX1  -P44        A01X+076299Y+120610X0180Y         S1      
327GND              PEX1  -P43        A01X+075925Y+120610X0180Y         S1      
327GND              PEX1  -R42        A01X+075551Y+120236X0180Y         S1      
327GND              PEX1  -R45        A01X+076673Y+120236X0180Y         S1      
327GND              PEX1  -T45        A01X+076673Y+119862X0180Y         S1      
327GND              PEX1  -T44        A01X+076299Y+119862X0180Y         S1      
327GND              PEX1  -T43        A01X+075925Y+119862X0180Y         S1      
327GND              PEX1  -C41        A01X+075177Y+124724X0180Y         S1      
327GND              PEX1  -D41        A01X+075177Y+124350X0180Y         S1      
327GND              PEX1  -E41        A01X+075177Y+123976X0180Y         S1      
327GND              PEX1  -J41        A01X+075177Y+122480X0180Y         S1      
327GND              PEX1  -H41        A01X+075177Y+122854X0180Y         S1      
327GND              PEX1  -K41        A01X+075177Y+122106X0180Y         S1      
327GND              PEX1  -L41        A01X+075177Y+121732X0180Y         S1      
327GND              PEX1  -N41        A01X+075177Y+120984X0180Y         S1      
327GND              PEX1  -R41        A01X+075177Y+120236X0180Y         S1      
327GND              PEX1  -AY42       A01X+075551Y+110886X0180Y         S1      
327GND              PEX1  -AY43       A01X+075925Y+110886X0180Y         S1      
327GND              PEX1  -AR42       A01X+075551Y+112756X0180Y         S1      
327GND              PEX1  -AP43       A01X+075925Y+113130X0180Y         S1      
327GND              PEX1  -AN42       A01X+075551Y+113504X0180Y         S1      
327GND              PEX1  -AV43       A01X+075925Y+111634X0180Y         S1      
327GND              PEX1  -AU42       A01X+075551Y+112008X0180Y         S1      
327GND              PEX1  -AT43       A01X+075925Y+112382X0180Y         S1      
327GND              PEX1  -AR41       A01X+075177Y+112756X0180Y         S1      
327GND              PEX1  -AN41       A01X+075177Y+113504X0180Y         S1      
327GND              PEX1  -AW41M      A01X+075177Y+111260X0180Y         S1      
327GND              PEX1  -AU41       A01X+075177Y+112008X0180Y         S1      
327GND              PEX1  -AR49       A01X+078169Y+112756X0180Y         S1      
327GND              PEX1  -AR48       A01X+077795Y+112756X0180Y         S1      
327GND              PEX1  -AP47       A01X+077421Y+113130X0180Y         S1      
327GND              PEX1  -AP46       A01X+077047Y+113130X0180Y         S1      
327GND              PEX1  -AN48       A01X+077795Y+113504X0180Y         S1      
327GND              PEX1  -AN49       A01X+078169Y+113504X0180Y         S1      
327GND              PEX1  -AY46       A01X+077047Y+110886X0180Y         S1      
327GND              PEX1  -AY47       A01X+077421Y+110886X0180Y         S1      
327GND              PEX1  -AV46       A01X+077047Y+111634X0180Y         S1      
327GND              PEX1  -AV47       A01X+077421Y+111634X0180Y         S1      
327GND              PEX1  -AW48       A01X+077795Y+111260X0180Y         S1      
327GND              PEX1  -AW49       A01X+078169Y+111260X0180Y         S1      
327GND              PEX1  -AT46       A01X+077047Y+112382X0180Y         S1      
327GND              PEX1  -AT47       A01X+077421Y+112382X0180Y         S1      
327GND              PEX1  -AU48       A01X+077795Y+112008X0180Y         S1      
327GND              PEX1  -AU49       A01X+078169Y+112008X0180Y         S1      
327GND              PEX1  -AR45       A01X+076673Y+112756X0180Y         S1      
327GND              PEX1  -AP45       A01X+076673Y+113130X0180Y         S1      
327GND              PEX1  -AP44       A01X+076299Y+113130X0180Y         S1      
327GND              PEX1  -AN45       A01X+076673Y+113504X0180Y         S1      
327GND              PEX1  -AY44       A01X+076299Y+110886X0180Y         S1      
327GND              PEX1  -AY45       A01X+076673Y+110886X0180Y         S1      
327GND              PEX1  -AV45       A01X+076673Y+111634X0180Y         S1      
327GND              PEX1  -AV44       A01X+076299Y+111634X0180Y         S1      
327GND              PEX1  -AW45       A01X+076673Y+111260X0180Y         S1      
327GND              PEX1  -AT45       A01X+076673Y+112382X0180Y         S1      
327GND              PEX1  -AT44       A01X+076299Y+112382X0180Y         S1      
327GND              PEX1  -AU45       A01X+076673Y+112008X0180Y         S1      
327GND              PEX1  -BD46       A01X+077047Y+109390X0180Y         S1      
327GND              PEX1  -BC46       A01X+077047Y+109764X0180Y         S1      
327GND              PEX1  -BB47       A01X+077421Y+110138X0180Y         S1      
327GND              PEX1  -BD48       A01X+077795Y+109390X0180Y         S1      
327GND              PEX1  -BD49       A01X+078169Y+109390X0180Y         S1      
327GND              PEX1  -BC49       A01X+078169Y+109764X0180Y         S1      
327GND              PEX1  -BC48       A01X+077795Y+109764X0180Y         S1      
327GND              PEX1  -BA47       A01X+077421Y+110512X0180Y         S1      
327GND              PEX1  -BA48       A01X+077795Y+110512X0180Y         S1      
327GND              PEX1  -BA49       A01X+078169Y+110512X0180Y         S1      
327GND              PEX1  -BH48       A01X+077795Y+107894X0180Y         S1      
327GND              PEX1  -BH46       A01X+077047Y+107894X0180Y         S1      
327GND              PEX1  -BG47       A01X+077421Y+108268X0180Y         S1      
327GND              PEX1  -BF49       A01X+078169Y+108642X0180Y         S1      
327GND              PEX1  -BF48       A01X+077795Y+108642X0180Y         S1      
327GND              PEX1  -BF47       A01X+077421Y+108642X0180Y         S1      
327GND              PEX1  -BE46       A01X+077047Y+109016X0180Y         S1      
327GND              PEX1  -BE47       A01X+077421Y+109016X0180Y         S1      
327GND              PEX1  -BH49       A01X+078169Y+107894X0180Y         S1      
327GND              PEX1  -BJ46       A01X+077047Y+107520X0180Y         S1      
327GND              PEX1  -BJ48       A01X+077795Y+107520X0180Y         S1      
327GND              PEX1  -BD42       A01X+075551Y+109390X0180Y         S1      
327GND              PEX1  -BD44       A01X+076299Y+109390X0180Y         S1      
327GND              PEX1  -BC42       A01X+075551Y+109764X0180Y         S1      
327GND              PEX1  -BC44       A01X+076299Y+109764X0180Y         S1      
327GND              PEX1  -BB45       A01X+076673Y+110138X0180Y         S1      
327GND              PEX1  -BB43       A01X+075925Y+110138X0180Y         S1      
327GND              PEX1  -BA43       A01X+075925Y+110512X0180Y         S1      
327GND              PEX1  -BA45       A01X+076673Y+110512X0180Y         S1      
327GND              PEX1  -BH44       A01X+076299Y+107894X0180Y         S1      
327GND              PEX1  -BH42       A01X+075551Y+107894X0180Y         S1      
327GND              PEX1  -BG45       A01X+076673Y+108268X0180Y         S1      
327GND              PEX1  -BG43       A01X+075925Y+108268X0180Y         S1      
327GND              PEX1  -BF43       A01X+075925Y+108642X0180Y         S1      
327GND              PEX1  -BF45       A01X+076673Y+108642X0180Y         S1      
327GND              PEX1  -BE42       A01X+075551Y+109016X0180Y         S1      
327GND              PEX1  -BE43       A01X+075925Y+109016X0180Y         S1      
327GND              PEX1  -BE44       A01X+076299Y+109016X0180Y         S1      
327GND              PEX1  -BE45       A01X+076673Y+109016X0180Y         S1      
327GND              PEX1  -BJ42       A01X+075551Y+107520X0180Y         S1      
327GND              PEX1  -BJ44       A01X+076299Y+107520X0180Y         S1      
327GND              PEX1  -BC38       A01X+074055Y+109764X0180Y         S1      
327GND              PEX1  -BB39       A01X+074429Y+110138X0180Y         S1      
327GND              PEX1  -BD38       A01X+074055Y+109390X0180Y         S1      
327GND              PEX1  -BA41       A01X+075177Y+110512X0180Y         S1      
327GND              PEX1  -BD40       A01X+074803Y+109390X0180Y         S1      
327GND              PEX1  -BC40       A01X+074803Y+109764X0180Y         S1      
327GND              PEX1  -BB41       A01X+075177Y+110138X0180Y         S1      
327GND              PEX1  -BH38       A01X+074055Y+107894X0180Y         S1      
327GND              PEX1  -BE38       A01X+074055Y+109016X0180Y         S1      
327GND              PEX1  -BE39       A01X+074429Y+109016X0180Y         S1      
327GND              PEX1  -BF39       A01X+074429Y+108642X0180Y         S1      
327GND              PEX1  -BG39       A01X+074429Y+108268X0180Y         S1      
327GND              PEX1  -BH40       A01X+074803Y+107894X0180Y         S1      
327GND              PEX1  -BG41       A01X+075177Y+108268X0180Y         S1      
327GND              PEX1  -BF41       A01X+075177Y+108642X0180Y         S1      
327GND              PEX1  -BE40       A01X+074803Y+109016X0180Y         S1      
327GND              PEX1  -BE41       A01X+075177Y+109016X0180Y         S1      
327GND              PEX1  -BJ38       A01X+074055Y+107520X0180Y         S1      
327GND              PEX1  -BJ40       A01X+074803Y+107520X0180Y         S1      
327GND              PEX1  -BB33       A01X+072185Y+110138X0180Y         S1      
327GND              PEX1  -BB35       A01X+072933Y+110138X0180Y         S1      
327GND              PEX1  -BC34       A01X+072559Y+109764X0180Y         S1      
327GND              PEX1  -BD34       A01X+072559Y+109390X0180Y         S1      
327GND              PEX1  -BD36       A01X+073307Y+109390X0180Y         S1      
327GND              PEX1  -BC36       A01X+073307Y+109764X0180Y         S1      
327GND              PEX1  -BB37       A01X+073681Y+110138X0180Y         S1      
327GND              PEX1  -BE33       A01X+072185Y+109016X0180Y         S1      
327GND              PEX1  -BH34       A01X+072559Y+107894X0180Y         S1      
327GND              PEX1  -BG33       A01X+072185Y+108268X0180Y         S1      
327GND              PEX1  -BF33       A01X+072185Y+108642X0180Y         S1      
327GND              PEX1  -BE34       A01X+072559Y+109016X0180Y         S1      
327GND              PEX1  -BE35       A01X+072933Y+109016X0180Y         S1      
327GND              PEX1  -BF35       A01X+072933Y+108642X0180Y         S1      
327GND              PEX1  -BG35       A01X+072933Y+108268X0180Y         S1      
327GND              PEX1  -BH36       A01X+073307Y+107894X0180Y         S1      
327GND              PEX1  -BE36       A01X+073307Y+109016X0180Y         S1      
327GND              PEX1  -BG37       A01X+073681Y+108268X0180Y         S1      
327GND              PEX1  -BF37       A01X+073681Y+108642X0180Y         S1      
327GND              PEX1  -BE37       A01X+073681Y+109016X0180Y         S1      
327GND              PEX1  -BJ34       A01X+072559Y+107520X0180Y         S1      
327GND              PEX1  -BJ36       A01X+073307Y+107520X0180Y         S1      
327GND              PEX1  -BB29       A01X+070689Y+110138X0180Y         S1      
327GND              PEX1  -BB31       A01X+071437Y+110138X0180Y         S1      
327GND              PEX1  -BC30       A01X+071063Y+109764X0180Y         S1      
327GND              PEX1  -BD30       A01X+071063Y+109390X0180Y         S1      
327GND              PEX1  -BC32       A01X+071811Y+109764X0180Y         S1      
327GND              PEX1  -BD32       A01X+071811Y+109390X0180Y         S1      
327GND              PEX1  -BH30       A01X+071063Y+107894X0180Y         S1      
327GND              PEX1  -BG29       A01X+070689Y+108268X0180Y         S1      
327GND              PEX1  -BF29       A01X+070689Y+108642X0180Y         S1      
327GND              PEX1  -BE29       A01X+070689Y+109016X0180Y         S1      
327GND              PEX1  -BH32       A01X+071811Y+107894X0180Y         S1      
327GND              PEX1  -BG31       A01X+071437Y+108268X0180Y         S1      
327GND              PEX1  -BF31       A01X+071437Y+108642X0180Y         S1      
327GND              PEX1  -BE31       A01X+071437Y+109016X0180Y         S1      
327GND              PEX1  -BE30       A01X+071063Y+109016X0180Y         S1      
327GND              PEX1  -BE32       A01X+071811Y+109016X0180Y         S1      
327GND              PEX1  -BJ30       A01X+071063Y+107520X0180Y         S1      
327GND              PEX1  -BJ32       A01X+071811Y+107520X0180Y         S1      
327GND              PEX1  -BB25       A01X+069193Y+110138X0180Y         S1      
327GND              PEX1  -BD26       A01X+069567Y+109390X0180Y         S1      
327GND              PEX1  -BC26       A01X+069567Y+109764X0180Y         S1      
327GND              PEX1  -BB27       A01X+069941Y+110138X0180Y         S1      
327GND              PEX1  -BD28       A01X+070315Y+109390X0180Y         S1      
327GND              PEX1  -BC28       A01X+070315Y+109764X0180Y         S1      
327GND              PEX1  -BG25       A01X+069193Y+108268X0180Y         S1      
327GND              PEX1  -BF25       A01X+069193Y+108642X0180Y         S1      
327GND              PEX1  -BE26       A01X+069567Y+109016X0180Y         S1      
327GND              PEX1  -BE27       A01X+069941Y+109016X0180Y         S1      
327GND              PEX1  -BF27       A01X+069941Y+108642X0180Y         S1      
327GND              PEX1  -BE25       A01X+069193Y+109016X0180Y         S1      
327GND              PEX1  -BH26       A01X+069567Y+107894X0180Y         S1      
327GND              PEX1  -BH28       A01X+070315Y+107894X0180Y         S1      
327GND              PEX1  -BG27       A01X+069941Y+108268X0180Y         S1      
327GND              PEX1  -BE28       A01X+070315Y+109016X0180Y         S1      
327GND              PEX1  -BJ26       A01X+069567Y+107520X0180Y         S1      
327GND              PEX1  -BJ28       A01X+070315Y+107520X0180Y         S1      
327GND              PEX1  -BC20       A01X+067323Y+109764X0180Y         S1      
327GND              PEX1  -BD20       A01X+067323Y+109390X0180Y         S1      
327GND              PEX1  -BD22       A01X+068071Y+109390X0180Y         S1      
327GND              PEX1  -BC22       A01X+068071Y+109764X0180Y         S1      
327GND              PEX1  -BB21       A01X+067697Y+110138X0180Y         S1      
327GND              PEX1  -BB23       A01X+068445Y+110138X0180Y         S1      
327GND              PEX1  -BD24       A01X+068819Y+109390X0180Y         S1      
327GND              PEX1  -BC24       A01X+068819Y+109764X0180Y         S1      
327GND              PEX1  -BE20       A01X+067323Y+109016X0180Y         S1      
327GND              PEX1  -BH20       A01X+067323Y+107894X0180Y         S1      
327GND              PEX1  -BG21       A01X+067697Y+108268X0180Y         S1      
327GND              PEX1  -BF21       A01X+067697Y+108642X0180Y         S1      
327GND              PEX1  -BE21       A01X+067697Y+109016X0180Y         S1      
327GND              PEX1  -BE22       A01X+068071Y+109016X0180Y         S1      
327GND              PEX1  -BH22       A01X+068071Y+107894X0180Y         S1      
327GND              PEX1  -BG23       A01X+068445Y+108268X0180Y         S1      
327GND              PEX1  -BF23       A01X+068445Y+108642X0180Y         S1      
327GND              PEX1  -BE23       A01X+068445Y+109016X0180Y         S1      
327GND              PEX1  -BE24       A01X+068819Y+109016X0180Y         S1      
327GND              PEX1  -BH24       A01X+068819Y+107894X0180Y         S1      
327GND              PEX1  -BJ20       A01X+067323Y+107520X0180Y         S1      
327GND              PEX1  -BJ22       A01X+068071Y+107520X0180Y         S1      
327GND              PEX1  -BJ24       A01X+068819Y+107520X0180Y         S1      
327GND              PEX1  -BD18       A01X+066575Y+109390X0180Y         S1      
327GND              PEX1  -BD16       A01X+065827Y+109390X0180Y         S1      
327GND              PEX1  -BC18       A01X+066575Y+109764X0180Y         S1      
327GND              PEX1  -BC16       A01X+065827Y+109764X0180Y         S1      
327GND              PEX1  -BB17       A01X+066201Y+110138X0180Y         S1      
327GND              PEX1  -BB19       A01X+066949Y+110138X0180Y         S1      
327GND              PEX1  -BE16       A01X+065827Y+109016X0180Y         S1      
327GND              PEX1  -BH16       A01X+065827Y+107894X0180Y         S1      
327GND              PEX1  -BG17       A01X+066201Y+108268X0180Y         S1      
327GND              PEX1  -BF17       A01X+066201Y+108642X0180Y         S1      
327GND              PEX1  -BE17       A01X+066201Y+109016X0180Y         S1      
327GND              PEX1  -BE18       A01X+066575Y+109016X0180Y         S1      
327GND              PEX1  -BE19       A01X+066949Y+109016X0180Y         S1      
327GND              PEX1  -BF19       A01X+066949Y+108642X0180Y         S1      
327GND              PEX1  -BG19       A01X+066949Y+108268X0180Y         S1      
327GND              PEX1  -BH18       A01X+066575Y+107894X0180Y         S1      
327GND              PEX1  -BJ16       A01X+065827Y+107520X0180Y         S1      
327GND              PEX1  -BJ18       A01X+066575Y+107520X0180Y         S1      
327GND              PEX1  -BD14       A01X+065079Y+109390X0180Y         S1      
327GND              PEX1  -BC14       A01X+065079Y+109764X0180Y         S1      
327GND              PEX1  -BB15       A01X+065453Y+110138X0180Y         S1      
327GND              PEX1  -BB13       A01X+064705Y+110138X0180Y         S1      
327GND              PEX1  -BF13       A01X+064705Y+108642X0180Y         S1      
327GND              PEX1  -BE13       A01X+064705Y+109016X0180Y         S1      
327GND              PEX1  -BG13       A01X+064705Y+108268X0180Y         S1      
327GND              PEX1  -BE14       A01X+065079Y+109016X0180Y         S1      
327GND              PEX1  -BH14       A01X+065079Y+107894X0180Y         S1      
327GND              PEX1  -BG15       A01X+065453Y+108268X0180Y         S1      
327GND              PEX1  -BF15       A01X+065453Y+108642X0180Y         S1      
327GND              PEX1  -BE15       A01X+065453Y+109016X0180Y         S1      
327GND              PEX1  -BJ14       A01X+065079Y+107520X0180Y         S1      
327GND              PEX1  -BC12       A01X+064331Y+109764X0180Y         S1      
327GND              PEX1  -BD12       A01X+064331Y+109390X0180Y         S1      
327GND              PEX1  -BH12       A01X+064331Y+107894X0180Y         S1      
327GND              PEX1  -BE12       A01X+064331Y+109016X0180Y         S1      
327GND              PEX1  -BJ12       A01X+064331Y+107520X0180Y         S1      
327GND              PEX1  -BD10       A01X+063583Y+109390X0180Y         S1      
327GND              PEX1  -BC10       A01X+063583Y+109764X0180Y         S1      
327GND              PEX1  -BB9        A01X+063209Y+110138X0180Y         S1      
327GND              PEX1  -BB11       A01X+063957Y+110138X0180Y         S1      
327GND              PEX1  -BG9        A01X+063209Y+108268X0180Y         S1      
327GND              PEX1  -BF9        A01X+063209Y+108642X0180Y         S1      
327GND              PEX1  -BH10       A01X+063583Y+107894X0180Y         S1      
327GND              PEX1  -BG11       A01X+063957Y+108268X0180Y         S1      
327GND              PEX1  -BF11       A01X+063957Y+108642X0180Y         S1      
327GND              PEX1  -BE9        A01X+063209Y+109016X0180Y         S1      
327GND              PEX1  -BE10       A01X+063583Y+109016X0180Y         S1      
327GND              PEX1  -BE11       A01X+063957Y+109016X0180Y         S1      
327GND              PEX1  -BJ10       A01X+063583Y+107520X0180Y         S1      
327GND              PEX0  -K25        A01X+023484Y+122106X0180Y         S1      
327GND              PEX0  -BH49       A01X+032461Y+107894X0180Y         S1      
327GND              C2598 -2          A01X+054260Y+077989X0198Y0197     S1      
327GND              C2597 -2          A01X+053245Y+077989X0198Y0197R180 S1      
317GND              VIA   -    MD0100PA00X+034372Y+135068X0180Y         S0      
317GND              VIA   -    MD0100PA00X+034372Y+134569X0180Y         S0      
317GND              VIA   -    MD0080PA00X+033294Y+134819X0160Y         S0      
317GND              VIA   -    MD0100PA00X+033148Y+135068X0180Y         S0      
317GND              VIA   -    MD0100PA00X+033148Y+134569X0180Y         S0      
317GND              VIA   -    MD0100PA00X+033876Y+135760X0180Y         S0      
317GND              VIA   -    MD0080PA00X+033730Y+136010X0160Y         S0      
317GND              VIA   -    MD0100PA00X+034372Y+135760X0180Y         S0      
317GND              VIA   -    MD0080PA00X+033294Y+136010X0160Y         S0      
317GND              VIA   -    MD0100PA00X+033148Y+135760X0180Y         S0      
317GND              VIA   -    MD0080PA00X+034518Y+134819X0160Y         S0      
317GND              VIA   -    MD0080PA00X+034518Y+136010X0160Y         S0      
317GND              VIA   -    MD0100PA00X+028252Y+135068X0180Y         S0      
317GND              VIA   -    MD0080PA00X+028398Y+134819X0160Y         S0      
317GND              VIA   -    MD0100PA00X+029476Y+134569X0180Y         S0      
317GND              VIA   -    MD0100PA00X+029476Y+135068X0180Y         S0      
317GND              VIA   -    MD0080PA00X+029622Y+134819X0160Y         S0      
317GND              VIA   -    MD0080PA00X+028834Y+134819X0160Y         S0      
317GND              VIA   -    MD0100PA00X+028980Y+134569X0180Y         S0      
317GND              VIA   -    MD0100PA00X+028980Y+135068X0180Y         S0      
317GND              VIA   -    MD0100PA00X+028252Y+135760X0180Y         S0      
317GND              VIA   -    MD0080PA00X+028398Y+136010X0160Y         S0      
317GND              VIA   -    MD0080PA00X+029622Y+136010X0160Y         S0      
317GND              VIA   -    MD0100PA00X+029476Y+135760X0180Y         S0      
317GND              VIA   -    MD0080PA00X+028834Y+136010X0160Y         S0      
317GND              VIA   -    MD0100PA00X+028980Y+135760X0180Y         S0      
317GND              VIA   -    MD0100PA00X+030700Y+134569X0180Y         S0      
317GND              VIA   -    MD0100PA00X+030700Y+135068X0180Y         S0      
317GND              VIA   -    MD0080PA00X+030058Y+134819X0160Y         S0      
317GND              VIA   -    MD0100PA00X+030204Y+135068X0180Y         S0      
317GND              VIA   -    MD0100PA00X+030204Y+134569X0180Y         S0      
317GND              VIA   -    MD0080PA00X+030846Y+134819X0160Y         S0      
317GND              VIA   -    MD0100PA00X+030700Y+135760X0180Y         S0      
317GND              VIA   -    MD0100PA00X+030204Y+135760X0180Y         S0      
317GND              VIA   -    MD0080PA00X+030058Y+136010X0160Y         S0      
317GND              VIA   -    MD0080PA00X+030846Y+136010X0160Y         S0      
317GND              VIA   -    MD0080PA00X+032506Y+134819X0160Y         S0      
317GND              VIA   -    MD0100PA00X+032652Y+135068X0180Y         S0      
317GND              VIA   -    MD0100PA00X+032652Y+134569X0180Y         S0      
317GND              VIA   -    MD0100PA00X+031428Y+135068X0180Y         S0      
317GND              VIA   -    MD0100PA00X+031428Y+134569X0180Y         S0      
317GND              VIA   -    MD0080PA00X+031282Y+134819X0160Y         S0      
317GND              VIA   -    MD0080PA00X+032070Y+134819X0160Y         S0      
317GND              VIA   -    MD0100PA00X+031924Y+134569X0180Y         S0      
317GND              VIA   -    MD0100PA00X+031924Y+135068X0180Y         S0      
317GND              VIA   -    MD0080PA00X+032506Y+136010X0160Y         S0      
317GND              VIA   -    MD0100PA00X+032652Y+135760X0180Y         S0      
317GND              VIA   -    MD0080PA00X+031282Y+136010X0160Y         S0      
317GND              VIA   -    MD0100PA00X+031428Y+135760X0180Y         S0      
317GND              VIA   -    MD0080PA00X+032070Y+136010X0160Y         S0      
317GND              VIA   -    MD0100PA00X+031924Y+135760X0180Y         S0      
317GND              VIA   -    MD0100PA00X+033876Y+134569X0180Y         S0      
317GND              VIA   -    MD0100PA00X+033876Y+135068X0180Y         S0      
317GND              VIA   -    MD0080PA00X+033730Y+134819X0160Y         S0      
317GND              VIA   -    MD0100PA00X+024580Y+136260X0180Y         S0      
317GND              VIA   -    MD0100PA00X+024580Y+135760X0180Y         S0      
317GND              VIA   -    MD0080PA00X+023938Y+136010X0160Y         S0      
317GND              VIA   -    MD0100PA00X+024084Y+136260X0180Y         S0      
317GND              VIA   -    MD0100PA00X+024084Y+135760X0180Y         S0      
317GND              VIA   -    MD0100PA00X+024580Y+136989X0180Y         S0      
317GND              VIA   -    MD0100PA00X+024580Y+137488X0180Y         S0      
317GND              VIA   -    MD0100PA00X+024580Y+138180X0180Y         S0      
317GND              VIA   -    MD0080PA00X+023938Y+137238X0160Y         S0      
317GND              VIA   -    MD0080PA00X+023938Y+138430X0160Y         S0      
317GND              VIA   -    MD0100PA00X+024084Y+136989X0180Y         S0      
317GND              VIA   -    MD0100PA00X+024084Y+137488X0180Y         S0      
317GND              VIA   -    MD0100PA00X+024084Y+138180X0180Y         S0      
317GND              VIA   -    MD0100PA00X+024580Y+138679X0180Y         S0      
317GND              VIA   -    MD0100PA00X+024084Y+138679X0180Y         S0      
317GND              VIA   -    MD0100PA00X+025308Y+134569X0180Y         S0      
317GND              VIA   -    MD0100PA00X+025308Y+135068X0180Y         S0      
317GND              VIA   -    MD0080PA00X+025162Y+134819X0160Y         S0      
317GND              VIA   -    MD0100PA00X+025804Y+134569X0180Y         S0      
317GND              VIA   -    MD0100PA00X+025804Y+135068X0180Y         S0      
317GND              VIA   -    MD0080PA00X+025950Y+134819X0160Y         S0      
317GND              VIA   -    MD0080PA00X+026386Y+134819X0160Y         S0      
317GND              VIA   -    MD0100PA00X+025308Y+135760X0180Y         S0      
317GND              VIA   -    MD0080PA00X+025162Y+136010X0160Y         S0      
317GND              VIA   -    MD0100PA00X+025804Y+135760X0180Y         S0      
317GND              VIA   -    MD0080PA00X+025950Y+136010X0160Y         S0      
317GND              VIA   -    MD0080PA00X+026386Y+136010X0160Y         S0      
317GND              VIA   -    MD0100PA00X+027028Y+135068X0180Y         S0      
317GND              VIA   -    MD0100PA00X+027028Y+134569X0180Y         S0      
317GND              VIA   -    MD0080PA00X+027174Y+134819X0160Y         S0      
317GND              VIA   -    MD0100PA00X+026532Y+135068X0180Y         S0      
317GND              VIA   -    MD0100PA00X+026532Y+134569X0180Y         S0      
317GND              VIA   -    MD0100PA00X+027756Y+134569X0180Y         S0      
317GND              VIA   -    MD0100PA00X+027756Y+135068X0180Y         S0      
317GND              VIA   -    MD0080PA00X+027610Y+134819X0160Y         S0      
317GND              VIA   -    MD0100PA00X+027028Y+135760X0180Y         S0      
317GND              VIA   -    MD0080PA00X+027174Y+136010X0160Y         S0      
317GND              VIA   -    MD0100PA00X+026532Y+135760X0180Y         S0      
317GND              VIA   -    MD0100PA00X+027756Y+135760X0180Y         S0      
317GND              VIA   -    MD0080PA00X+027610Y+136010X0160Y         S0      
317GND              VIA   -    MD0100PA00X+028252Y+134569X0180Y         S0      
317GND              VIA   -    MD0080PA00X+036178Y+139658X0160Y         S0      
317GND              VIA   -    MD0080PA00X+036966Y+139658X0160Y         S0      
317GND              VIA   -    MD0100PA00X+036820Y+139908X0180Y         S0      
317GND              VIA   -    MD0100PA00X+036820Y+139409X0180Y         S0      
317GND              VIA   -    MD0100PA00X+036820Y+138679X0180Y         S0      
317GND              VIA   -    MD0100PA00X+036324Y+138679X0180Y         S0      
317GND              VIA   -    MD0100PA00X+036324Y+139409X0180Y         S0      
317GND              VIA   -    MD0100PA00X+036324Y+139908X0180Y         S0      
317GND              VIA   -    MD0080PA00X+036178Y+140850X0160Y         S0      
317GND              VIA   -    MD0080PA00X+036966Y+140850X0160Y         S0      
317GND              VIA   -    MD0100PA00X+036820Y+140600X0180Y         S0      
317GND              VIA   -    MD0100PA00X+036820Y+141099X0180Y         S0      
317GND              VIA   -    MD0100PA00X+036324Y+141099X0180Y         S0      
317GND              VIA   -    MD0100PA00X+036324Y+140600X0180Y         S0      
317GND              VIA   -    MD0100PA00X+035596Y+134560X0180Y         S0      
317GND              VIA   -    MD0080PA00X+035742Y+134819X0160Y         S0      
317GND              VIA   -    MD0080PA00X+034954Y+134819X0160Y         S0      
317GND              VIA   -    MD0100PA00X+035100Y+135068X0180Y         S0      
317GND              VIA   -    MD0100PA00X+035100Y+134560X0180Y         S0      
317GND              VIA   -    MD0100PA00X+035596Y+135068X0180Y         S0      
317GND              VIA   -    MD0100PA00X+035596Y+135760X0180Y         S0      
317GND              VIA   -    MD0080PA00X+035742Y+136010X0160Y         S0      
317GND              VIA   -    MD0080PA00X+034954Y+136010X0160Y         S0      
317GND              VIA   -    MD0100PA00X+035100Y+135760X0180Y         S0      
317GND              VIA   -    MD0080PA00X+036178Y+134819X0160Y         S0      
317GND              VIA   -    MD0080PA00X+036966Y+134819X0160Y         S0      
317GND              VIA   -    MD0100PA00X+036820Y+135068X0180Y         S0      
317GND              VIA   -    MD0100PA00X+036820Y+134569X0180Y         S0      
317GND              VIA   -    MD0100PA00X+036324Y+135068X0180Y         S0      
317GND              VIA   -    MD0100PA00X+036324Y+134569X0180Y         S0      
317GND              VIA   -    MD0080PA00X+036178Y+136010X0160Y         S0      
317GND              VIA   -    MD0080PA00X+036966Y+136010X0160Y         S0      
317GND              VIA   -    MD0100PA00X+036820Y+135760X0180Y         S0      
317GND              VIA   -    MD0100PA00X+036324Y+135760X0180Y         S0      
317GND              VIA   -    MD0080PA00X+024726Y+134819X0160Y         S0      
317GND              VIA   -    MD0100PA00X+024580Y+135068X0180Y         S0      
317GND              VIA   -    MD0100PA00X+024580Y+134569X0180Y         S0      
317GND              VIA   -    MD0080PA00X+023938Y+134819X0160Y         S0      
317GND              VIA   -    MD0100PA00X+024084Y+135068X0180Y         S0      
317GND              VIA   -    MD0100PA00X+024084Y+134569X0180Y         S0      
317GND              VIA   -    MD0080PA00X+024726Y+136010X0160Y         S0      
317GND              VIA   -    MD0100PA00X+033876Y+140600X0180Y         S0      
317GND              VIA   -    MD0100PA00X+033876Y+141099X0180Y         S0      
317GND              VIA   -    MD0080PA00X+033730Y+140850X0160Y         S0      
317GND              VIA   -    MD0100PA00X+034372Y+140600X0180Y         S0      
317GND              VIA   -    MD0100PA00X+034372Y+141099X0180Y         S0      
317GND              VIA   -    MD0080PA00X+033294Y+140850X0160Y         S0      
317GND              VIA   -    MD0100PA00X+033148Y+140600X0180Y         S0      
317GND              VIA   -    MD0100PA00X+033148Y+141099X0180Y         S0      
317GND              VIA   -    MD0100PA00X+035596Y+136260X0180Y         S0      
317GND              VIA   -    MD0100PA00X+035100Y+136260X0180Y         S0      
317GND              VIA   -    MD0100PA00X+035596Y+136989X0180Y         S0      
317GND              VIA   -    MD0100PA00X+035596Y+137488X0180Y         S0      
317GND              VIA   -    MD0100PA00X+035596Y+138180X0180Y         S0      
317GND              VIA   -    MD0080PA00X+035742Y+138430X0160Y         S0      
317GND              VIA   -    MD0080PA00X+035742Y+137238X0160Y         S0      
317GND              VIA   -    MD0080PA00X+034954Y+137238X0160Y         S0      
317GND              VIA   -    MD0080PA00X+034954Y+138430X0160Y         S0      
317GND              VIA   -    MD0100PA00X+035100Y+136989X0180Y         S0      
317GND              VIA   -    MD0100PA00X+035100Y+138180X0180Y         S0      
317GND              VIA   -    MD0100PA00X+035100Y+137488X0180Y         S0      
317GND              VIA   -    MD0080PA00X+034518Y+138430X0160Y         S0      
317GND              VIA   -    MD0080PA00X+034518Y+137238X0160Y         S0      
317GND              VIA   -    MD0100PA00X+035596Y+139399X0180Y         S0      
317GND              VIA   -    MD0100PA00X+035596Y+139908X0180Y         S0      
317GND              VIA   -    MD0100PA00X+035596Y+138679X0180Y         S0      
317GND              VIA   -    MD0080PA00X+035742Y+139658X0160Y         S0      
317GND              VIA   -    MD0080PA00X+034954Y+139658X0160Y         S0      
317GND              VIA   -    MD0100PA00X+035100Y+138679X0180Y         S0      
317GND              VIA   -    MD0100PA00X+035100Y+139399X0180Y         S0      
317GND              VIA   -    MD0100PA00X+035100Y+139908X0180Y         S0      
317GND              VIA   -    MD0080PA00X+034518Y+139658X0160Y         S0      
317GND              VIA   -    MD0100PA00X+035596Y+141099X0180Y         S0      
317GND              VIA   -    MD0100PA00X+035596Y+140600X0180Y         S0      
317GND              VIA   -    MD0080PA00X+035742Y+140850X0160Y         S0      
317GND              VIA   -    MD0080PA00X+034954Y+140850X0160Y         S0      
317GND              VIA   -    MD0100PA00X+035100Y+140600X0180Y         S0      
317GND              VIA   -    MD0100PA00X+035100Y+141099X0180Y         S0      
317GND              VIA   -    MD0080PA00X+034518Y+140850X0160Y         S0      
317GND              VIA   -    MD0100PA00X+036820Y+136260X0180Y         S0      
317GND              VIA   -    MD0100PA00X+036324Y+136260X0180Y         S0      
317GND              VIA   -    MD0080PA00X+036178Y+137238X0160Y         S0      
317GND              VIA   -    MD0080PA00X+036178Y+138430X0160Y         S0      
317GND              VIA   -    MD0080PA00X+036966Y+138430X0160Y         S0      
317GND              VIA   -    MD0080PA00X+036966Y+137238X0160Y         S0      
317GND              VIA   -    MD0100PA00X+036820Y+136989X0180Y         S0      
317GND              VIA   -    MD0100PA00X+036820Y+138180X0180Y         S0      
317GND              VIA   -    MD0100PA00X+036820Y+137488X0180Y         S0      
317GND              VIA   -    MD0100PA00X+036324Y+137488X0180Y         S0      
317GND              VIA   -    MD0100PA00X+036324Y+138180X0180Y         S0      
317GND              VIA   -    MD0100PA00X+036324Y+136989X0180Y         S0      
317GND              VIA   -    MD0100PA00X+032652Y+138679X0180Y         S0      
317GND              VIA   -    MD0100PA00X+032652Y+139409X0180Y         S0      
317GND              VIA   -    MD0100PA00X+032652Y+139908X0180Y         S0      
317GND              VIA   -    MD0100PA00X+031428Y+139409X0180Y         S0      
317GND              VIA   -    MD0100PA00X+031428Y+139908X0180Y         S0      
317GND              VIA   -    MD0100PA00X+031428Y+138679X0180Y         S0      
317GND              VIA   -    MD0080PA00X+031282Y+139658X0160Y         S0      
317GND              VIA   -    MD0080PA00X+032070Y+139658X0160Y         S0      
317GND              VIA   -    MD0100PA00X+031924Y+139409X0180Y         S0      
317GND              VIA   -    MD0100PA00X+031924Y+139908X0180Y         S0      
317GND              VIA   -    MD0100PA00X+031924Y+138679X0180Y         S0      
317GND              VIA   -    MD0080PA00X+032506Y+140850X0160Y         S0      
317GND              VIA   -    MD0100PA00X+032652Y+140600X0180Y         S0      
317GND              VIA   -    MD0100PA00X+032652Y+141099X0180Y         S0      
317GND              VIA   -    MD0100PA00X+031428Y+140600X0180Y         S0      
317GND              VIA   -    MD0100PA00X+031428Y+141099X0180Y         S0      
317GND              VIA   -    MD0080PA00X+031282Y+140850X0160Y         S0      
317GND              VIA   -    MD0080PA00X+032070Y+140850X0160Y         S0      
317GND              VIA   -    MD0100PA00X+031924Y+140600X0180Y         S0      
317GND              VIA   -    MD0100PA00X+031924Y+141099X0180Y         S0      
317GND              VIA   -    MD0100PA00X+033876Y+136260X0180Y         S0      
317GND              VIA   -    MD0100PA00X+034372Y+136260X0180Y         S0      
317GND              VIA   -    MD0100PA00X+033148Y+136260X0180Y         S0      
317GND              VIA   -    MD0080PA00X+033730Y+138430X0160Y         S0      
317GND              VIA   -    MD0080PA00X+033730Y+137238X0160Y         S0      
317GND              VIA   -    MD0100PA00X+033876Y+137488X0180Y         S0      
317GND              VIA   -    MD0100PA00X+033876Y+136989X0180Y         S0      
317GND              VIA   -    MD0100PA00X+033876Y+138180X0180Y         S0      
317GND              VIA   -    MD0100PA00X+034372Y+137488X0180Y         S0      
317GND              VIA   -    MD0100PA00X+034372Y+136989X0180Y         S0      
317GND              VIA   -    MD0100PA00X+034372Y+138180X0180Y         S0      
317GND              VIA   -    MD0100PA00X+033148Y+136989X0180Y         S0      
317GND              VIA   -    MD0100PA00X+033148Y+138180X0180Y         S0      
317GND              VIA   -    MD0100PA00X+033148Y+137488X0180Y         S0      
317GND              VIA   -    MD0080PA00X+033294Y+137238X0160Y         S0      
317GND              VIA   -    MD0080PA00X+033294Y+138430X0160Y         S0      
317GND              VIA   -    MD0100PA00X+033876Y+139908X0180Y         S0      
317GND              VIA   -    MD0100PA00X+033876Y+139409X0180Y         S0      
317GND              VIA   -    MD0100PA00X+033876Y+138679X0180Y         S0      
317GND              VIA   -    MD0080PA00X+033730Y+139658X0160Y         S0      
317GND              VIA   -    MD0100PA00X+034372Y+139908X0180Y         S0      
317GND              VIA   -    MD0100PA00X+034372Y+139409X0180Y         S0      
317GND              VIA   -    MD0100PA00X+034372Y+138679X0180Y         S0      
317GND              VIA   -    MD0080PA00X+033294Y+139658X0160Y         S0      
317GND              VIA   -    MD0100PA00X+033148Y+138679X0180Y         S0      
317GND              VIA   -    MD0100PA00X+033148Y+139409X0180Y         S0      
317GND              VIA   -    MD0100PA00X+033148Y+139908X0180Y         S0      
317GND              VIA   -    MD0100PA00X+030700Y+138180X0180Y         S0      
317GND              VIA   -    MD0100PA00X+030700Y+136989X0180Y         S0      
317GND              VIA   -    MD0100PA00X+030700Y+137488X0180Y         S0      
317GND              VIA   -    MD0100PA00X+030204Y+136989X0180Y         S0      
317GND              VIA   -    MD0100PA00X+030204Y+138180X0180Y         S0      
317GND              VIA   -    MD0100PA00X+030204Y+137488X0180Y         S0      
317GND              VIA   -    MD0080PA00X+030058Y+138430X0160Y         S0      
317GND              VIA   -    MD0080PA00X+030058Y+137238X0160Y         S0      
317GND              VIA   -    MD0080PA00X+030846Y+137238X0160Y         S0      
317GND              VIA   -    MD0100PA00X+030700Y+139409X0180Y         S0      
317GND              VIA   -    MD0100PA00X+030700Y+139908X0180Y         S0      
317GND              VIA   -    MD0100PA00X+030700Y+138679X0180Y         S0      
317GND              VIA   -    MD0100PA00X+030204Y+139908X0180Y         S0      
317GND              VIA   -    MD0100PA00X+030204Y+139409X0180Y         S0      
317GND              VIA   -    MD0100PA00X+030204Y+138679X0180Y         S0      
317GND              VIA   -    MD0080PA00X+030058Y+139658X0160Y         S0      
317GND              VIA   -    MD0080PA00X+030846Y+139658X0160Y         S0      
317GND              VIA   -    MD0100PA00X+030700Y+141099X0180Y         S0      
317GND              VIA   -    MD0100PA00X+030700Y+140600X0180Y         S0      
317GND              VIA   -    MD0100PA00X+030204Y+141099X0180Y         S0      
317GND              VIA   -    MD0100PA00X+030204Y+140600X0180Y         S0      
317GND              VIA   -    MD0080PA00X+030058Y+140850X0160Y         S0      
317GND              VIA   -    MD0080PA00X+030846Y+140850X0160Y         S0      
317GND              VIA   -    MD0100PA00X+032652Y+136260X0180Y         S0      
317GND              VIA   -    MD0100PA00X+031428Y+136260X0180Y         S0      
317GND              VIA   -    MD0100PA00X+031924Y+136260X0180Y         S0      
317GND              VIA   -    MD0100PA00X+032652Y+137488X0180Y         S0      
317GND              VIA   -    MD0080PA00X+032506Y+138430X0160Y         S0      
317GND              VIA   -    MD0080PA00X+032506Y+137238X0160Y         S0      
317GND              VIA   -    MD0100PA00X+032652Y+136989X0180Y         S0      
317GND              VIA   -    MD0100PA00X+032652Y+138180X0180Y         S0      
317GND              VIA   -    MD0100PA00X+031428Y+136989X0180Y         S0      
317GND              VIA   -    MD0100PA00X+031428Y+138180X0180Y         S0      
317GND              VIA   -    MD0100PA00X+031428Y+137488X0180Y         S0      
317GND              VIA   -    MD0080PA00X+031282Y+138430X0160Y         S0      
317GND              VIA   -    MD0080PA00X+031282Y+137238X0160Y         S0      
317GND              VIA   -    MD0080PA00X+032070Y+138430X0160Y         S0      
317GND              VIA   -    MD0080PA00X+032070Y+137238X0160Y         S0      
317GND              VIA   -    MD0100PA00X+031924Y+136989X0180Y         S0      
317GND              VIA   -    MD0100PA00X+031924Y+138180X0180Y         S0      
317GND              VIA   -    MD0100PA00X+031924Y+137488X0180Y         S0      
317GND              VIA   -    MD0080PA00X+032506Y+139658X0160Y         S0      
317GND              VIA   -    MD0100PA00X+027756Y+141099X0180Y         S0      
317GND              VIA   -    MD0100PA00X+027756Y+140600X0180Y         S0      
317GND              VIA   -    MD0080PA00X+027610Y+140850X0160Y         S0      
317GND              VIA   -    MD0100PA00X+028252Y+136260X0180Y         S0      
317GND              VIA   -    MD0100PA00X+029476Y+136260X0180Y         S0      
317GND              VIA   -    MD0100PA00X+028980Y+136260X0180Y         S0      
317GND              VIA   -    MD0100PA00X+028252Y+136989X0180Y         S0      
317GND              VIA   -    MD0100PA00X+028252Y+137488X0180Y         S0      
317GND              VIA   -    MD0100PA00X+028252Y+138180X0180Y         S0      
317GND              VIA   -    MD0080PA00X+028398Y+138430X0160Y         S0      
317GND              VIA   -    MD0080PA00X+028398Y+137238X0160Y         S0      
317GND              VIA   -    MD0080PA00X+029622Y+137238X0160Y         S0      
317GND              VIA   -    MD0080PA00X+029622Y+138430X0160Y         S0      
317GND              VIA   -    MD0100PA00X+029476Y+138180X0180Y         S0      
317GND              VIA   -    MD0100PA00X+029476Y+136989X0180Y         S0      
317GND              VIA   -    MD0100PA00X+029476Y+137488X0180Y         S0      
317GND              VIA   -    MD0080PA00X+028834Y+137238X0160Y         S0      
317GND              VIA   -    MD0080PA00X+028834Y+138430X0160Y         S0      
317GND              VIA   -    MD0100PA00X+028980Y+138180X0180Y         S0      
317GND              VIA   -    MD0100PA00X+028980Y+136989X0180Y         S0      
317GND              VIA   -    MD0100PA00X+028980Y+137488X0180Y         S0      
317GND              VIA   -    MD0100PA00X+028252Y+139409X0180Y         S0      
317GND              VIA   -    MD0100PA00X+028252Y+139908X0180Y         S0      
317GND              VIA   -    MD0100PA00X+028252Y+138679X0180Y         S0      
317GND              VIA   -    MD0080PA00X+028398Y+139658X0160Y         S0      
317GND              VIA   -    MD0080PA00X+029622Y+139658X0160Y         S0      
317GND              VIA   -    MD0100PA00X+029476Y+138679X0180Y         S0      
317GND              VIA   -    MD0100PA00X+029476Y+139908X0180Y         S0      
317GND              VIA   -    MD0100PA00X+029476Y+139409X0180Y         S0      
317GND              VIA   -    MD0080PA00X+028834Y+139658X0160Y         S0      
317GND              VIA   -    MD0100PA00X+028980Y+138679X0180Y         S0      
317GND              VIA   -    MD0100PA00X+028980Y+139908X0180Y         S0      
317GND              VIA   -    MD0100PA00X+028980Y+139409X0180Y         S0      
317GND              VIA   -    MD0100PA00X+028252Y+141099X0180Y         S0      
317GND              VIA   -    MD0100PA00X+028252Y+140600X0180Y         S0      
317GND              VIA   -    MD0080PA00X+028398Y+140850X0160Y         S0      
317GND              VIA   -    MD0080PA00X+029622Y+140850X0160Y         S0      
317GND              VIA   -    MD0100PA00X+029476Y+141099X0180Y         S0      
317GND              VIA   -    MD0100PA00X+029476Y+140600X0180Y         S0      
317GND              VIA   -    MD0080PA00X+028834Y+140850X0160Y         S0      
317GND              VIA   -    MD0100PA00X+028980Y+141099X0180Y         S0      
317GND              VIA   -    MD0100PA00X+028980Y+140600X0180Y         S0      
317GND              VIA   -    MD0100PA00X+030700Y+136260X0180Y         S0      
317GND              VIA   -    MD0100PA00X+030204Y+136260X0180Y         S0      
317GND              VIA   -    MD0100PA00X+025308Y+138679X0180Y         S0      
317GND              VIA   -    MD0080PA00X+025162Y+139658X0160Y         S0      
317GND              VIA   -    MD0100PA00X+025804Y+139399X0180Y         S0      
317GND              VIA   -    MD0100PA00X+025804Y+139908X0180Y         S0      
317GND              VIA   -    MD0100PA00X+025804Y+138679X0180Y         S0      
317GND              VIA   -    MD0080PA00X+025950Y+139658X0160Y         S0      
317GND              VIA   -    MD0080PA00X+026386Y+139658X0160Y         S0      
317GND              VIA   -    MD0100PA00X+025308Y+141099X0180Y         S0      
317GND              VIA   -    MD0100PA00X+025308Y+140600X0180Y         S0      
317GND              VIA   -    MD0080PA00X+025162Y+140850X0160Y         S0      
317GND              VIA   -    MD0100PA00X+025804Y+141099X0180Y         S0      
317GND              VIA   -    MD0100PA00X+025804Y+140600X0180Y         S0      
317GND              VIA   -    MD0080PA00X+025950Y+140850X0160Y         S0      
317GND              VIA   -    MD0080PA00X+026386Y+140850X0160Y         S0      
317GND              VIA   -    MD0100PA00X+027028Y+136260X0180Y         S0      
317GND              VIA   -    MD0100PA00X+026532Y+136260X0180Y         S0      
317GND              VIA   -    MD0100PA00X+027756Y+136260X0180Y         S0      
317GND              VIA   -    MD0100PA00X+027028Y+138180X0180Y         S0      
317GND              VIA   -    MD0100PA00X+027028Y+137488X0180Y         S0      
317GND              VIA   -    MD0100PA00X+027028Y+136989X0180Y         S0      
317GND              VIA   -    MD0080PA00X+027174Y+137238X0160Y         S0      
317GND              VIA   -    MD0080PA00X+027174Y+138430X0160Y         S0      
317GND              VIA   -    MD0100PA00X+026532Y+138180X0180Y         S0      
317GND              VIA   -    MD0100PA00X+026532Y+137488X0180Y         S0      
317GND              VIA   -    MD0100PA00X+026532Y+136989X0180Y         S0      
317GND              VIA   -    MD0100PA00X+027756Y+136989X0180Y         S0      
317GND              VIA   -    MD0100PA00X+027756Y+137488X0180Y         S0      
317GND              VIA   -    MD0100PA00X+027756Y+138180X0180Y         S0      
317GND              VIA   -    MD0080PA00X+027610Y+137238X0160Y         S0      
317GND              VIA   -    MD0080PA00X+027610Y+138430X0160Y         S0      
317GND              VIA   -    MD0100PA00X+027028Y+138679X0180Y         S0      
317GND              VIA   -    MD0100PA00X+027028Y+139409X0180Y         S0      
317GND              VIA   -    MD0100PA00X+027028Y+139908X0180Y         S0      
317GND              VIA   -    MD0080PA00X+027174Y+139658X0160Y         S0      
317GND              VIA   -    MD0100PA00X+026532Y+138679X0180Y         S0      
317GND              VIA   -    MD0100PA00X+026532Y+139908X0180Y         S0      
317GND              VIA   -    MD0100PA00X+026532Y+139409X0180Y         S0      
317GND              VIA   -    MD0100PA00X+027756Y+139908X0180Y         S0      
317GND              VIA   -    MD0100PA00X+027756Y+139409X0180Y         S0      
317GND              VIA   -    MD0100PA00X+027756Y+138679X0180Y         S0      
317GND              VIA   -    MD0080PA00X+027610Y+139658X0160Y         S0      
317GND              VIA   -    MD0100PA00X+027028Y+141099X0180Y         S0      
317GND              VIA   -    MD0100PA00X+027028Y+140600X0180Y         S0      
317GND              VIA   -    MD0080PA00X+027174Y+140850X0160Y         S0      
317GND              VIA   -    MD0100PA00X+026532Y+141099X0180Y         S0      
317GND              VIA   -    MD0100PA00X+026532Y+140600X0180Y         S0      
317GND              VIA   -    MD0080PA00X+016743Y+139658X0160Y         S0      
317GND              VIA   -    MD0080PA00X+017967Y+140850X0160Y         S0      
317GND              VIA   -    MD0100PA00X+017821Y+141099X0180Y         S0      
317GND              VIA   -    MD0100PA00X+017821Y+140600X0180Y         S0      
317GND              VIA   -    MD0080PA00X+017179Y+140850X0160Y         S0      
317GND              VIA   -    MD0100PA00X+017325Y+141099X0180Y         S0      
317GND              VIA   -    MD0100PA00X+017325Y+140600X0180Y         S0      
317GND              VIA   -    MD0080PA00X+016743Y+140850X0160Y         S0      
317GND              VIA   -    MD0080PA00X+019627Y+139658X0160Y         S0      
317GND              VIA   -    MD0100PA00X+019773Y+139908X0180Y         S0      
317GND              VIA   -    MD0080PA00X+019191Y+139658X0160Y         S0      
317GND              VIA   -    MD0100PA00X+019045Y+139908X0180Y         S0      
317GND              VIA   -    MD0100PA00X+018549Y+139908X0180Y         S0      
317GND              VIA   -    MD0080PA00X+018403Y+139658X0160Y         S0      
317GND              VIA   -    MD0080PA00X+019627Y+140850X0160Y         S0      
317GND              VIA   -    MD0100PA00X+019773Y+141099X0180Y         S0      
317GND              VIA   -    MD0100PA00X+019773Y+140600X0180Y         S0      
317GND              VIA   -    MD0080PA00X+019191Y+140850X0160Y         S0      
317GND              VIA   -    MD0100PA00X+019045Y+140600X0180Y         S0      
317GND              VIA   -    MD0100PA00X+019045Y+141099X0180Y         S0      
317GND              VIA   -    MD0100PA00X+018549Y+140600X0180Y         S0      
317GND              VIA   -    MD0100PA00X+018549Y+141099X0180Y         S0      
317GND              VIA   -    MD0080PA00X+018403Y+140850X0160Y         S0      
317GND              VIA   -    MD0080PA00X+020415Y+139658X0160Y         S0      
317GND              VIA   -    MD0100PA00X+020269Y+139908X0180Y         S0      
317GND              VIA   -    MD0080PA00X+020415Y+140850X0160Y         S0      
317GND              VIA   -    MD0100PA00X+020269Y+141099X0180Y         S0      
317GND              VIA   -    MD0100PA00X+020269Y+140600X0180Y         S0      
317GND              VIA   -    MD0100PA00X+025308Y+136260X0180Y         S0      
317GND              VIA   -    MD0100PA00X+025804Y+136260X0180Y         S0      
317GND              VIA   -    MD0080PA00X+024726Y+137238X0160Y         S0      
317GND              VIA   -    MD0080PA00X+024726Y+138430X0160Y         S0      
317GND              VIA   -    MD0100PA00X+025308Y+137488X0180Y         S0      
317GND              VIA   -    MD0100PA00X+025308Y+136980X0180Y         S0      
317GND              VIA   -    MD0100PA00X+025308Y+138180X0180Y         S0      
317GND              VIA   -    MD0080PA00X+025162Y+138430X0160Y         S0      
317GND              VIA   -    MD0080PA00X+025162Y+137238X0160Y         S0      
317GND              VIA   -    MD0100PA00X+025804Y+137488X0180Y         S0      
317GND              VIA   -    MD0100PA00X+025804Y+136980X0180Y         S0      
317GND              VIA   -    MD0100PA00X+025804Y+138180X0180Y         S0      
317GND              VIA   -    MD0080PA00X+025950Y+137238X0160Y         S0      
317GND              VIA   -    MD0080PA00X+025950Y+138430X0160Y         S0      
317GND              VIA   -    MD0080PA00X+026386Y+137238X0160Y         S0      
317GND              VIA   -    MD0080PA00X+026386Y+138430X0160Y         S0      
317GND              VIA   -    MD0100PA00X+025308Y+139908X0180Y         S0      
317GND              VIA   -    MD0100PA00X+025308Y+139399X0180Y         S0      
317GND              VIA   -    MD0080PA00X+019191Y+137238X0160Y         S0      
317GND              VIA   -    MD0080PA00X+019191Y+138430X0160Y         S0      
317GND              VIA   -    MD0100PA00X+019045Y+138180X0180Y         S0      
317GND              VIA   -    MD0100PA00X+019045Y+137488X0180Y         S0      
317GND              VIA   -    MD0100PA00X+019045Y+136989X0180Y         S0      
317GND              VIA   -    MD0080PA00X+019627Y+137238X0160Y         S0      
317GND              VIA   -    MD0080PA00X+019627Y+138430X0160Y         S0      
317GND              VIA   -    MD0100PA00X+019773Y+137488X0180Y         S0      
317GND              VIA   -    MD0100PA00X+019773Y+138180X0180Y         S0      
317GND              VIA   -    MD0100PA00X+019773Y+136989X0180Y         S0      
317GND              VIA   -    MD0100PA00X+018549Y+136989X0180Y         S0      
317GND              VIA   -    MD0100PA00X+018549Y+138180X0180Y         S0      
317GND              VIA   -    MD0100PA00X+018549Y+137488X0180Y         S0      
317GND              VIA   -    MD0080PA00X+018403Y+137238X0160Y         S0      
317GND              VIA   -    MD0080PA00X+018403Y+138430X0160Y         S0      
317GND              VIA   -    MD0100PA00X+019773Y+138679X0180Y         S0      
317GND              VIA   -    MD0100PA00X+019773Y+139409X0180Y         S0      
317GND              VIA   -    MD0100PA00X+019045Y+138679X0180Y         S0      
317GND              VIA   -    MD0100PA00X+019045Y+139399X0180Y         S0      
317GND              VIA   -    MD0100PA00X+018549Y+138679X0180Y         S0      
317GND              VIA   -    MD0100PA00X+018549Y+139399X0180Y         S0      
317GND              VIA   -    MD0080PA00X+020415Y+134819X0160Y         S0      
317GND              VIA   -    MD0100PA00X+020269Y+135068X0180Y         S0      
317GND              VIA   -    MD0100PA00X+020269Y+134560X0180Y         S0      
317GND              VIA   -    MD0080PA00X+020415Y+136010X0160Y         S0      
317GND              VIA   -    MD0100PA00X+020269Y+135760X0180Y         S0      
317GND              VIA   -    MD0100PA00X+020269Y+136260X0180Y         S0      
317GND              VIA   -    MD0080PA00X+020415Y+137238X0160Y         S0      
317GND              VIA   -    MD0080PA00X+020415Y+138430X0160Y         S0      
317GND              VIA   -    MD0100PA00X+020269Y+137488X0180Y         S0      
317GND              VIA   -    MD0100PA00X+020269Y+138180X0180Y         S0      
317GND              VIA   -    MD0100PA00X+020269Y+136989X0180Y         S0      
317GND              VIA   -    MD0100PA00X+020269Y+138679X0180Y         S0      
317GND              VIA   -    MD0100PA00X+020269Y+139409X0180Y         S0      
317GND              VIA   -    MD0100PA00X+016597Y+139908X0180Y         S0      
317GND              VIA   -    MD0080PA00X+015519Y+139658X0160Y         S0      
317GND              VIA   -    MD0100PA00X+015373Y+139908X0180Y         S0      
317GND              VIA   -    MD0080PA00X+015955Y+139658X0160Y         S0      
317GND              VIA   -    MD0100PA00X+016101Y+139908X0180Y         S0      
317GND              VIA   -    MD0100PA00X+016597Y+140600X0180Y         S0      
317GND              VIA   -    MD0100PA00X+016597Y+141099X0180Y         S0      
317GND              VIA   -    MD0080PA00X+015519Y+140850X0160Y         S0      
317GND              VIA   -    MD0100PA00X+015373Y+141099X0180Y         S0      
317GND              VIA   -    MD0100PA00X+015373Y+140600X0180Y         S0      
317GND              VIA   -    MD0080PA00X+015955Y+140850X0160Y         S0      
317GND              VIA   -    MD0100PA00X+016101Y+140600X0180Y         S0      
317GND              VIA   -    MD0100PA00X+016101Y+141099X0180Y         S0      
317GND              VIA   -    MD0080PA00X+017967Y+139658X0160Y         S0      
317GND              VIA   -    MD0100PA00X+017821Y+139908X0180Y         S0      
317GND              VIA   -    MD0080PA00X+017179Y+139658X0160Y         S0      
317GND              VIA   -    MD0100PA00X+017325Y+139908X0180Y         S0      
317GND              VIA   -    MD0080PA00X+017967Y+136010X0160Y         S0      
317GND              VIA   -    MD0100PA00X+017821Y+136260X0180Y         S0      
317GND              VIA   -    MD0100PA00X+017821Y+135760X0180Y         S0      
317GND              VIA   -    MD0080PA00X+017179Y+136010X0160Y         S0      
317GND              VIA   -    MD0100PA00X+017325Y+135760X0180Y         S0      
317GND              VIA   -    MD0100PA00X+017325Y+136260X0180Y         S0      
317GND              VIA   -    MD0080PA00X+016743Y+136010X0160Y         S0      
317GND              VIA   -    MD0080PA00X+017967Y+137238X0160Y         S0      
317GND              VIA   -    MD0080PA00X+017967Y+138430X0160Y         S0      
317GND              VIA   -    MD0100PA00X+017821Y+138180X0180Y         S0      
317GND              VIA   -    MD0100PA00X+017821Y+136989X0180Y         S0      
317GND              VIA   -    MD0100PA00X+017821Y+137488X0180Y         S0      
317GND              VIA   -    MD0100PA00X+017325Y+138180X0180Y         S0      
317GND              VIA   -    MD0100PA00X+017325Y+136989X0180Y         S0      
317GND              VIA   -    MD0100PA00X+017325Y+137488X0180Y         S0      
317GND              VIA   -    MD0080PA00X+017179Y+137238X0160Y         S0      
317GND              VIA   -    MD0080PA00X+017179Y+138430X0160Y         S0      
317GND              VIA   -    MD0080PA00X+016743Y+137238X0160Y         S0      
317GND              VIA   -    MD0080PA00X+016743Y+138430X0160Y         S0      
317GND              VIA   -    MD0100PA00X+017821Y+138679X0180Y         S0      
317GND              VIA   -    MD0100PA00X+017821Y+139409X0180Y         S0      
317GND              VIA   -    MD0100PA00X+017325Y+138679X0180Y         S0      
317GND              VIA   -    MD0100PA00X+017325Y+139409X0180Y         S0      
317GND              VIA   -    MD0080PA00X+019627Y+134819X0160Y         S0      
317GND              VIA   -    MD0100PA00X+019773Y+135068X0180Y         S0      
317GND              VIA   -    MD0100PA00X+019773Y+134569X0180Y         S0      
317GND              VIA   -    MD0080PA00X+019191Y+134819X0160Y         S0      
317GND              VIA   -    MD0100PA00X+019045Y+135068X0180Y         S0      
317GND              VIA   -    MD0100PA00X+019045Y+134560X0180Y         S0      
317GND              VIA   -    MD0100PA00X+018549Y+135068X0180Y         S0      
317GND              VIA   -    MD0100PA00X+018549Y+134560X0180Y         S0      
317GND              VIA   -    MD0080PA00X+018403Y+134819X0160Y         S0      
317GND              VIA   -    MD0080PA00X+019191Y+136010X0160Y         S0      
317GND              VIA   -    MD0100PA00X+019045Y+135760X0180Y         S0      
317GND              VIA   -    MD0100PA00X+019045Y+136260X0180Y         S0      
317GND              VIA   -    MD0080PA00X+019627Y+136010X0160Y         S0      
317GND              VIA   -    MD0100PA00X+019773Y+135760X0180Y         S0      
317GND              VIA   -    MD0100PA00X+019773Y+136260X0180Y         S0      
317GND              VIA   -    MD0100PA00X+018549Y+135760X0180Y         S0      
317GND              VIA   -    MD0100PA00X+018549Y+136260X0180Y         S0      
317GND              VIA   -    MD0080PA00X+018403Y+136010X0160Y         S0      
317GND              VIA   -    MD0100PA00X+016597Y+135068X0180Y         S0      
317GND              VIA   -    MD0100PA00X+016597Y+134569X0180Y         S0      
317GND              VIA   -    MD0080PA00X+015519Y+134819X0160Y         S0      
317GND              VIA   -    MD0100PA00X+015373Y+135068X0180Y         S0      
317GND              VIA   -    MD0100PA00X+015373Y+134569X0180Y         S0      
317GND              VIA   -    MD0080PA00X+015955Y+134819X0160Y         S0      
317GND              VIA   -    MD0100PA00X+016101Y+135068X0180Y         S0      
317GND              VIA   -    MD0100PA00X+016101Y+134569X0180Y         S0      
317GND              VIA   -    MD0100PA00X+016597Y+135760X0180Y         S0      
317GND              VIA   -    MD0100PA00X+016597Y+136260X0180Y         S0      
317GND              VIA   -    MD0100PA00X+015373Y+135760X0180Y         S0      
317GND              VIA   -    MD0100PA00X+015373Y+136260X0180Y         S0      
317GND              VIA   -    MD0080PA00X+015519Y+136010X0160Y         S0      
317GND              VIA   -    MD0080PA00X+015955Y+136010X0160Y         S0      
317GND              VIA   -    MD0100PA00X+016101Y+135760X0180Y         S0      
317GND              VIA   -    MD0100PA00X+016101Y+136260X0180Y         S0      
317GND              VIA   -    MD0100PA00X+016597Y+136989X0180Y         S0      
317GND              VIA   -    MD0100PA00X+016597Y+138180X0180Y         S0      
317GND              VIA   -    MD0100PA00X+016597Y+137488X0180Y         S0      
317GND              VIA   -    MD0080PA00X+015519Y+137238X0160Y         S0      
317GND              VIA   -    MD0080PA00X+015519Y+138430X0160Y         S0      
317GND              VIA   -    MD0100PA00X+015373Y+137488X0180Y         S0      
317GND              VIA   -    MD0100PA00X+015373Y+138180X0180Y         S0      
317GND              VIA   -    MD0100PA00X+015373Y+136989X0180Y         S0      
317GND              VIA   -    MD0100PA00X+016101Y+137488X0180Y         S0      
317GND              VIA   -    MD0080PA00X+015955Y+138430X0160Y         S0      
317GND              VIA   -    MD0080PA00X+015955Y+137238X0160Y         S0      
317GND              VIA   -    MD0100PA00X+016101Y+136989X0180Y         S0      
317GND              VIA   -    MD0100PA00X+016101Y+138180X0180Y         S0      
317GND              VIA   -    MD0100PA00X+016597Y+138679X0180Y         S0      
317GND              VIA   -    MD0100PA00X+016597Y+139409X0180Y         S0      
317GND              VIA   -    MD0100PA00X+015373Y+138679X0180Y         S0      
317GND              VIA   -    MD0100PA00X+015373Y+139409X0180Y         S0      
317GND              VIA   -    MD0100PA00X+016101Y+138679X0180Y         S0      
317GND              VIA   -    MD0100PA00X+016101Y+139409X0180Y         S0      
317GND              VIA   -    MD0080PA00X+017967Y+134819X0160Y         S0      
317GND              VIA   -    MD0100PA00X+017821Y+135068X0180Y         S0      
317GND              VIA   -    MD0100PA00X+017821Y+134569X0180Y         S0      
317GND              VIA   -    MD0100PA00X+017325Y+135068X0180Y         S0      
317GND              VIA   -    MD0100PA00X+017325Y+134569X0180Y         S0      
317GND              VIA   -    MD0080PA00X+017179Y+134819X0160Y         S0      
317GND              VIA   -    MD0080PA00X+016743Y+134819X0160Y         S0      
317GND              VIA   -    MD0100PA00X+011701Y+135068X0180Y         S0      
317GND              VIA   -    MD0100PA00X+011701Y+134569X0180Y         S0      
317GND              VIA   -    MD0080PA00X+010623Y+134819X0160Y         S0      
317GND              VIA   -    MD0080PA00X+011059Y+134819X0160Y         S0      
317GND              VIA   -    MD0100PA00X+011205Y+135068X0180Y         S0      
317GND              VIA   -    MD0100PA00X+011205Y+134569X0180Y         S0      
317GND              VIA   -    MD0100PA00X+010477Y+134569X0180Y         S0      
317GND              VIA   -    MD0100PA00X+010477Y+135068X0180Y         S0      
317GND              VIA   -    MD0100PA00X+011701Y+135760X0180Y         S0      
317GND              VIA   -    MD0100PA00X+011701Y+136260X0180Y         S0      
317GND              VIA   -    MD0080PA00X+010623Y+136010X0160Y         S0      
317GND              VIA   -    MD0080PA00X+011059Y+136010X0160Y         S0      
317GND              VIA   -    MD0100PA00X+011205Y+135760X0180Y         S0      
317GND              VIA   -    MD0100PA00X+011205Y+136260X0180Y         S0      
317GND              VIA   -    MD0100PA00X+010477Y+135760X0180Y         S0      
317GND              VIA   -    MD0100PA00X+010477Y+136260X0180Y         S0      
317GND              VIA   -    MD0100PA00X+012925Y+134569X0180Y         S0      
317GND              VIA   -    MD0100PA00X+012925Y+135068X0180Y         S0      
317GND              VIA   -    MD0080PA00X+013071Y+134819X0160Y         S0      
317GND              VIA   -    MD0080PA00X+012283Y+134819X0160Y         S0      
317GND              VIA   -    MD0100PA00X+012429Y+134569X0180Y         S0      
317GND              VIA   -    MD0100PA00X+012429Y+135068X0180Y         S0      
317GND              VIA   -    MD0080PA00X+011847Y+134819X0160Y         S0      
317GND              VIA   -    MD0080PA00X+013071Y+136010X0160Y         S0      
317GND              VIA   -    MD0100PA00X+012925Y+136260X0180Y         S0      
317GND              VIA   -    MD0100PA00X+012925Y+135760X0180Y         S0      
317GND              VIA   -    MD0080PA00X+012283Y+136010X0160Y         S0      
317GND              VIA   -    MD0100PA00X+012429Y+135760X0180Y         S0      
317GND              VIA   -    MD0100PA00X+012429Y+136260X0180Y         S0      
317GND              VIA   -    MD0080PA00X+011847Y+136010X0160Y         S0      
317GND              VIA   -    MD0080PA00X+014731Y+134819X0160Y         S0      
317GND              VIA   -    MD0080PA00X+014295Y+134819X0160Y         S0      
317GND              VIA   -    MD0100PA00X+014877Y+134569X0180Y         S0      
317GND              VIA   -    MD0100PA00X+014877Y+135068X0180Y         S0      
317GND              VIA   -    MD0100PA00X+013653Y+134569X0180Y         S0      
317GND              VIA   -    MD0100PA00X+013653Y+135068X0180Y         S0      
317GND              VIA   -    MD0080PA00X+013507Y+134819X0160Y         S0      
317GND              VIA   -    MD0100PA00X+014149Y+135068X0180Y         S0      
317GND              VIA   -    MD0100PA00X+014149Y+134569X0180Y         S0      
317GND              VIA   -    MD0080PA00X+014295Y+136010X0160Y         S0      
317GND              VIA   -    MD0080PA00X+014731Y+136010X0160Y         S0      
317GND              VIA   -    MD0100PA00X+014877Y+136260X0180Y         S0      
317GND              VIA   -    MD0100PA00X+014877Y+135760X0180Y         S0      
317GND              VIA   -    MD0080PA00X+013507Y+136010X0160Y         S0      
317GND              VIA   -    MD0100PA00X+013653Y+135760X0180Y         S0      
317GND              VIA   -    MD0100PA00X+013653Y+136260X0180Y         S0      
317GND              VIA   -    MD0100PA00X+014149Y+136260X0180Y         S0      
317GND              VIA   -    MD0100PA00X+014149Y+135760X0180Y         S0      
317GND              VIA   -    MD0080PA00X+008175Y+134819X0160Y         S0      
317GND              VIA   -    MD0080PA00X+007387Y+134819X0160Y         S0      
317GND              VIA   -    MD0100PA00X+007533Y+135068X0180Y         S0      
317GND              VIA   -    MD0100PA00X+007533Y+134569X0180Y         S0      
317GND              VIA   -    MD0100PA00X+008029Y+135068X0180Y         S0      
317GND              VIA   -    MD0100PA00X+008029Y+134569X0180Y         S0      
317GND              VIA   -    MD0080PA00X+008175Y+136010X0160Y         S0      
317GND              VIA   -    MD0080PA00X+007387Y+136010X0160Y         S0      
317GND              VIA   -    MD0100PA00X+007533Y+136260X0180Y         S0      
317GND              VIA   -    MD0100PA00X+007533Y+135760X0180Y         S0      
317GND              VIA   -    MD0100PA00X+008029Y+136260X0180Y         S0      
317GND              VIA   -    MD0100PA00X+008029Y+135760X0180Y         S0      
317GND              VIA   -    MD0080PA00X+008175Y+137238X0160Y         S0      
317GND              VIA   -    MD0080PA00X+008175Y+138430X0160Y         S0      
317GND              VIA   -    MD0080PA00X+007387Y+137238X0160Y         S0      
317GND              VIA   -    MD0080PA00X+007387Y+138430X0160Y         S0      
317GND              VIA   -    MD0100PA00X+007533Y+136989X0180Y         S0      
317GND              VIA   -    MD0100PA00X+007533Y+137488X0180Y         S0      
317GND              VIA   -    MD0100PA00X+007533Y+138180X0180Y         S0      
317GND              VIA   -    MD0100PA00X+008029Y+137488X0180Y         S0      
317GND              VIA   -    MD0100PA00X+008029Y+136989X0180Y         S0      
317GND              VIA   -    MD0100PA00X+008029Y+138180X0180Y         S0      
317GND              VIA   -    MD0100PA00X+007533Y+138679X0180Y         S0      
317GND              VIA   -    MD0100PA00X+008029Y+138679X0180Y         S0      
317GND              VIA   -    MD0100PA00X+009253Y+135068X0180Y         S0      
317GND              VIA   -    MD0100PA00X+009253Y+134569X0180Y         S0      
317GND              VIA   -    MD0080PA00X+009399Y+134819X0160Y         S0      
317GND              VIA   -    MD0080PA00X+009835Y+134819X0160Y         S0      
317GND              VIA   -    MD0100PA00X+009981Y+134569X0180Y         S0      
317GND              VIA   -    MD0100PA00X+009981Y+135068X0180Y         S0      
317GND              VIA   -    MD0080PA00X+008611Y+134819X0160Y         S0      
317GND              VIA   -    MD0100PA00X+008757Y+135068X0180Y         S0      
317GND              VIA   -    MD0100PA00X+008757Y+134569X0180Y         S0      
317GND              VIA   -    MD0100PA00X+009253Y+135760X0180Y         S0      
317GND              VIA   -    MD0100PA00X+009253Y+136260X0180Y         S0      
317GND              VIA   -    MD0080PA00X+009399Y+136010X0160Y         S0      
317GND              VIA   -    MD0080PA00X+009835Y+136010X0160Y         S0      
317GND              VIA   -    MD0100PA00X+009981Y+135760X0180Y         S0      
317GND              VIA   -    MD0100PA00X+009981Y+136260X0180Y         S0      
317GND              VIA   -    MD0080PA00X+008611Y+136010X0160Y         S0      
317GND              VIA   -    MD0100PA00X+008757Y+135760X0180Y         S0      
317GND              VIA   -    MD0100PA00X+008757Y+136260X0180Y         S0      
317GND              VIA   -    MD0080PA00X+013071Y+140850X0160Y         S0      
317GND              VIA   -    MD0100PA00X+012925Y+141099X0180Y         S0      
317GND              VIA   -    MD0100PA00X+012925Y+140600X0180Y         S0      
317GND              VIA   -    MD0080PA00X+012283Y+140850X0160Y         S0      
317GND              VIA   -    MD0100PA00X+012429Y+141099X0180Y         S0      
317GND              VIA   -    MD0100PA00X+012429Y+140600X0180Y         S0      
317GND              VIA   -    MD0080PA00X+011847Y+140850X0160Y         S0      
317GND              VIA   -    MD0080PA00X+014295Y+137238X0160Y         S0      
317GND              VIA   -    MD0080PA00X+014295Y+138430X0160Y         S0      
317GND              VIA   -    MD0080PA00X+014731Y+137238X0160Y         S0      
317GND              VIA   -    MD0080PA00X+014731Y+138430X0160Y         S0      
317GND              VIA   -    MD0100PA00X+014877Y+137488X0180Y         S0      
317GND              VIA   -    MD0100PA00X+014877Y+138180X0180Y         S0      
317GND              VIA   -    MD0100PA00X+014877Y+136989X0180Y         S0      
317GND              VIA   -    MD0080PA00X+013507Y+137238X0160Y         S0      
317GND              VIA   -    MD0080PA00X+013507Y+138430X0160Y         S0      
317GND              VIA   -    MD0100PA00X+013653Y+137488X0180Y         S0      
317GND              VIA   -    MD0100PA00X+013653Y+138180X0180Y         S0      
317GND              VIA   -    MD0100PA00X+013653Y+136989X0180Y         S0      
317GND              VIA   -    MD0100PA00X+014149Y+138180X0180Y         S0      
317GND              VIA   -    MD0100PA00X+014149Y+137488X0180Y         S0      
317GND              VIA   -    MD0100PA00X+014149Y+136989X0180Y         S0      
317GND              VIA   -    MD0080PA00X+014295Y+139658X0160Y         S0      
317GND              VIA   -    MD0080PA00X+014731Y+139658X0160Y         S0      
317GND              VIA   -    MD0100PA00X+014877Y+138679X0180Y         S0      
317GND              VIA   -    MD0100PA00X+014877Y+139908X0180Y         S0      
317GND              VIA   -    MD0100PA00X+014877Y+139409X0180Y         S0      
317GND              VIA   -    MD0080PA00X+013507Y+139658X0160Y         S0      
317GND              VIA   -    MD0100PA00X+013653Y+138679X0180Y         S0      
317GND              VIA   -    MD0100PA00X+013653Y+139409X0180Y         S0      
317GND              VIA   -    MD0100PA00X+013653Y+139908X0180Y         S0      
317GND              VIA   -    MD0100PA00X+014149Y+139908X0180Y         S0      
317GND              VIA   -    MD0100PA00X+014149Y+139409X0180Y         S0      
317GND              VIA   -    MD0100PA00X+014149Y+138679X0180Y         S0      
317GND              VIA   -    MD0080PA00X+014295Y+140850X0160Y         S0      
317GND              VIA   -    MD0080PA00X+014731Y+140850X0160Y         S0      
317GND              VIA   -    MD0100PA00X+014877Y+141099X0180Y         S0      
317GND              VIA   -    MD0100PA00X+014877Y+140600X0180Y         S0      
317GND              VIA   -    MD0080PA00X+013507Y+140850X0160Y         S0      
317GND              VIA   -    MD0100PA00X+013653Y+140600X0180Y         S0      
317GND              VIA   -    MD0100PA00X+013653Y+141099X0180Y         S0      
317GND              VIA   -    MD0100PA00X+014149Y+141099X0180Y         S0      
317GND              VIA   -    MD0100PA00X+014149Y+140600X0180Y         S0      
317GND              VIA   -    MD0080PA00X+011059Y+137238X0160Y         S0      
317GND              VIA   -    MD0100PA00X+011205Y+138180X0180Y         S0      
317GND              VIA   -    MD0100PA00X+011205Y+137488X0180Y         S0      
317GND              VIA   -    MD0100PA00X+011205Y+136989X0180Y         S0      
317GND              VIA   -    MD0100PA00X+010477Y+136989X0180Y         S0      
317GND              VIA   -    MD0100PA00X+010477Y+137488X0180Y         S0      
317GND              VIA   -    MD0100PA00X+010477Y+138180X0180Y         S0      
317GND              VIA   -    MD0100PA00X+011701Y+138679X0180Y         S0      
317GND              VIA   -    MD0100PA00X+011701Y+139908X0180Y         S0      
317GND              VIA   -    MD0100PA00X+011701Y+139409X0180Y         S0      
317GND              VIA   -    MD0080PA00X+010623Y+139658X0160Y         S0      
317GND              VIA   -    MD0080PA00X+011059Y+139658X0160Y         S0      
317GND              VIA   -    MD0100PA00X+011205Y+138679X0180Y         S0      
317GND              VIA   -    MD0100PA00X+011205Y+139409X0180Y         S0      
317GND              VIA   -    MD0100PA00X+011205Y+139908X0180Y         S0      
317GND              VIA   -    MD0100PA00X+010477Y+138679X0180Y         S0      
317GND              VIA   -    MD0100PA00X+010477Y+139409X0180Y         S0      
317GND              VIA   -    MD0100PA00X+010477Y+139908X0180Y         S0      
317GND              VIA   -    MD0100PA00X+011701Y+140600X0180Y         S0      
317GND              VIA   -    MD0100PA00X+011701Y+141099X0180Y         S0      
317GND              VIA   -    MD0080PA00X+010623Y+140850X0160Y         S0      
317GND              VIA   -    MD0080PA00X+011059Y+140850X0160Y         S0      
317GND              VIA   -    MD0100PA00X+011205Y+140600X0180Y         S0      
317GND              VIA   -    MD0100PA00X+011205Y+141099X0180Y         S0      
317GND              VIA   -    MD0100PA00X+010477Y+140600X0180Y         S0      
317GND              VIA   -    MD0100PA00X+010477Y+141099X0180Y         S0      
317GND              VIA   -    MD0080PA00X+013071Y+137238X0160Y         S0      
317GND              VIA   -    MD0080PA00X+013071Y+138430X0160Y         S0      
317GND              VIA   -    MD0100PA00X+012925Y+138180X0180Y         S0      
317GND              VIA   -    MD0100PA00X+012925Y+136989X0180Y         S0      
317GND              VIA   -    MD0100PA00X+012925Y+137488X0180Y         S0      
317GND              VIA   -    MD0080PA00X+012283Y+137238X0160Y         S0      
317GND              VIA   -    MD0080PA00X+012283Y+138430X0160Y         S0      
317GND              VIA   -    MD0100PA00X+012429Y+138180X0180Y         S0      
317GND              VIA   -    MD0100PA00X+012429Y+136989X0180Y         S0      
317GND              VIA   -    MD0100PA00X+012429Y+137488X0180Y         S0      
317GND              VIA   -    MD0080PA00X+011847Y+137238X0160Y         S0      
317GND              VIA   -    MD0080PA00X+011847Y+138430X0160Y         S0      
317GND              VIA   -    MD0080PA00X+013071Y+139658X0160Y         S0      
317GND              VIA   -    MD0100PA00X+012925Y+138679X0180Y         S0      
317GND              VIA   -    MD0100PA00X+012925Y+139908X0180Y         S0      
317GND              VIA   -    MD0100PA00X+012925Y+139409X0180Y         S0      
317GND              VIA   -    MD0080PA00X+012283Y+139658X0160Y         S0      
317GND              VIA   -    MD0100PA00X+012429Y+138679X0180Y         S0      
317GND              VIA   -    MD0100PA00X+012429Y+139908X0180Y         S0      
317GND              VIA   -    MD0100PA00X+012429Y+139409X0180Y         S0      
317GND              VIA   -    MD0080PA00X+011847Y+139658X0160Y         S0      
317GND              VIA   -    MD0080PA00X+009399Y+138430X0160Y         S0      
317GND              VIA   -    MD0080PA00X+009399Y+137238X0160Y         S0      
317GND              VIA   -    MD0100PA00X+009253Y+138180X0180Y         S0      
317GND              VIA   -    MD0100PA00X+009253Y+136980X0180Y         S0      
317GND              VIA   -    MD0100PA00X+009253Y+137488X0180Y         S0      
317GND              VIA   -    MD0080PA00X+009835Y+137238X0160Y         S0      
317GND              VIA   -    MD0080PA00X+009835Y+138430X0160Y         S0      
317GND              VIA   -    MD0100PA00X+009981Y+136989X0180Y         S0      
317GND              VIA   -    MD0100PA00X+009981Y+137488X0180Y         S0      
317GND              VIA   -    MD0100PA00X+009981Y+138180X0180Y         S0      
317GND              VIA   -    MD0080PA00X+008611Y+137238X0160Y         S0      
317GND              VIA   -    MD0080PA00X+008611Y+138430X0160Y         S0      
317GND              VIA   -    MD0100PA00X+008757Y+138180X0180Y         S0      
317GND              VIA   -    MD0100PA00X+008757Y+136980X0180Y         S0      
317GND              VIA   -    MD0100PA00X+008757Y+137488X0180Y         S0      
317GND              VIA   -    MD0080PA00X+009835Y+139658X0160Y         S0      
317GND              VIA   -    MD0100PA00X+009253Y+138679X0180Y         S0      
317GND              VIA   -    MD0080PA00X+009399Y+139658X0160Y         S0      
317GND              VIA   -    MD0100PA00X+009253Y+139908X0180Y         S0      
317GND              VIA   -    MD0100PA00X+009253Y+139399X0180Y         S0      
317GND              VIA   -    MD0100PA00X+009981Y+138679X0180Y         S0      
317GND              VIA   -    MD0100PA00X+009981Y+139409X0180Y         S0      
317GND              VIA   -    MD0100PA00X+009981Y+139908X0180Y         S0      
317GND              VIA   -    MD0080PA00X+008611Y+139658X0160Y         S0      
317GND              VIA   -    MD0100PA00X+008757Y+138679X0180Y         S0      
317GND              VIA   -    MD0100PA00X+008757Y+139399X0180Y         S0      
317GND              VIA   -    MD0100PA00X+008757Y+139908X0180Y         S0      
317GND              VIA   -    MD0080PA00X+009835Y+140850X0160Y         S0      
317GND              VIA   -    MD0080PA00X+009399Y+140850X0160Y         S0      
317GND              VIA   -    MD0100PA00X+009253Y+140600X0180Y         S0      
317GND              VIA   -    MD0100PA00X+009253Y+141099X0180Y         S0      
317GND              VIA   -    MD0100PA00X+009981Y+140600X0180Y         S0      
317GND              VIA   -    MD0100PA00X+009981Y+141099X0180Y         S0      
317GND              VIA   -    MD0080PA00X+008611Y+140850X0160Y         S0      
317GND              VIA   -    MD0100PA00X+008757Y+140600X0180Y         S0      
317GND              VIA   -    MD0100PA00X+008757Y+141099X0180Y         S0      
317GND              VIA   -    MD0100PA00X+011701Y+138180X0180Y         S0      
317GND              VIA   -    MD0100PA00X+011701Y+137488X0180Y         S0      
317GND              VIA   -    MD0100PA00X+011701Y+136989X0180Y         S0      
317GND              VIA   -    MD0080PA00X+010623Y+137238X0160Y         S0      
317GND              VIA   -    MD0080PA00X+010623Y+138430X0160Y         S0      
317GND              VIA   -    MD0080PA00X+011059Y+138430X0160Y         S0      
317GND              VIA   -    MD0080PA00X+158153Y+136010X0160Y         S0      
317GND              VIA   -    MD0100PA00X+158299Y+135760X0180Y         S0      
317GND              VIA   -    MD0100PA00X+158299Y+136260X0180Y         S0      
317GND              VIA   -    MD0080PA00X+158941Y+136010X0160Y         S0      
317GND              VIA   -    MD0100PA00X+158795Y+135760X0180Y         S0      
317GND              VIA   -    MD0100PA00X+158795Y+136260X0180Y         S0      
317GND              VIA   -    MD0080PA00X+158941Y+137238X0160Y         S0      
317GND              VIA   -    MD0080PA00X+158941Y+138430X0160Y         S0      
317GND              VIA   -    MD0100PA00X+158795Y+137488X0180Y         S0      
317GND              VIA   -    MD0100PA00X+158795Y+138180X0180Y         S0      
317GND              VIA   -    MD0100PA00X+158795Y+136989X0180Y         S0      
317GND              VIA   -    MD0080PA00X+158153Y+137238X0160Y         S0      
317GND              VIA   -    MD0080PA00X+158153Y+138430X0160Y         S0      
317GND              VIA   -    MD0100PA00X+158299Y+137488X0180Y         S0      
317GND              VIA   -    MD0100PA00X+158299Y+138180X0180Y         S0      
317GND              VIA   -    MD0100PA00X+158299Y+136989X0180Y         S0      
317GND              VIA   -    MD0080PA00X+158941Y+139658X0160Y         S0      
317GND              VIA   -    MD0100PA00X+158795Y+138679X0180Y         S0      
317GND              VIA   -    MD0100PA00X+158795Y+139409X0180Y         S0      
317GND              VIA   -    MD0100PA00X+158795Y+139908X0180Y         S0      
317GND              VIA   -    MD0080PA00X+158153Y+139658X0160Y         S0      
317GND              VIA   -    MD0100PA00X+158299Y+138679X0180Y         S0      
317GND              VIA   -    MD0100PA00X+158299Y+139409X0180Y         S0      
317GND              VIA   -    MD0100PA00X+158299Y+139908X0180Y         S0      
317GND              VIA   -    MD0100PA00X+158795Y+141099X0180Y         S0      
317GND              VIA   -    MD0080PA00X+158941Y+140850X0160Y         S0      
317GND              VIA   -    MD0100PA00X+158795Y+140600X0180Y         S0      
317GND              VIA   -    MD0080PA00X+158153Y+140850X0160Y         S0      
317GND              VIA   -    MD0100PA00X+158299Y+141099X0180Y         S0      
317GND              VIA   -    MD0100PA00X+158299Y+140600X0180Y         S0      
317GND              VIA   -    MD0100PA00X+157571Y+135068X0180Y         S0      
317GND              VIA   -    MD0080PA00X+157717Y+134819X0160Y         S0      
317GND              VIA   -    MD0100PA00X+157075Y+134560X0180Y         S0      
317GND              VIA   -    MD0100PA00X+157075Y+135068X0180Y         S0      
317GND              VIA   -    MD0080PA00X+156929Y+134819X0160Y         S0      
317GND              VIA   -    MD0080PA00X+156493Y+136010X0160Y         S0      
317GND              VIA   -    MD0100PA00X+157571Y+135760X0180Y         S0      
317GND              VIA   -    MD0100PA00X+157571Y+136260X0180Y         S0      
317GND              VIA   -    MD0080PA00X+157717Y+136010X0160Y         S0      
317GND              VIA   -    MD0100PA00X+157075Y+136260X0180Y         S0      
317GND              VIA   -    MD0100PA00X+157075Y+135760X0180Y         S0      
317GND              VIA   -    MD0080PA00X+156929Y+136010X0160Y         S0      
317GND              VIA   -    MD0080PA00X+156493Y+137238X0160Y         S0      
317GND              VIA   -    MD0080PA00X+156493Y+138430X0160Y         S0      
317GND              VIA   -    MD0100PA00X+157075Y+137488X0180Y         S0      
317GND              VIA   -    MD0100PA00X+157075Y+138180X0180Y         S0      
317GND              VIA   -    MD0100PA00X+157075Y+136989X0180Y         S0      
317GND              VIA   -    MD0080PA00X+156929Y+138430X0160Y         S0      
317GND              VIA   -    MD0080PA00X+156929Y+137238X0160Y         S0      
317GND              VIA   -    MD0100PA00X+157571Y+136989X0180Y         S0      
317GND              VIA   -    MD0100PA00X+157571Y+137488X0180Y         S0      
317GND              VIA   -    MD0100PA00X+157571Y+138180X0180Y         S0      
317GND              VIA   -    MD0080PA00X+157717Y+138430X0160Y         S0      
317GND              VIA   -    MD0080PA00X+157717Y+137238X0160Y         S0      
317GND              VIA   -    MD0080PA00X+156493Y+139658X0160Y         S0      
317GND              VIA   -    MD0100PA00X+157075Y+139908X0180Y         S0      
317GND              VIA   -    MD0100PA00X+157075Y+139399X0180Y         S0      
317GND              VIA   -    MD0100PA00X+157075Y+138679X0180Y         S0      
317GND              VIA   -    MD0080PA00X+156929Y+139658X0160Y         S0      
317GND              VIA   -    MD0100PA00X+157571Y+139399X0180Y         S0      
317GND              VIA   -    MD0100PA00X+157571Y+139908X0180Y         S0      
317GND              VIA   -    MD0100PA00X+157571Y+138679X0180Y         S0      
317GND              VIA   -    MD0080PA00X+157717Y+139658X0160Y         S0      
317GND              VIA   -    MD0080PA00X+156493Y+140850X0160Y         S0      
317GND              VIA   -    MD0100PA00X+157075Y+141099X0180Y         S0      
317GND              VIA   -    MD0100PA00X+157075Y+140600X0180Y         S0      
317GND              VIA   -    MD0080PA00X+156929Y+140850X0160Y         S0      
317GND              VIA   -    MD0100PA00X+157571Y+141099X0180Y         S0      
317GND              VIA   -    MD0100PA00X+157571Y+140600X0180Y         S0      
317GND              VIA   -    MD0080PA00X+157717Y+140850X0160Y         S0      
317GND              VIA   -    MD0080PA00X+158153Y+134819X0160Y         S0      
317GND              VIA   -    MD0100PA00X+158299Y+135068X0180Y         S0      
317GND              VIA   -    MD0100PA00X+158299Y+134569X0180Y         S0      
317GND              VIA   -    MD0080PA00X+158941Y+134819X0160Y         S0      
317GND              VIA   -    MD0100PA00X+158795Y+134569X0180Y         S0      
317GND              VIA   -    MD0100PA00X+158795Y+135068X0180Y         S0      
317GND              VIA   -    MD0100PA00X+156347Y+135760X0180Y         S0      
317GND              VIA   -    MD0080PA00X+155705Y+136010X0160Y         S0      
317GND              VIA   -    MD0100PA00X+155851Y+135760X0180Y         S0      
317GND              VIA   -    MD0100PA00X+155851Y+136260X0180Y         S0      
317GND              VIA   -    MD0080PA00X+155269Y+138430X0160Y         S0      
317GND              VIA   -    MD0080PA00X+155269Y+137238X0160Y         S0      
317GND              VIA   -    MD0100PA00X+155123Y+137488X0180Y         S0      
317GND              VIA   -    MD0100PA00X+155123Y+138180X0180Y         S0      
317GND              VIA   -    MD0100PA00X+155123Y+136989X0180Y         S0      
317GND              VIA   -    MD0100PA00X+156347Y+138180X0180Y         S0      
317GND              VIA   -    MD0100PA00X+156347Y+136989X0180Y         S0      
317GND              VIA   -    MD0100PA00X+156347Y+137488X0180Y         S0      
317GND              VIA   -    MD0100PA00X+155851Y+138180X0180Y         S0      
317GND              VIA   -    MD0100PA00X+155851Y+136989X0180Y         S0      
317GND              VIA   -    MD0100PA00X+155851Y+137488X0180Y         S0      
317GND              VIA   -    MD0080PA00X+155705Y+137238X0160Y         S0      
317GND              VIA   -    MD0080PA00X+155705Y+138430X0160Y         S0      
317GND              VIA   -    MD0100PA00X+155123Y+139908X0180Y         S0      
317GND              VIA   -    MD0100PA00X+155123Y+139409X0180Y         S0      
317GND              VIA   -    MD0100PA00X+155123Y+138679X0180Y         S0      
317GND              VIA   -    MD0080PA00X+155269Y+139658X0160Y         S0      
317GND              VIA   -    MD0100PA00X+156347Y+138679X0180Y         S0      
317GND              VIA   -    MD0100PA00X+156347Y+139409X0180Y         S0      
317GND              VIA   -    MD0100PA00X+156347Y+139908X0180Y         S0      
317GND              VIA   -    MD0080PA00X+155705Y+139658X0160Y         S0      
317GND              VIA   -    MD0100PA00X+155851Y+138679X0180Y         S0      
317GND              VIA   -    MD0100PA00X+155851Y+139409X0180Y         S0      
317GND              VIA   -    MD0100PA00X+155851Y+139908X0180Y         S0      
317GND              VIA   -    MD0100PA00X+155123Y+141099X0180Y         S0      
317GND              VIA   -    MD0100PA00X+155123Y+140600X0180Y         S0      
317GND              VIA   -    MD0080PA00X+155269Y+140850X0160Y         S0      
317GND              VIA   -    MD0100PA00X+156347Y+141099X0180Y         S0      
317GND              VIA   -    MD0100PA00X+156347Y+140600X0180Y         S0      
317GND              VIA   -    MD0080PA00X+155705Y+140850X0160Y         S0      
317GND              VIA   -    MD0100PA00X+155851Y+141099X0180Y         S0      
317GND              VIA   -    MD0100PA00X+155851Y+140600X0180Y         S0      
317GND              VIA   -    MD0080PA00X+156493Y+134819X0160Y         S0      
317GND              VIA   -    MD0100PA00X+157571Y+134560X0180Y         S0      
317GND              VIA   -    MD0080PA00X+154045Y+137238X0160Y         S0      
317GND              VIA   -    MD0080PA00X+154045Y+138430X0160Y         S0      
317GND              VIA   -    MD0100PA00X+153899Y+137488X0180Y         S0      
317GND              VIA   -    MD0100PA00X+153899Y+138180X0180Y         S0      
317GND              VIA   -    MD0100PA00X+153899Y+136989X0180Y         S0      
317GND              VIA   -    MD0080PA00X+153257Y+137238X0160Y         S0      
317GND              VIA   -    MD0080PA00X+153257Y+138430X0160Y         S0      
317GND              VIA   -    MD0100PA00X+153403Y+137488X0180Y         S0      
317GND              VIA   -    MD0100PA00X+153403Y+138180X0180Y         S0      
317GND              VIA   -    MD0100PA00X+153403Y+136989X0180Y         S0      
317GND              VIA   -    MD0100PA00X+154627Y+138180X0180Y         S0      
317GND              VIA   -    MD0100PA00X+154627Y+136989X0180Y         S0      
317GND              VIA   -    MD0080PA00X+154481Y+137238X0160Y         S0      
317GND              VIA   -    MD0080PA00X+154481Y+138430X0160Y         S0      
317GND              VIA   -    MD0100PA00X+154627Y+137488X0180Y         S0      
317GND              VIA   -    MD0080PA00X+154045Y+139658X0160Y         S0      
317GND              VIA   -    MD0100PA00X+153899Y+138679X0180Y         S0      
317GND              VIA   -    MD0100PA00X+153899Y+139908X0180Y         S0      
317GND              VIA   -    MD0100PA00X+153899Y+139409X0180Y         S0      
317GND              VIA   -    MD0080PA00X+153257Y+139658X0160Y         S0      
317GND              VIA   -    MD0100PA00X+153403Y+138679X0180Y         S0      
317GND              VIA   -    MD0100PA00X+153403Y+139908X0180Y         S0      
317GND              VIA   -    MD0100PA00X+153403Y+139409X0180Y         S0      
317GND              VIA   -    MD0100PA00X+154627Y+139908X0180Y         S0      
317GND              VIA   -    MD0100PA00X+154627Y+139409X0180Y         S0      
317GND              VIA   -    MD0100PA00X+154627Y+138679X0180Y         S0      
317GND              VIA   -    MD0080PA00X+154481Y+139658X0160Y         S0      
317GND              VIA   -    MD0080PA00X+154045Y+140850X0160Y         S0      
317GND              VIA   -    MD0100PA00X+153899Y+141099X0180Y         S0      
317GND              VIA   -    MD0100PA00X+153899Y+140600X0180Y         S0      
317GND              VIA   -    MD0080PA00X+153257Y+140850X0160Y         S0      
317GND              VIA   -    MD0100PA00X+153403Y+141099X0180Y         S0      
317GND              VIA   -    MD0100PA00X+153403Y+140600X0180Y         S0      
317GND              VIA   -    MD0100PA00X+154627Y+141099X0180Y         S0      
317GND              VIA   -    MD0100PA00X+154627Y+140600X0180Y         S0      
317GND              VIA   -    MD0080PA00X+154481Y+140850X0160Y         S0      
317GND              VIA   -    MD0100PA00X+155123Y+134569X0180Y         S0      
317GND              VIA   -    MD0100PA00X+155123Y+135068X0180Y         S0      
317GND              VIA   -    MD0080PA00X+155269Y+134819X0160Y         S0      
317GND              VIA   -    MD0100PA00X+156347Y+134569X0180Y         S0      
317GND              VIA   -    MD0100PA00X+156347Y+135068X0180Y         S0      
317GND              VIA   -    MD0080PA00X+155705Y+134819X0160Y         S0      
317GND              VIA   -    MD0100PA00X+155851Y+135068X0180Y         S0      
317GND              VIA   -    MD0100PA00X+155851Y+134569X0180Y         S0      
317GND              VIA   -    MD0100PA00X+155123Y+136260X0180Y         S0      
317GND              VIA   -    MD0100PA00X+155123Y+135760X0180Y         S0      
317GND              VIA   -    MD0080PA00X+155269Y+136010X0160Y         S0      
317GND              VIA   -    MD0100PA00X+156347Y+136260X0180Y         S0      
317GND              VIA   -    MD0080PA00X+151597Y+137238X0160Y         S0      
317GND              VIA   -    MD0080PA00X+151597Y+138430X0160Y         S0      
317GND              VIA   -    MD0100PA00X+152179Y+136989X0180Y         S0      
317GND              VIA   -    MD0100PA00X+152179Y+138180X0180Y         S0      
317GND              VIA   -    MD0100PA00X+152179Y+137488X0180Y         S0      
317GND              VIA   -    MD0080PA00X+152033Y+138430X0160Y         S0      
317GND              VIA   -    MD0080PA00X+152033Y+137238X0160Y         S0      
317GND              VIA   -    MD0100PA00X+152675Y+138180X0180Y         S0      
317GND              VIA   -    MD0100PA00X+152675Y+137488X0180Y         S0      
317GND              VIA   -    MD0100PA00X+152675Y+136989X0180Y         S0      
317GND              VIA   -    MD0080PA00X+152821Y+138430X0160Y         S0      
317GND              VIA   -    MD0080PA00X+152821Y+137238X0160Y         S0      
317GND              VIA   -    MD0080PA00X+151597Y+139658X0160Y         S0      
317GND              VIA   -    MD0100PA00X+152179Y+139908X0180Y         S0      
317GND              VIA   -    MD0100PA00X+152179Y+139409X0180Y         S0      
317GND              VIA   -    MD0100PA00X+152179Y+138679X0180Y         S0      
317GND              VIA   -    MD0080PA00X+152033Y+139658X0160Y         S0      
317GND              VIA   -    MD0100PA00X+152675Y+139409X0180Y         S0      
317GND              VIA   -    MD0100PA00X+152675Y+139908X0180Y         S0      
317GND              VIA   -    MD0100PA00X+152675Y+138679X0180Y         S0      
317GND              VIA   -    MD0080PA00X+152821Y+139658X0160Y         S0      
317GND              VIA   -    MD0080PA00X+151597Y+140850X0160Y         S0      
317GND              VIA   -    MD0100PA00X+152179Y+141099X0180Y         S0      
317GND              VIA   -    MD0100PA00X+152179Y+140600X0180Y         S0      
317GND              VIA   -    MD0080PA00X+152033Y+140850X0160Y         S0      
317GND              VIA   -    MD0100PA00X+152675Y+141099X0180Y         S0      
317GND              VIA   -    MD0100PA00X+152675Y+140600X0180Y         S0      
317GND              VIA   -    MD0080PA00X+152821Y+140850X0160Y         S0      
317GND              VIA   -    MD0080PA00X+154045Y+134819X0160Y         S0      
317GND              VIA   -    MD0100PA00X+153899Y+135068X0180Y         S0      
317GND              VIA   -    MD0100PA00X+153899Y+134569X0180Y         S0      
317GND              VIA   -    MD0080PA00X+153257Y+134819X0160Y         S0      
317GND              VIA   -    MD0100PA00X+153403Y+134569X0180Y         S0      
317GND              VIA   -    MD0100PA00X+153403Y+135068X0180Y         S0      
317GND              VIA   -    MD0100PA00X+154627Y+134569X0180Y         S0      
317GND              VIA   -    MD0100PA00X+154627Y+135068X0180Y         S0      
317GND              VIA   -    MD0080PA00X+154481Y+134819X0160Y         S0      
317GND              VIA   -    MD0080PA00X+154045Y+136010X0160Y         S0      
317GND              VIA   -    MD0100PA00X+153899Y+135760X0180Y         S0      
317GND              VIA   -    MD0100PA00X+153899Y+136260X0180Y         S0      
317GND              VIA   -    MD0100PA00X+153403Y+136260X0180Y         S0      
317GND              VIA   -    MD0100PA00X+153403Y+135760X0180Y         S0      
317GND              VIA   -    MD0080PA00X+153257Y+136010X0160Y         S0      
317GND              VIA   -    MD0100PA00X+154627Y+136260X0180Y         S0      
317GND              VIA   -    MD0100PA00X+154627Y+135760X0180Y         S0      
317GND              VIA   -    MD0080PA00X+154481Y+136010X0160Y         S0      
317GND              VIA   -    MD0100PA00X+150227Y+136989X0180Y         S0      
317GND              VIA   -    MD0100PA00X+150227Y+137488X0180Y         S0      
317GND              VIA   -    MD0100PA00X+150227Y+138180X0180Y         S0      
317GND              VIA   -    MD0080PA00X+150373Y+138430X0160Y         S0      
317GND              VIA   -    MD0080PA00X+150373Y+137238X0160Y         S0      
317GND              VIA   -    MD0100PA00X+151451Y+138180X0180Y         S0      
317GND              VIA   -    MD0100PA00X+151451Y+136989X0180Y         S0      
317GND              VIA   -    MD0100PA00X+151451Y+137488X0180Y         S0      
317GND              VIA   -    MD0080PA00X+150809Y+137238X0160Y         S0      
317GND              VIA   -    MD0080PA00X+150809Y+138430X0160Y         S0      
317GND              VIA   -    MD0100PA00X+150955Y+138180X0180Y         S0      
317GND              VIA   -    MD0100PA00X+150955Y+136989X0180Y         S0      
317GND              VIA   -    MD0100PA00X+150955Y+137488X0180Y         S0      
317GND              VIA   -    MD0100PA00X+150227Y+139409X0180Y         S0      
317GND              VIA   -    MD0100PA00X+150227Y+139908X0180Y         S0      
317GND              VIA   -    MD0100PA00X+150227Y+138679X0180Y         S0      
317GND              VIA   -    MD0080PA00X+150373Y+139658X0160Y         S0      
317GND              VIA   -    MD0100PA00X+151451Y+138679X0180Y         S0      
317GND              VIA   -    MD0100PA00X+151451Y+139908X0180Y         S0      
317GND              VIA   -    MD0100PA00X+151451Y+139409X0180Y         S0      
317GND              VIA   -    MD0080PA00X+150809Y+139658X0160Y         S0      
317GND              VIA   -    MD0100PA00X+150955Y+138679X0180Y         S0      
317GND              VIA   -    MD0100PA00X+150955Y+139908X0180Y         S0      
317GND              VIA   -    MD0100PA00X+150955Y+139409X0180Y         S0      
317GND              VIA   -    MD0100PA00X+150227Y+141099X0180Y         S0      
317GND              VIA   -    MD0100PA00X+150227Y+140600X0180Y         S0      
317GND              VIA   -    MD0080PA00X+150373Y+140850X0160Y         S0      
317GND              VIA   -    MD0100PA00X+151451Y+141099X0180Y         S0      
317GND              VIA   -    MD0100PA00X+151451Y+140600X0180Y         S0      
317GND              VIA   -    MD0080PA00X+150809Y+140850X0160Y         S0      
317GND              VIA   -    MD0100PA00X+150955Y+141099X0180Y         S0      
317GND              VIA   -    MD0100PA00X+150955Y+140600X0180Y         S0      
317GND              VIA   -    MD0080PA00X+151597Y+134819X0160Y         S0      
317GND              VIA   -    MD0080PA00X+152033Y+134819X0160Y         S0      
317GND              VIA   -    MD0100PA00X+152179Y+135068X0180Y         S0      
317GND              VIA   -    MD0100PA00X+152179Y+134569X0180Y         S0      
317GND              VIA   -    MD0100PA00X+152675Y+135068X0180Y         S0      
317GND              VIA   -    MD0100PA00X+152675Y+134569X0180Y         S0      
317GND              VIA   -    MD0080PA00X+152821Y+134819X0160Y         S0      
317GND              VIA   -    MD0080PA00X+151597Y+136010X0160Y         S0      
317GND              VIA   -    MD0100PA00X+152179Y+136260X0180Y         S0      
317GND              VIA   -    MD0100PA00X+152179Y+135760X0180Y         S0      
317GND              VIA   -    MD0080PA00X+152033Y+136010X0160Y         S0      
317GND              VIA   -    MD0100PA00X+152675Y+136260X0180Y         S0      
317GND              VIA   -    MD0100PA00X+152675Y+135760X0180Y         S0      
317GND              VIA   -    MD0080PA00X+152821Y+136010X0160Y         S0      
317GND              VIA   -    MD0100PA00X+149731Y+136989X0180Y         S0      
317GND              VIA   -    MD0100PA00X+149731Y+137488X0180Y         S0      
317GND              VIA   -    MD0100PA00X+149731Y+138180X0180Y         S0      
317GND              VIA   -    MD0080PA00X+149585Y+137238X0160Y         S0      
317GND              VIA   -    MD0080PA00X+149585Y+138430X0160Y         S0      
317GND              VIA   -    MD0080PA00X+149149Y+139658X0160Y         S0      
317GND              VIA   -    MD0100PA00X+149003Y+138679X0180Y         S0      
317GND              VIA   -    MD0100PA00X+149003Y+139409X0180Y         S0      
317GND              VIA   -    MD0100PA00X+149003Y+139908X0180Y         S0      
317GND              VIA   -    MD0080PA00X+148361Y+139658X0160Y         S0      
317GND              VIA   -    MD0100PA00X+148507Y+138679X0180Y         S0      
317GND              VIA   -    MD0100PA00X+148507Y+139908X0180Y         S0      
317GND              VIA   -    MD0100PA00X+148507Y+139409X0180Y         S0      
317GND              VIA   -    MD0100PA00X+149731Y+139908X0180Y         S0      
317GND              VIA   -    MD0100PA00X+149731Y+139409X0180Y         S0      
317GND              VIA   -    MD0100PA00X+149731Y+138679X0180Y         S0      
317GND              VIA   -    MD0080PA00X+149585Y+139658X0160Y         S0      
317GND              VIA   -    MD0080PA00X+149149Y+140850X0160Y         S0      
317GND              VIA   -    MD0100PA00X+149003Y+141099X0180Y         S0      
317GND              VIA   -    MD0100PA00X+149003Y+140600X0180Y         S0      
317GND              VIA   -    MD0080PA00X+148361Y+140850X0160Y         S0      
317GND              VIA   -    MD0100PA00X+148507Y+141099X0180Y         S0      
317GND              VIA   -    MD0100PA00X+148507Y+140600X0180Y         S0      
317GND              VIA   -    MD0100PA00X+149731Y+141099X0180Y         S0      
317GND              VIA   -    MD0100PA00X+149731Y+140600X0180Y         S0      
317GND              VIA   -    MD0080PA00X+149585Y+140850X0160Y         S0      
317GND              VIA   -    MD0100PA00X+150227Y+134569X0180Y         S0      
317GND              VIA   -    MD0100PA00X+150227Y+135068X0180Y         S0      
317GND              VIA   -    MD0080PA00X+150373Y+134819X0160Y         S0      
317GND              VIA   -    MD0100PA00X+151451Y+134569X0180Y         S0      
317GND              VIA   -    MD0100PA00X+151451Y+135068X0180Y         S0      
317GND              VIA   -    MD0080PA00X+150809Y+134819X0160Y         S0      
317GND              VIA   -    MD0100PA00X+150955Y+134569X0180Y         S0      
317GND              VIA   -    MD0100PA00X+150955Y+135068X0180Y         S0      
317GND              VIA   -    MD0100PA00X+150227Y+136260X0180Y         S0      
317GND              VIA   -    MD0100PA00X+150227Y+135760X0180Y         S0      
317GND              VIA   -    MD0080PA00X+150373Y+136010X0160Y         S0      
317GND              VIA   -    MD0100PA00X+151451Y+136260X0180Y         S0      
317GND              VIA   -    MD0100PA00X+151451Y+135760X0180Y         S0      
317GND              VIA   -    MD0080PA00X+150809Y+136010X0160Y         S0      
317GND              VIA   -    MD0100PA00X+150955Y+135760X0180Y         S0      
317GND              VIA   -    MD0100PA00X+150955Y+136260X0180Y         S0      
317GND              VIA   -    MD0100PA00X+147283Y+139908X0180Y         S0      
317GND              VIA   -    MD0100PA00X+147283Y+139399X0180Y         S0      
317GND              VIA   -    MD0100PA00X+147283Y+138679X0180Y         S0      
317GND              VIA   -    MD0080PA00X+147137Y+139658X0160Y         S0      
317GND              VIA   -    MD0100PA00X+147779Y+139399X0180Y         S0      
317GND              VIA   -    MD0100PA00X+147779Y+139908X0180Y         S0      
317GND              VIA   -    MD0080PA00X+147925Y+139658X0160Y         S0      
317GND              VIA   -    MD0100PA00X+147779Y+138679X0180Y         S0      
317GND              VIA   -    MD0100PA00X+147283Y+141099X0180Y         S0      
317GND              VIA   -    MD0100PA00X+147283Y+140600X0180Y         S0      
317GND              VIA   -    MD0080PA00X+147137Y+140850X0160Y         S0      
317GND              VIA   -    MD0100PA00X+147779Y+141099X0180Y         S0      
317GND              VIA   -    MD0100PA00X+147779Y+140600X0180Y         S0      
317GND              VIA   -    MD0080PA00X+147925Y+140850X0160Y         S0      
317GND              VIA   -    MD0080PA00X+149149Y+134819X0160Y         S0      
317GND              VIA   -    MD0100PA00X+149003Y+135068X0180Y         S0      
317GND              VIA   -    MD0100PA00X+149003Y+134569X0180Y         S0      
317GND              VIA   -    MD0080PA00X+148361Y+134819X0160Y         S0      
317GND              VIA   -    MD0100PA00X+148507Y+135068X0180Y         S0      
317GND              VIA   -    MD0100PA00X+148507Y+134569X0180Y         S0      
317GND              VIA   -    MD0100PA00X+149731Y+134569X0180Y         S0      
317GND              VIA   -    MD0100PA00X+149731Y+135068X0180Y         S0      
317GND              VIA   -    MD0080PA00X+149585Y+134819X0160Y         S0      
317GND              VIA   -    MD0080PA00X+149149Y+136010X0160Y         S0      
317GND              VIA   -    MD0100PA00X+149003Y+136260X0180Y         S0      
317GND              VIA   -    MD0100PA00X+149003Y+135760X0180Y         S0      
317GND              VIA   -    MD0080PA00X+148361Y+136010X0160Y         S0      
317GND              VIA   -    MD0100PA00X+148507Y+135760X0180Y         S0      
317GND              VIA   -    MD0100PA00X+148507Y+136260X0180Y         S0      
317GND              VIA   -    MD0100PA00X+149731Y+136260X0180Y         S0      
317GND              VIA   -    MD0100PA00X+149731Y+135760X0180Y         S0      
317GND              VIA   -    MD0080PA00X+149585Y+136010X0160Y         S0      
317GND              VIA   -    MD0080PA00X+149149Y+137238X0160Y         S0      
317GND              VIA   -    MD0080PA00X+149149Y+138430X0160Y         S0      
317GND              VIA   -    MD0100PA00X+149003Y+138180X0180Y         S0      
317GND              VIA   -    MD0100PA00X+149003Y+137488X0180Y         S0      
317GND              VIA   -    MD0100PA00X+149003Y+136989X0180Y         S0      
317GND              VIA   -    MD0080PA00X+148361Y+137238X0160Y         S0      
317GND              VIA   -    MD0080PA00X+148361Y+138430X0160Y         S0      
317GND              VIA   -    MD0100PA00X+148507Y+138180X0180Y         S0      
317GND              VIA   -    MD0100PA00X+148507Y+137488X0180Y         S0      
317GND              VIA   -    MD0100PA00X+148507Y+136989X0180Y         S0      
317GND              VIA   -    MD0100PA00X+146555Y+135068X0180Y         S0      
317GND              VIA   -    MD0100PA00X+146555Y+134569X0180Y         S0      
317GND              VIA   -    MD0080PA00X+145913Y+134819X0160Y         S0      
317GND              VIA   -    MD0100PA00X+146059Y+135068X0180Y         S0      
317GND              VIA   -    MD0100PA00X+146059Y+134569X0180Y         S0      
317GND              VIA   -    MD0100PA00X+146555Y+136260X0180Y         S0      
317GND              VIA   -    MD0100PA00X+146555Y+135760X0180Y         S0      
317GND              VIA   -    MD0080PA00X+145913Y+136010X0160Y         S0      
317GND              VIA   -    MD0100PA00X+146059Y+136260X0180Y         S0      
317GND              VIA   -    MD0100PA00X+146059Y+135760X0180Y         S0      
317GND              VIA   -    MD0100PA00X+146555Y+136989X0180Y         S0      
317GND              VIA   -    MD0100PA00X+146555Y+137488X0180Y         S0      
317GND              VIA   -    MD0100PA00X+146555Y+138180X0180Y         S0      
317GND              VIA   -    MD0080PA00X+145913Y+137238X0160Y         S0      
317GND              VIA   -    MD0080PA00X+145913Y+138430X0160Y         S0      
317GND              VIA   -    MD0100PA00X+146059Y+136989X0180Y         S0      
317GND              VIA   -    MD0100PA00X+146059Y+137488X0180Y         S0      
317GND              VIA   -    MD0100PA00X+146059Y+138180X0180Y         S0      
317GND              VIA   -    MD0100PA00X+146555Y+138679X0180Y         S0      
317GND              VIA   -    MD0100PA00X+146059Y+138679X0180Y         S0      
317GND              VIA   -    MD0080PA00X+146701Y+134819X0160Y         S0      
317GND              VIA   -    MD0100PA00X+147283Y+134569X0180Y         S0      
317GND              VIA   -    MD0100PA00X+147283Y+135068X0180Y         S0      
317GND              VIA   -    MD0080PA00X+147137Y+134819X0160Y         S0      
317GND              VIA   -    MD0080PA00X+147925Y+134819X0160Y         S0      
317GND              VIA   -    MD0100PA00X+147779Y+134569X0180Y         S0      
317GND              VIA   -    MD0100PA00X+147779Y+135068X0180Y         S0      
317GND              VIA   -    MD0080PA00X+146701Y+136010X0160Y         S0      
317GND              VIA   -    MD0100PA00X+147283Y+136260X0180Y         S0      
317GND              VIA   -    MD0100PA00X+147283Y+135760X0180Y         S0      
317GND              VIA   -    MD0080PA00X+147137Y+136010X0160Y         S0      
317GND              VIA   -    MD0080PA00X+147925Y+136010X0160Y         S0      
317GND              VIA   -    MD0100PA00X+147779Y+136260X0180Y         S0      
317GND              VIA   -    MD0100PA00X+147779Y+135760X0180Y         S0      
317GND              VIA   -    MD0080PA00X+146701Y+137238X0160Y         S0      
317GND              VIA   -    MD0080PA00X+146701Y+138430X0160Y         S0      
317GND              VIA   -    MD0100PA00X+147283Y+137488X0180Y         S0      
317GND              VIA   -    MD0100PA00X+147283Y+136980X0180Y         S0      
317GND              VIA   -    MD0100PA00X+147283Y+138180X0180Y         S0      
317GND              VIA   -    MD0080PA00X+147137Y+138430X0160Y         S0      
317GND              VIA   -    MD0080PA00X+147137Y+137238X0160Y         S0      
317GND              VIA   -    MD0100PA00X+147779Y+137488X0180Y         S0      
317GND              VIA   -    MD0100PA00X+147779Y+136980X0180Y         S0      
317GND              VIA   -    MD0100PA00X+147779Y+138180X0180Y         S0      
317GND              VIA   -    MD0080PA00X+147925Y+137238X0160Y         S0      
317GND              VIA   -    MD0080PA00X+147925Y+138430X0160Y         S0      
327GND              U6    -F21        A01X+137832Y+088184X0160Y         S1      
327GND              C2041 -2          A18X+138146Y+088502X0164Y0164R180 S2      
317GND              VIA   -    MD0100PA00X+137990Y+088341X0180Y    R180 S0      
317GND              VIA   -    MD0100PA00X+137045Y+088656X0180Y         S0      
327GND              U6    -E18        A01X+136887Y+088499X0160Y         S1      
317GND              VIA   -    MD0100PA00X+132636Y+088656X0180Y         S0      
327GND              U6    -E5         A01X+132793Y+088499X0160Y         S1      
317GND              VIA   -    MD0100PA00X+088767Y+087679X0180Y    R270 S0      
327GND              U5    -N13        A01X+088924Y+087521X0160Y    R180 S1      
327GND              C2039 -2          A18X+137827Y+084402X0164Y0164R180 S2      
327GND              U6    -V21        A01X+137832Y+084404X0160Y         S1      
317GND              VIA   -    MD0100PA00X+137990Y+084247X0180Y         S0      
327GND              U70   -1          A01X+149943Y+091668X0110Y0540     S1      
327GND              U70   -5          A01X+150730Y+091668X0110Y0540     S1      
327GND              C2579 -2          A01X+150736Y+090724X0198Y0197     S1      
327GND              C2578 -2          A01X+149721Y+090724X0198Y0197R180 S1      
327GND              Y3    -4          A01X+150270Y+089482X0480Y0560R090 S1      
317GND              VIA   -    MD0080PA00X+106035Y+136010X0160Y         S0      
317GND              VIA   -    MD0080PA00X+106471Y+136010X0160Y         S0      
317GND              VIA   -    MD0080PA00X+106035Y+134819X0160Y         S0      
317GND              VIA   -    MD0080PA00X+106471Y+134819X0160Y         S0      
317GND              VIA   -    MD0080PA00X+105247Y+136010X0160Y         S0      
317GND              VIA   -    MD0100PA00X+105394Y+135760X0180Y         S0      
317GND              VIA   -    MD0100PA00X+105889Y+135760X0180Y         S0      
317GND              VIA   -    MD0080PA00X+105247Y+134819X0160Y         S0      
317GND              VIA   -    MD0100PA00X+105394Y+135068X0180Y         S0      
317GND              VIA   -    MD0100PA00X+105394Y+134569X0180Y         S0      
317GND              VIA   -    MD0100PA00X+105889Y+135068X0180Y         S0      
317GND              VIA   -    MD0100PA00X+105889Y+134569X0180Y         S0      
317GND              VIA   -    MD0080PA00X+106035Y+137238X0160Y         S0      
317GND              VIA   -    MD0080PA00X+106035Y+138430X0160Y         S0      
317GND              VIA   -    MD0080PA00X+106471Y+138430X0160Y         S0      
317GND              VIA   -    MD0080PA00X+106471Y+137238X0160Y         S0      
317GND              VIA   -    MD0100PA00X+105394Y+138679X0180Y         S0      
317GND              VIA   -    MD0100PA00X+105889Y+138679X0180Y         S0      
317GND              VIA   -    MD0080PA00X+105247Y+137238X0160Y         S0      
317GND              VIA   -    MD0080PA00X+105247Y+138430X0160Y         S0      
317GND              VIA   -    MD0100PA00X+105394Y+136989X0180Y         S0      
317GND              VIA   -    MD0100PA00X+105394Y+137488X0180Y         S0      
317GND              VIA   -    MD0100PA00X+105394Y+138180X0180Y         S0      
317GND              VIA   -    MD0100PA00X+105889Y+136989X0180Y         S0      
317GND              VIA   -    MD0100PA00X+105889Y+137488X0180Y         S0      
317GND              VIA   -    MD0100PA00X+105889Y+138180X0180Y         S0      
317GND              VIA   -    MD0100PA00X+105394Y+136260X0180Y         S0      
317GND              VIA   -    MD0100PA00X+105889Y+136260X0180Y         S0      
317GND              VIA   -    MD0080PA00X+106471Y+140850X0160Y         S0      
317GND              VIA   -    MD0080PA00X+106471Y+139658X0160Y         S0      
317GND              VIA   -    MD0080PA00X+117487Y+140850X0160Y         S0      
317GND              VIA   -    MD0100PA00X+117634Y+141099X0180Y         S0      
317GND              VIA   -    MD0100PA00X+117634Y+140600X0180Y         S0      
317GND              VIA   -    MD0080PA00X+118275Y+140850X0160Y         S0      
317GND              VIA   -    MD0100PA00X+118129Y+141099X0180Y         S0      
317GND              VIA   -    MD0100PA00X+118129Y+140600X0180Y         S0      
317GND              VIA   -    MD0080PA00X+117487Y+139658X0160Y         S0      
317GND              VIA   -    MD0100PA00X+117634Y+139409X0180Y         S0      
317GND              VIA   -    MD0100PA00X+117634Y+139908X0180Y         S0      
317GND              VIA   -    MD0100PA00X+117634Y+138679X0180Y         S0      
317GND              VIA   -    MD0080PA00X+118275Y+139658X0160Y         S0      
317GND              VIA   -    MD0100PA00X+118129Y+139409X0180Y         S0      
317GND              VIA   -    MD0100PA00X+118129Y+139908X0180Y         S0      
317GND              VIA   -    MD0100PA00X+118129Y+138679X0180Y         S0      
317GND              VIA   -    MD0080PA00X+117487Y+137238X0160Y         S0      
317GND              VIA   -    MD0080PA00X+117487Y+138430X0160Y         S0      
317GND              VIA   -    MD0100PA00X+117634Y+137488X0180Y         S0      
317GND              VIA   -    MD0100PA00X+117634Y+138180X0180Y         S0      
317GND              VIA   -    MD0100PA00X+117634Y+136989X0180Y         S0      
317GND              VIA   -    MD0080PA00X+118275Y+137238X0160Y         S0      
317GND              VIA   -    MD0080PA00X+118275Y+138430X0160Y         S0      
317GND              VIA   -    MD0100PA00X+118129Y+137488X0180Y         S0      
317GND              VIA   -    MD0100PA00X+118129Y+138180X0180Y         S0      
317GND              VIA   -    MD0100PA00X+118129Y+136989X0180Y         S0      
317GND              VIA   -    MD0080PA00X+117487Y+136010X0160Y         S0      
317GND              VIA   -    MD0100PA00X+117634Y+135760X0180Y         S0      
317GND              VIA   -    MD0100PA00X+117634Y+136260X0180Y         S0      
317GND              VIA   -    MD0080PA00X+118275Y+136010X0160Y         S0      
317GND              VIA   -    MD0100PA00X+118129Y+135760X0180Y         S0      
317GND              VIA   -    MD0100PA00X+118129Y+136260X0180Y         S0      
317GND              VIA   -    MD0080PA00X+117487Y+134819X0160Y         S0      
317GND              VIA   -    MD0100PA00X+117634Y+135068X0180Y         S0      
317GND              VIA   -    MD0100PA00X+117634Y+134569X0180Y         S0      
317GND              VIA   -    MD0080PA00X+118275Y+134819X0160Y         S0      
317GND              VIA   -    MD0100PA00X+118129Y+134569X0180Y         S0      
317GND              VIA   -    MD0100PA00X+118129Y+135068X0180Y         S0      
317GND              VIA   -    MD0080PA00X+115827Y+140850X0160Y         S0      
317GND              VIA   -    MD0080PA00X+117051Y+140850X0160Y         S0      
317GND              VIA   -    MD0100PA00X+116410Y+141099X0180Y         S0      
317GND              VIA   -    MD0100PA00X+116410Y+140600X0180Y         S0      
317GND              VIA   -    MD0080PA00X+116263Y+140850X0160Y         S0      
317GND              VIA   -    MD0100PA00X+116905Y+140600X0180Y         S0      
317GND              VIA   -    MD0100PA00X+116905Y+141099X0180Y         S0      
317GND              VIA   -    MD0080PA00X+115827Y+139658X0160Y         S0      
317GND              VIA   -    MD0080PA00X+117051Y+139658X0160Y         S0      
317GND              VIA   -    MD0100PA00X+116410Y+138679X0180Y         S0      
317GND              VIA   -    MD0100PA00X+116410Y+139908X0180Y         S0      
317GND              VIA   -    MD0100PA00X+116410Y+139399X0180Y         S0      
317GND              VIA   -    MD0080PA00X+116263Y+139658X0160Y         S0      
317GND              VIA   -    MD0100PA00X+116905Y+138679X0180Y         S0      
317GND              VIA   -    MD0100PA00X+116905Y+139908X0180Y         S0      
317GND              VIA   -    MD0100PA00X+116905Y+139399X0180Y         S0      
317GND              VIA   -    MD0080PA00X+115827Y+137238X0160Y         S0      
317GND              VIA   -    MD0080PA00X+115827Y+138430X0160Y         S0      
317GND              VIA   -    MD0080PA00X+117051Y+138430X0160Y         S0      
317GND              VIA   -    MD0080PA00X+117051Y+137238X0160Y         S0      
317GND              VIA   -    MD0100PA00X+116410Y+137488X0180Y         S0      
317GND              VIA   -    MD0100PA00X+116410Y+138180X0180Y         S0      
317GND              VIA   -    MD0100PA00X+116410Y+136989X0180Y         S0      
317GND              VIA   -    MD0080PA00X+116263Y+138430X0160Y         S0      
317GND              VIA   -    MD0080PA00X+116263Y+137238X0160Y         S0      
317GND              VIA   -    MD0100PA00X+116905Y+136989X0180Y         S0      
317GND              VIA   -    MD0100PA00X+116905Y+137488X0180Y         S0      
317GND              VIA   -    MD0100PA00X+116905Y+138180X0180Y         S0      
317GND              VIA   -    MD0080PA00X+115827Y+136010X0160Y         S0      
317GND              VIA   -    MD0080PA00X+117051Y+136010X0160Y         S0      
317GND              VIA   -    MD0100PA00X+116410Y+136260X0180Y         S0      
317GND              VIA   -    MD0100PA00X+116410Y+135760X0180Y         S0      
317GND              VIA   -    MD0080PA00X+116263Y+136010X0160Y         S0      
317GND              VIA   -    MD0100PA00X+116905Y+136260X0180Y         S0      
317GND              VIA   -    MD0100PA00X+116905Y+135760X0180Y         S0      
317GND              VIA   -    MD0080PA00X+115827Y+134819X0160Y         S0      
317GND              VIA   -    MD0080PA00X+117051Y+134819X0160Y         S0      
317GND              VIA   -    MD0100PA00X+116410Y+134560X0180Y         S0      
317GND              VIA   -    MD0100PA00X+116410Y+135068X0180Y         S0      
317GND              VIA   -    MD0080PA00X+116263Y+134819X0160Y         S0      
317GND              VIA   -    MD0100PA00X+116905Y+135068X0180Y         S0      
317GND              VIA   -    MD0100PA00X+116905Y+134560X0180Y         S0      
317GND              VIA   -    MD0080PA00X+114603Y+140850X0160Y         S0      
317GND              VIA   -    MD0100PA00X+114457Y+141099X0180Y         S0      
317GND              VIA   -    MD0100PA00X+114457Y+140600X0180Y         S0      
317GND              VIA   -    MD0080PA00X+115039Y+140850X0160Y         S0      
317GND              VIA   -    MD0100PA00X+115186Y+141099X0180Y         S0      
317GND              VIA   -    MD0100PA00X+115186Y+140600X0180Y         S0      
317GND              VIA   -    MD0100PA00X+115681Y+141099X0180Y         S0      
317GND              VIA   -    MD0100PA00X+115681Y+140600X0180Y         S0      
317GND              VIA   -    MD0100PA00X+114457Y+138679X0180Y         S0      
317GND              VIA   -    MD0080PA00X+114603Y+139658X0160Y         S0      
317GND              VIA   -    MD0100PA00X+114457Y+139908X0180Y         S0      
317GND              VIA   -    MD0100PA00X+114457Y+139409X0180Y         S0      
317GND              VIA   -    MD0080PA00X+115039Y+139658X0160Y         S0      
317GND              VIA   -    MD0100PA00X+115186Y+139409X0180Y         S0      
317GND              VIA   -    MD0100PA00X+115186Y+139908X0180Y         S0      
317GND              VIA   -    MD0100PA00X+115186Y+138679X0180Y         S0      
317GND              VIA   -    MD0100PA00X+115681Y+139409X0180Y         S0      
317GND              VIA   -    MD0100PA00X+115681Y+139908X0180Y         S0      
317GND              VIA   -    MD0100PA00X+115681Y+138679X0180Y         S0      
317GND              VIA   -    MD0080PA00X+114603Y+138430X0160Y         S0      
317GND              VIA   -    MD0080PA00X+114603Y+137238X0160Y         S0      
317GND              VIA   -    MD0100PA00X+114457Y+137488X0180Y         S0      
317GND              VIA   -    MD0100PA00X+114457Y+138180X0180Y         S0      
317GND              VIA   -    MD0100PA00X+114457Y+136989X0180Y         S0      
317GND              VIA   -    MD0100PA00X+115186Y+138180X0180Y         S0      
317GND              VIA   -    MD0100PA00X+115186Y+136989X0180Y         S0      
317GND              VIA   -    MD0100PA00X+115186Y+137488X0180Y         S0      
317GND              VIA   -    MD0080PA00X+115039Y+137238X0160Y         S0      
317GND              VIA   -    MD0080PA00X+115039Y+138430X0160Y         S0      
317GND              VIA   -    MD0100PA00X+115681Y+138180X0180Y         S0      
317GND              VIA   -    MD0100PA00X+115681Y+136989X0180Y         S0      
317GND              VIA   -    MD0100PA00X+115681Y+137488X0180Y         S0      
317GND              VIA   -    MD0080PA00X+114603Y+136010X0160Y         S0      
317GND              VIA   -    MD0100PA00X+114457Y+136260X0180Y         S0      
317GND              VIA   -    MD0100PA00X+114457Y+135760X0180Y         S0      
317GND              VIA   -    MD0080PA00X+115039Y+136010X0160Y         S0      
317GND              VIA   -    MD0100PA00X+115186Y+135760X0180Y         S0      
317GND              VIA   -    MD0100PA00X+115186Y+136260X0180Y         S0      
317GND              VIA   -    MD0100PA00X+115681Y+136260X0180Y         S0      
317GND              VIA   -    MD0100PA00X+115681Y+135760X0180Y         S0      
317GND              VIA   -    MD0080PA00X+114603Y+134819X0160Y         S0      
317GND              VIA   -    MD0100PA00X+114457Y+134569X0180Y         S0      
317GND              VIA   -    MD0100PA00X+114457Y+135068X0180Y         S0      
317GND              VIA   -    MD0080PA00X+115039Y+134819X0160Y         S0      
317GND              VIA   -    MD0100PA00X+115186Y+135068X0180Y         S0      
317GND              VIA   -    MD0100PA00X+115186Y+134569X0180Y         S0      
317GND              VIA   -    MD0100PA00X+115681Y+134569X0180Y         S0      
317GND              VIA   -    MD0100PA00X+115681Y+135068X0180Y         S0      
317GND              VIA   -    MD0080PA00X+112591Y+140850X0160Y         S0      
317GND              VIA   -    MD0100PA00X+112738Y+141099X0180Y         S0      
317GND              VIA   -    MD0100PA00X+112738Y+140600X0180Y         S0      
317GND              VIA   -    MD0080PA00X+113379Y+140850X0160Y         S0      
317GND              VIA   -    MD0100PA00X+113233Y+141099X0180Y         S0      
317GND              VIA   -    MD0100PA00X+113233Y+140600X0180Y         S0      
317GND              VIA   -    MD0080PA00X+113815Y+140850X0160Y         S0      
317GND              VIA   -    MD0100PA00X+113962Y+141099X0180Y         S0      
317GND              VIA   -    MD0100PA00X+113962Y+140600X0180Y         S0      
317GND              VIA   -    MD0080PA00X+112591Y+139658X0160Y         S0      
317GND              VIA   -    MD0100PA00X+112738Y+139908X0180Y         S0      
317GND              VIA   -    MD0100PA00X+112738Y+139409X0180Y         S0      
317GND              VIA   -    MD0100PA00X+112738Y+138679X0180Y         S0      
317GND              VIA   -    MD0080PA00X+113379Y+139658X0160Y         S0      
317GND              VIA   -    MD0100PA00X+113233Y+139908X0180Y         S0      
317GND              VIA   -    MD0100PA00X+113233Y+139409X0180Y         S0      
317GND              VIA   -    MD0100PA00X+113233Y+138679X0180Y         S0      
317GND              VIA   -    MD0080PA00X+113815Y+139658X0160Y         S0      
317GND              VIA   -    MD0100PA00X+113962Y+138679X0180Y         S0      
317GND              VIA   -    MD0100PA00X+113962Y+139908X0180Y         S0      
317GND              VIA   -    MD0100PA00X+113962Y+139409X0180Y         S0      
317GND              VIA   -    MD0080PA00X+112591Y+137238X0160Y         S0      
317GND              VIA   -    MD0080PA00X+112591Y+138430X0160Y         S0      
317GND              VIA   -    MD0100PA00X+112738Y+137488X0180Y         S0      
317GND              VIA   -    MD0100PA00X+112738Y+138180X0180Y         S0      
317GND              VIA   -    MD0100PA00X+112738Y+136989X0180Y         S0      
317GND              VIA   -    MD0080PA00X+113379Y+137238X0160Y         S0      
317GND              VIA   -    MD0080PA00X+113379Y+138430X0160Y         S0      
317GND              VIA   -    MD0100PA00X+113233Y+137488X0180Y         S0      
317GND              VIA   -    MD0100PA00X+113233Y+138180X0180Y         S0      
317GND              VIA   -    MD0100PA00X+113233Y+136989X0180Y         S0      
317GND              VIA   -    MD0080PA00X+113815Y+137238X0160Y         S0      
317GND              VIA   -    MD0080PA00X+113815Y+138430X0160Y         S0      
317GND              VIA   -    MD0100PA00X+113962Y+138180X0180Y         S0      
317GND              VIA   -    MD0100PA00X+113962Y+136989X0180Y         S0      
317GND              VIA   -    MD0100PA00X+113962Y+137488X0180Y         S0      
317GND              VIA   -    MD0100PA00X+112738Y+136260X0180Y         S0      
317GND              VIA   -    MD0100PA00X+112738Y+135760X0180Y         S0      
317GND              VIA   -    MD0080PA00X+112591Y+136010X0160Y         S0      
317GND              VIA   -    MD0100PA00X+113233Y+135760X0180Y         S0      
317GND              VIA   -    MD0100PA00X+113233Y+136260X0180Y         S0      
317GND              VIA   -    MD0080PA00X+113379Y+136010X0160Y         S0      
317GND              VIA   -    MD0080PA00X+113815Y+136010X0160Y         S0      
317GND              VIA   -    MD0100PA00X+113962Y+136260X0180Y         S0      
317GND              VIA   -    MD0100PA00X+113962Y+135760X0180Y         S0      
317GND              VIA   -    MD0080PA00X+112591Y+134819X0160Y         S0      
317GND              VIA   -    MD0100PA00X+112738Y+134569X0180Y         S0      
317GND              VIA   -    MD0100PA00X+112738Y+135068X0180Y         S0      
317GND              VIA   -    MD0080PA00X+113379Y+134819X0160Y         S0      
317GND              VIA   -    MD0100PA00X+113233Y+135068X0180Y         S0      
317GND              VIA   -    MD0100PA00X+113233Y+134569X0180Y         S0      
317GND              VIA   -    MD0080PA00X+113815Y+134819X0160Y         S0      
317GND              VIA   -    MD0100PA00X+113962Y+134569X0180Y         S0      
317GND              VIA   -    MD0100PA00X+113962Y+135068X0180Y         S0      
317GND              VIA   -    MD0080PA00X+110931Y+140850X0160Y         S0      
317GND              VIA   -    MD0100PA00X+112009Y+141099X0180Y         S0      
317GND              VIA   -    MD0100PA00X+112009Y+140600X0180Y         S0      
317GND              VIA   -    MD0080PA00X+112155Y+140850X0160Y         S0      
317GND              VIA   -    MD0100PA00X+111514Y+141099X0180Y         S0      
317GND              VIA   -    MD0100PA00X+111514Y+140600X0180Y         S0      
317GND              VIA   -    MD0080PA00X+111367Y+140850X0160Y         S0      
317GND              VIA   -    MD0080PA00X+110931Y+139658X0160Y         S0      
317GND              VIA   -    MD0100PA00X+112009Y+138679X0180Y         S0      
317GND              VIA   -    MD0100PA00X+112009Y+139409X0180Y         S0      
317GND              VIA   -    MD0100PA00X+112009Y+139908X0180Y         S0      
317GND              VIA   -    MD0080PA00X+112155Y+139658X0160Y         S0      
317GND              VIA   -    MD0100PA00X+111514Y+138679X0180Y         S0      
317GND              VIA   -    MD0100PA00X+111514Y+139908X0180Y         S0      
317GND              VIA   -    MD0100PA00X+111514Y+139409X0180Y         S0      
317GND              VIA   -    MD0080PA00X+111367Y+139658X0160Y         S0      
317GND              VIA   -    MD0080PA00X+110931Y+137238X0160Y         S0      
317GND              VIA   -    MD0080PA00X+110931Y+138430X0160Y         S0      
317GND              VIA   -    MD0100PA00X+112009Y+138180X0180Y         S0      
317GND              VIA   -    MD0100PA00X+112009Y+137488X0180Y         S0      
317GND              VIA   -    MD0100PA00X+112009Y+136989X0180Y         S0      
317GND              VIA   -    MD0080PA00X+112155Y+138430X0160Y         S0      
317GND              VIA   -    MD0080PA00X+112155Y+137238X0160Y         S0      
317GND              VIA   -    MD0100PA00X+111514Y+136989X0180Y         S0      
317GND              VIA   -    MD0100PA00X+111514Y+138180X0180Y         S0      
317GND              VIA   -    MD0100PA00X+111514Y+137488X0180Y         S0      
317GND              VIA   -    MD0080PA00X+111367Y+138430X0160Y         S0      
317GND              VIA   -    MD0080PA00X+111367Y+137238X0160Y         S0      
317GND              VIA   -    MD0080PA00X+110931Y+136010X0160Y         S0      
317GND              VIA   -    MD0100PA00X+112009Y+136260X0180Y         S0      
317GND              VIA   -    MD0100PA00X+112009Y+135760X0180Y         S0      
317GND              VIA   -    MD0080PA00X+112155Y+136010X0160Y         S0      
317GND              VIA   -    MD0100PA00X+111514Y+136260X0180Y         S0      
317GND              VIA   -    MD0100PA00X+111514Y+135760X0180Y         S0      
317GND              VIA   -    MD0080PA00X+111367Y+136010X0160Y         S0      
317GND              VIA   -    MD0080PA00X+110931Y+134819X0160Y         S0      
317GND              VIA   -    MD0100PA00X+112009Y+135068X0180Y         S0      
317GND              VIA   -    MD0100PA00X+112009Y+134569X0180Y         S0      
317GND              VIA   -    MD0080PA00X+112155Y+134819X0160Y         S0      
317GND              VIA   -    MD0080PA00X+111367Y+134819X0160Y         S0      
317GND              VIA   -    MD0100PA00X+111514Y+135068X0180Y         S0      
317GND              VIA   -    MD0100PA00X+111514Y+134569X0180Y         S0      
317GND              VIA   -    MD0080PA00X+109707Y+140850X0160Y         S0      
317GND              VIA   -    MD0100PA00X+109561Y+141099X0180Y         S0      
317GND              VIA   -    MD0100PA00X+109561Y+140600X0180Y         S0      
317GND              VIA   -    MD0080PA00X+110143Y+140850X0160Y         S0      
317GND              VIA   -    MD0100PA00X+110290Y+141099X0180Y         S0      
317GND              VIA   -    MD0100PA00X+110290Y+140600X0180Y         S0      
317GND              VIA   -    MD0100PA00X+110785Y+141099X0180Y         S0      
317GND              VIA   -    MD0100PA00X+110785Y+140600X0180Y         S0      
317GND              VIA   -    MD0100PA00X+109561Y+138679X0180Y         S0      
317GND              VIA   -    MD0080PA00X+109707Y+139658X0160Y         S0      
317GND              VIA   -    MD0100PA00X+109561Y+139409X0180Y         S0      
317GND              VIA   -    MD0100PA00X+109561Y+139908X0180Y         S0      
317GND              VIA   -    MD0080PA00X+110143Y+139658X0160Y         S0      
317GND              VIA   -    MD0100PA00X+110290Y+139908X0180Y         S0      
317GND              VIA   -    MD0100PA00X+110290Y+139409X0180Y         S0      
317GND              VIA   -    MD0100PA00X+110290Y+138679X0180Y         S0      
317GND              VIA   -    MD0100PA00X+110785Y+139908X0180Y         S0      
317GND              VIA   -    MD0100PA00X+110785Y+139409X0180Y         S0      
317GND              VIA   -    MD0100PA00X+110785Y+138679X0180Y         S0      
317GND              VIA   -    MD0080PA00X+109707Y+138430X0160Y         S0      
317GND              VIA   -    MD0080PA00X+109707Y+137238X0160Y         S0      
317GND              VIA   -    MD0100PA00X+109561Y+136989X0180Y         S0      
317GND              VIA   -    MD0100PA00X+109561Y+137488X0180Y         S0      
317GND              VIA   -    MD0100PA00X+109561Y+138180X0180Y         S0      
317GND              VIA   -    MD0080PA00X+110143Y+137238X0160Y         S0      
317GND              VIA   -    MD0080PA00X+110143Y+138430X0160Y         S0      
317GND              VIA   -    MD0100PA00X+110290Y+138180X0180Y         S0      
317GND              VIA   -    MD0100PA00X+110290Y+136989X0180Y         S0      
317GND              VIA   -    MD0100PA00X+110290Y+137488X0180Y         S0      
317GND              VIA   -    MD0100PA00X+110785Y+138180X0180Y         S0      
317GND              VIA   -    MD0100PA00X+110785Y+137488X0180Y         S0      
317GND              VIA   -    MD0100PA00X+110785Y+136989X0180Y         S0      
317GND              VIA   -    MD0080PA00X+109707Y+136010X0160Y         S0      
317GND              VIA   -    MD0100PA00X+109561Y+136260X0180Y         S0      
317GND              VIA   -    MD0100PA00X+109561Y+135760X0180Y         S0      
317GND              VIA   -    MD0100PA00X+110785Y+136260X0180Y         S0      
317GND              VIA   -    MD0080PA00X+110143Y+136010X0160Y         S0      
317GND              VIA   -    MD0100PA00X+110290Y+135760X0180Y         S0      
317GND              VIA   -    MD0100PA00X+110290Y+136260X0180Y         S0      
317GND              VIA   -    MD0100PA00X+110785Y+135760X0180Y         S0      
317GND              VIA   -    MD0080PA00X+109707Y+134819X0160Y         S0      
317GND              VIA   -    MD0100PA00X+109561Y+134569X0180Y         S0      
317GND              VIA   -    MD0100PA00X+109561Y+135068X0180Y         S0      
317GND              VIA   -    MD0100PA00X+110785Y+135068X0180Y         S0      
317GND              VIA   -    MD0080PA00X+110143Y+134819X0160Y         S0      
317GND              VIA   -    MD0100PA00X+110290Y+134569X0180Y         S0      
317GND              VIA   -    MD0100PA00X+110290Y+135068X0180Y         S0      
317GND              VIA   -    MD0100PA00X+110785Y+134569X0180Y         S0      
317GND              VIA   -    MD0080PA00X+107695Y+140850X0160Y         S0      
317GND              VIA   -    MD0100PA00X+107842Y+141099X0180Y         S0      
317GND              VIA   -    MD0100PA00X+107842Y+140600X0180Y         S0      
317GND              VIA   -    MD0080PA00X+108483Y+140850X0160Y         S0      
317GND              VIA   -    MD0100PA00X+108337Y+141099X0180Y         S0      
317GND              VIA   -    MD0100PA00X+108337Y+140600X0180Y         S0      
317GND              VIA   -    MD0100PA00X+109066Y+141099X0180Y         S0      
317GND              VIA   -    MD0100PA00X+109066Y+140600X0180Y         S0      
317GND              VIA   -    MD0080PA00X+108919Y+140850X0160Y         S0      
317GND              VIA   -    MD0080PA00X+107695Y+139658X0160Y         S0      
317GND              VIA   -    MD0100PA00X+107842Y+139908X0180Y         S0      
317GND              VIA   -    MD0100PA00X+107842Y+139409X0180Y         S0      
317GND              VIA   -    MD0100PA00X+107842Y+138679X0180Y         S0      
317GND              VIA   -    MD0080PA00X+108483Y+139658X0160Y         S0      
317GND              VIA   -    MD0100PA00X+108337Y+139409X0180Y         S0      
317GND              VIA   -    MD0100PA00X+108337Y+139908X0180Y         S0      
317GND              VIA   -    MD0100PA00X+108337Y+138679X0180Y         S0      
317GND              VIA   -    MD0100PA00X+109066Y+138679X0180Y         S0      
317GND              VIA   -    MD0100PA00X+109066Y+139908X0180Y         S0      
317GND              VIA   -    MD0100PA00X+109066Y+139409X0180Y         S0      
317GND              VIA   -    MD0080PA00X+108919Y+139658X0160Y         S0      
317GND              VIA   -    MD0080PA00X+107695Y+137238X0160Y         S0      
317GND              VIA   -    MD0080PA00X+107695Y+138430X0160Y         S0      
317GND              VIA   -    MD0100PA00X+107842Y+138180X0180Y         S0      
317GND              VIA   -    MD0100PA00X+107842Y+137488X0180Y         S0      
317GND              VIA   -    MD0100PA00X+107842Y+136989X0180Y         S0      
317GND              VIA   -    MD0080PA00X+108483Y+137238X0160Y         S0      
317GND              VIA   -    MD0080PA00X+108483Y+138430X0160Y         S0      
317GND              VIA   -    MD0100PA00X+108337Y+138180X0180Y         S0      
317GND              VIA   -    MD0100PA00X+108337Y+137488X0180Y         S0      
317GND              VIA   -    MD0100PA00X+108337Y+136989X0180Y         S0      
317GND              VIA   -    MD0100PA00X+109066Y+136989X0180Y         S0      
317GND              VIA   -    MD0100PA00X+109066Y+137488X0180Y         S0      
317GND              VIA   -    MD0100PA00X+109066Y+138180X0180Y         S0      
317GND              VIA   -    MD0080PA00X+108919Y+137238X0160Y         S0      
317GND              VIA   -    MD0080PA00X+108919Y+138430X0160Y         S0      
317GND              VIA   -    MD0080PA00X+107695Y+136010X0160Y         S0      
317GND              VIA   -    MD0100PA00X+107842Y+135760X0180Y         S0      
317GND              VIA   -    MD0100PA00X+107842Y+136260X0180Y         S0      
317GND              VIA   -    MD0080PA00X+108483Y+136010X0160Y         S0      
317GND              VIA   -    MD0100PA00X+108337Y+136260X0180Y         S0      
317GND              VIA   -    MD0100PA00X+108337Y+135760X0180Y         S0      
317GND              VIA   -    MD0100PA00X+109066Y+136260X0180Y         S0      
317GND              VIA   -    MD0100PA00X+109066Y+135760X0180Y         S0      
317GND              VIA   -    MD0080PA00X+108919Y+136010X0160Y         S0      
317GND              VIA   -    MD0080PA00X+107695Y+134819X0160Y         S0      
317GND              VIA   -    MD0100PA00X+107842Y+135068X0180Y         S0      
317GND              VIA   -    MD0100PA00X+107842Y+134569X0180Y         S0      
317GND              VIA   -    MD0080PA00X+108483Y+134819X0160Y         S0      
317GND              VIA   -    MD0100PA00X+108337Y+135068X0180Y         S0      
317GND              VIA   -    MD0100PA00X+108337Y+134569X0180Y         S0      
317GND              VIA   -    MD0100PA00X+109066Y+134569X0180Y         S0      
317GND              VIA   -    MD0100PA00X+109066Y+135068X0180Y         S0      
317GND              VIA   -    MD0080PA00X+108919Y+134819X0160Y         S0      
317GND              VIA   -    MD0100PA00X+107113Y+141099X0180Y         S0      
317GND              VIA   -    MD0100PA00X+107113Y+140600X0180Y         S0      
317GND              VIA   -    MD0080PA00X+107259Y+140850X0160Y         S0      
317GND              VIA   -    MD0100PA00X+106618Y+141099X0180Y         S0      
317GND              VIA   -    MD0100PA00X+106618Y+140600X0180Y         S0      
317GND              VIA   -    MD0100PA00X+107113Y+138679X0180Y         S0      
317GND              VIA   -    MD0100PA00X+107113Y+139399X0180Y         S0      
317GND              VIA   -    MD0100PA00X+107113Y+139908X0180Y         S0      
317GND              VIA   -    MD0080PA00X+107259Y+139658X0160Y         S0      
317GND              VIA   -    MD0100PA00X+106618Y+138679X0180Y         S0      
317GND              VIA   -    MD0100PA00X+106618Y+139908X0180Y         S0      
317GND              VIA   -    MD0100PA00X+106618Y+139399X0180Y         S0      
317GND              VIA   -    MD0100PA00X+107113Y+137488X0180Y         S0      
317GND              VIA   -    MD0100PA00X+107113Y+136980X0180Y         S0      
317GND              VIA   -    MD0100PA00X+107113Y+138180X0180Y         S0      
317GND              VIA   -    MD0080PA00X+107259Y+137238X0160Y         S0      
317GND              VIA   -    MD0080PA00X+107259Y+138430X0160Y         S0      
317GND              VIA   -    MD0100PA00X+106618Y+137488X0180Y         S0      
317GND              VIA   -    MD0100PA00X+106618Y+136980X0180Y         S0      
317GND              VIA   -    MD0100PA00X+106618Y+138180X0180Y         S0      
317GND              VIA   -    MD0080PA00X+107259Y+136010X0160Y         S0      
317GND              VIA   -    MD0100PA00X+107113Y+136260X0180Y         S0      
317GND              VIA   -    MD0100PA00X+107113Y+135760X0180Y         S0      
317GND              VIA   -    MD0100PA00X+106618Y+136260X0180Y         S0      
317GND              VIA   -    MD0100PA00X+106618Y+135760X0180Y         S0      
317GND              VIA   -    MD0080PA00X+107259Y+134819X0160Y         S0      
317GND              VIA   -    MD0100PA00X+107113Y+134569X0180Y         S0      
317GND              VIA   -    MD0100PA00X+107113Y+135068X0180Y         S0      
317GND              VIA   -    MD0100PA00X+106618Y+134569X0180Y         S0      
317GND              VIA   -    MD0100PA00X+106618Y+135068X0180Y         S0      
317GND              VIA   -    MD0100PA00X+135690Y+140600X0180Y         S0      
317GND              VIA   -    MD0100PA00X+135690Y+141099X0180Y         S0      
317GND              VIA   -    MD0080PA00X+135837Y+140850X0160Y         S0      
317GND              VIA   -    MD0100PA00X+135690Y+139908X0180Y         S0      
317GND              VIA   -    MD0100PA00X+135690Y+139409X0180Y         S0      
317GND              VIA   -    MD0100PA00X+135690Y+138679X0180Y         S0      
317GND              VIA   -    MD0080PA00X+135837Y+139658X0160Y         S0      
317GND              VIA   -    MD0100PA00X+135690Y+136989X0180Y         S0      
317GND              VIA   -    MD0100PA00X+135690Y+138180X0180Y         S0      
317GND              VIA   -    MD0080PA00X+135837Y+138430X0160Y         S0      
317GND              VIA   -    MD0080PA00X+135837Y+137238X0160Y         S0      
317GND              VIA   -    MD0100PA00X+135690Y+136260X0180Y         S0      
317GND              VIA   -    MD0100PA00X+135690Y+135760X0180Y         S0      
317GND              VIA   -    MD0080PA00X+135837Y+136010X0160Y         S0      
317GND              VIA   -    MD0100PA00X+135690Y+135068X0180Y         S0      
317GND              VIA   -    MD0100PA00X+135690Y+134569X0180Y         S0      
317GND              VIA   -    MD0080PA00X+135837Y+134819X0160Y         S0      
317GND              VIA   -    MD0080PA00X+134613Y+140850X0160Y         S0      
317GND              VIA   -    MD0100PA00X+134466Y+140600X0180Y         S0      
317GND              VIA   -    MD0100PA00X+134466Y+141099X0180Y         S0      
317GND              VIA   -    MD0080PA00X+133825Y+140850X0160Y         S0      
317GND              VIA   -    MD0100PA00X+133971Y+140600X0180Y         S0      
317GND              VIA   -    MD0100PA00X+133971Y+141099X0180Y         S0      
317GND              VIA   -    MD0100PA00X+135195Y+140600X0180Y         S0      
317GND              VIA   -    MD0100PA00X+135195Y+141099X0180Y         S0      
317GND              VIA   -    MD0080PA00X+135049Y+140850X0160Y         S0      
317GND              VIA   -    MD0080PA00X+134613Y+139658X0160Y         S0      
317GND              VIA   -    MD0100PA00X+134466Y+138679X0180Y         S0      
317GND              VIA   -    MD0100PA00X+134466Y+139908X0180Y         S0      
317GND              VIA   -    MD0100PA00X+134466Y+139399X0180Y         S0      
317GND              VIA   -    MD0080PA00X+133825Y+139658X0160Y         S0      
317GND              VIA   -    MD0100PA00X+133971Y+138679X0180Y         S0      
317GND              VIA   -    MD0100PA00X+133971Y+139399X0180Y         S0      
317GND              VIA   -    MD0100PA00X+133971Y+139908X0180Y         S0      
317GND              VIA   -    MD0100PA00X+135195Y+139908X0180Y         S0      
317GND              VIA   -    MD0100PA00X+135195Y+139409X0180Y         S0      
317GND              VIA   -    MD0100PA00X+135195Y+138679X0180Y         S0      
317GND              VIA   -    MD0080PA00X+135049Y+139658X0160Y         S0      
317GND              VIA   -    MD0080PA00X+134613Y+137238X0160Y         S0      
317GND              VIA   -    MD0080PA00X+134613Y+138430X0160Y         S0      
317GND              VIA   -    MD0100PA00X+134466Y+138180X0180Y         S0      
317GND              VIA   -    MD0100PA00X+134466Y+137488X0180Y         S0      
317GND              VIA   -    MD0100PA00X+134466Y+136989X0180Y         S0      
317GND              VIA   -    MD0080PA00X+133825Y+137238X0160Y         S0      
317GND              VIA   -    MD0080PA00X+133825Y+138430X0160Y         S0      
317GND              VIA   -    MD0100PA00X+133971Y+136989X0180Y         S0      
317GND              VIA   -    MD0100PA00X+133971Y+138180X0180Y         S0      
317GND              VIA   -    MD0100PA00X+133971Y+137488X0180Y         S0      
317GND              VIA   -    MD0100PA00X+135195Y+136989X0180Y         S0      
317GND              VIA   -    MD0100PA00X+135195Y+138180X0180Y         S0      
317GND              VIA   -    MD0100PA00X+135195Y+137488X0180Y         S0      
317GND              VIA   -    MD0080PA00X+135049Y+138430X0160Y         S0      
317GND              VIA   -    MD0080PA00X+135049Y+137238X0160Y         S0      
317GND              VIA   -    MD0080PA00X+134613Y+136010X0160Y         S0      
317GND              VIA   -    MD0100PA00X+134466Y+135760X0180Y         S0      
317GND              VIA   -    MD0100PA00X+134466Y+136260X0180Y         S0      
317GND              VIA   -    MD0080PA00X+133825Y+136010X0160Y         S0      
317GND              VIA   -    MD0100PA00X+133971Y+135760X0180Y         S0      
317GND              VIA   -    MD0100PA00X+133971Y+136260X0180Y         S0      
317GND              VIA   -    MD0100PA00X+135195Y+136260X0180Y         S0      
317GND              VIA   -    MD0100PA00X+135195Y+135760X0180Y         S0      
317GND              VIA   -    MD0080PA00X+135049Y+136010X0160Y         S0      
317GND              VIA   -    MD0080PA00X+134613Y+134819X0160Y         S0      
317GND              VIA   -    MD0100PA00X+134466Y+135068X0180Y         S0      
317GND              VIA   -    MD0100PA00X+134466Y+134560X0180Y         S0      
317GND              VIA   -    MD0080PA00X+133825Y+134819X0160Y         S0      
317GND              VIA   -    MD0100PA00X+133971Y+135068X0180Y         S0      
317GND              VIA   -    MD0100PA00X+133971Y+134560X0180Y         S0      
317GND              VIA   -    MD0100PA00X+135195Y+134569X0180Y         S0      
317GND              VIA   -    MD0100PA00X+135195Y+135068X0180Y         S0      
317GND              VIA   -    MD0080PA00X+135049Y+134819X0160Y         S0      
317GND              VIA   -    MD0080PA00X+132165Y+140850X0160Y         S0      
317GND              VIA   -    MD0100PA00X+132018Y+140600X0180Y         S0      
317GND              VIA   -    MD0100PA00X+132018Y+141099X0180Y         S0      
317GND              VIA   -    MD0100PA00X+132747Y+140600X0180Y         S0      
317GND              VIA   -    MD0100PA00X+132747Y+141099X0180Y         S0      
317GND              VIA   -    MD0080PA00X+132601Y+140850X0160Y         S0      
317GND              VIA   -    MD0100PA00X+133242Y+140600X0180Y         S0      
317GND              VIA   -    MD0100PA00X+133242Y+141099X0180Y         S0      
317GND              VIA   -    MD0080PA00X+133389Y+140850X0160Y         S0      
317GND              VIA   -    MD0080PA00X+132165Y+139658X0160Y         S0      
317GND              VIA   -    MD0100PA00X+132018Y+138679X0180Y         S0      
317GND              VIA   -    MD0100PA00X+132018Y+139409X0180Y         S0      
317GND              VIA   -    MD0100PA00X+132018Y+139908X0180Y         S0      
317GND              VIA   -    MD0100PA00X+132747Y+139908X0180Y         S0      
317GND              VIA   -    MD0100PA00X+132747Y+139409X0180Y         S0      
317GND              VIA   -    MD0100PA00X+132747Y+138679X0180Y         S0      
317GND              VIA   -    MD0080PA00X+132601Y+139658X0160Y         S0      
317GND              VIA   -    MD0100PA00X+133242Y+139908X0180Y         S0      
317GND              VIA   -    MD0100PA00X+133242Y+139409X0180Y         S0      
317GND              VIA   -    MD0100PA00X+133242Y+138679X0180Y         S0      
317GND              VIA   -    MD0080PA00X+133389Y+139658X0160Y         S0      
317GND              VIA   -    MD0080PA00X+132165Y+137238X0160Y         S0      
317GND              VIA   -    MD0080PA00X+132165Y+138430X0160Y         S0      
317GND              VIA   -    MD0100PA00X+132018Y+136989X0180Y         S0      
317GND              VIA   -    MD0100PA00X+132018Y+137488X0180Y         S0      
317GND              VIA   -    MD0100PA00X+132018Y+138180X0180Y         S0      
317GND              VIA   -    MD0080PA00X+132601Y+138430X0160Y         S0      
317GND              VIA   -    MD0080PA00X+132601Y+137238X0160Y         S0      
317GND              VIA   -    MD0100PA00X+132747Y+137488X0180Y         S0      
317GND              VIA   -    MD0100PA00X+132747Y+136989X0180Y         S0      
317GND              VIA   -    MD0100PA00X+132747Y+138180X0180Y         S0      
317GND              VIA   -    MD0100PA00X+133242Y+137488X0180Y         S0      
317GND              VIA   -    MD0100PA00X+133242Y+136989X0180Y         S0      
317GND              VIA   -    MD0100PA00X+133242Y+138180X0180Y         S0      
317GND              VIA   -    MD0080PA00X+133389Y+138430X0160Y         S0      
317GND              VIA   -    MD0080PA00X+133389Y+137238X0160Y         S0      
317GND              VIA   -    MD0080PA00X+132165Y+136010X0160Y         S0      
317GND              VIA   -    MD0100PA00X+132018Y+135760X0180Y         S0      
317GND              VIA   -    MD0100PA00X+132018Y+136260X0180Y         S0      
317GND              VIA   -    MD0100PA00X+132747Y+136260X0180Y         S0      
317GND              VIA   -    MD0100PA00X+132747Y+135760X0180Y         S0      
317GND              VIA   -    MD0080PA00X+132601Y+136010X0160Y         S0      
317GND              VIA   -    MD0100PA00X+133242Y+135760X0180Y         S0      
317GND              VIA   -    MD0100PA00X+133242Y+136260X0180Y         S0      
317GND              VIA   -    MD0080PA00X+133389Y+136010X0160Y         S0      
317GND              VIA   -    MD0080PA00X+132165Y+134819X0160Y         S0      
317GND              VIA   -    MD0100PA00X+132018Y+134569X0180Y         S0      
317GND              VIA   -    MD0100PA00X+132018Y+135068X0180Y         S0      
317GND              VIA   -    MD0100PA00X+132747Y+134569X0180Y         S0      
317GND              VIA   -    MD0100PA00X+132747Y+135068X0180Y         S0      
317GND              VIA   -    MD0080PA00X+132601Y+134819X0160Y         S0      
317GND              VIA   -    MD0100PA00X+133242Y+135068X0180Y         S0      
317GND              VIA   -    MD0100PA00X+133242Y+134569X0180Y         S0      
317GND              VIA   -    MD0080PA00X+133389Y+134819X0160Y         S0      
317GND              VIA   -    MD0100PA00X+130794Y+140600X0180Y         S0      
317GND              VIA   -    MD0100PA00X+130794Y+141099X0180Y         S0      
317GND              VIA   -    MD0080PA00X+130941Y+140850X0160Y         S0      
317GND              VIA   -    MD0080PA00X+131377Y+140850X0160Y         S0      
317GND              VIA   -    MD0100PA00X+131523Y+140600X0180Y         S0      
317GND              VIA   -    MD0100PA00X+131523Y+141099X0180Y         S0      
317GND              VIA   -    MD0100PA00X+130794Y+139409X0180Y         S0      
317GND              VIA   -    MD0100PA00X+130794Y+139908X0180Y         S0      
317GND              VIA   -    MD0100PA00X+130794Y+138679X0180Y         S0      
317GND              VIA   -    MD0080PA00X+130941Y+139658X0160Y         S0      
317GND              VIA   -    MD0080PA00X+131377Y+139658X0160Y         S0      
317GND              VIA   -    MD0100PA00X+131523Y+138679X0180Y         S0      
317GND              VIA   -    MD0100PA00X+131523Y+139409X0180Y         S0      
317GND              VIA   -    MD0100PA00X+131523Y+139908X0180Y         S0      
317GND              VIA   -    MD0100PA00X+130794Y+136989X0180Y         S0      
317GND              VIA   -    MD0100PA00X+130794Y+138180X0180Y         S0      
317GND              VIA   -    MD0100PA00X+130794Y+137488X0180Y         S0      
317GND              VIA   -    MD0080PA00X+130941Y+138430X0160Y         S0      
317GND              VIA   -    MD0080PA00X+130941Y+137238X0160Y         S0      
317GND              VIA   -    MD0100PA00X+131523Y+137488X0180Y         S0      
317GND              VIA   -    MD0080PA00X+131377Y+138430X0160Y         S0      
317GND              VIA   -    MD0080PA00X+131377Y+137238X0160Y         S0      
317GND              VIA   -    MD0100PA00X+131523Y+136989X0180Y         S0      
317GND              VIA   -    MD0100PA00X+131523Y+138180X0180Y         S0      
317GND              VIA   -    MD0100PA00X+130794Y+136260X0180Y         S0      
317GND              VIA   -    MD0100PA00X+130794Y+135760X0180Y         S0      
317GND              VIA   -    MD0080PA00X+130941Y+136010X0160Y         S0      
317GND              VIA   -    MD0080PA00X+131377Y+136010X0160Y         S0      
317GND              VIA   -    MD0100PA00X+131523Y+135760X0180Y         S0      
317GND              VIA   -    MD0100PA00X+131523Y+136260X0180Y         S0      
317GND              VIA   -    MD0100PA00X+130794Y+134569X0180Y         S0      
317GND              VIA   -    MD0100PA00X+130794Y+135068X0180Y         S0      
317GND              VIA   -    MD0080PA00X+130941Y+134819X0160Y         S0      
317GND              VIA   -    MD0080PA00X+131377Y+134819X0160Y         S0      
317GND              VIA   -    MD0100PA00X+131523Y+135068X0180Y         S0      
317GND              VIA   -    MD0100PA00X+131523Y+134569X0180Y         S0      
317GND              VIA   -    MD0080PA00X+129717Y+140850X0160Y         S0      
317GND              VIA   -    MD0100PA00X+129570Y+140600X0180Y         S0      
317GND              VIA   -    MD0100PA00X+129570Y+141099X0180Y         S0      
317GND              VIA   -    MD0080PA00X+128929Y+140850X0160Y         S0      
317GND              VIA   -    MD0100PA00X+129075Y+140600X0180Y         S0      
317GND              VIA   -    MD0100PA00X+129075Y+141099X0180Y         S0      
317GND              VIA   -    MD0100PA00X+130299Y+140600X0180Y         S0      
317GND              VIA   -    MD0100PA00X+130299Y+141099X0180Y         S0      
317GND              VIA   -    MD0080PA00X+130153Y+140850X0160Y         S0      
317GND              VIA   -    MD0080PA00X+129717Y+139658X0160Y         S0      
317GND              VIA   -    MD0100PA00X+129570Y+138679X0180Y         S0      
317GND              VIA   -    MD0100PA00X+129570Y+139908X0180Y         S0      
317GND              VIA   -    MD0100PA00X+129570Y+139409X0180Y         S0      
317GND              VIA   -    MD0080PA00X+128929Y+139658X0160Y         S0      
317GND              VIA   -    MD0100PA00X+129075Y+138679X0180Y         S0      
317GND              VIA   -    MD0100PA00X+129075Y+139409X0180Y         S0      
317GND              VIA   -    MD0100PA00X+129075Y+139908X0180Y         S0      
317GND              VIA   -    MD0100PA00X+130299Y+139409X0180Y         S0      
317GND              VIA   -    MD0100PA00X+130299Y+139908X0180Y         S0      
317GND              VIA   -    MD0100PA00X+130299Y+138679X0180Y         S0      
317GND              VIA   -    MD0080PA00X+130153Y+139658X0160Y         S0      
317GND              VIA   -    MD0080PA00X+129717Y+137238X0160Y         S0      
317GND              VIA   -    MD0080PA00X+129717Y+138430X0160Y         S0      
317GND              VIA   -    MD0100PA00X+129570Y+136989X0180Y         S0      
317GND              VIA   -    MD0100PA00X+129570Y+137488X0180Y         S0      
317GND              VIA   -    MD0100PA00X+129570Y+138180X0180Y         S0      
317GND              VIA   -    MD0080PA00X+128929Y+137238X0160Y         S0      
317GND              VIA   -    MD0080PA00X+128929Y+138430X0160Y         S0      
317GND              VIA   -    MD0100PA00X+129075Y+137488X0180Y         S0      
317GND              VIA   -    MD0100PA00X+129075Y+138180X0180Y         S0      
317GND              VIA   -    MD0100PA00X+129075Y+136989X0180Y         S0      
317GND              VIA   -    MD0100PA00X+130299Y+136989X0180Y         S0      
317GND              VIA   -    MD0100PA00X+130299Y+138180X0180Y         S0      
317GND              VIA   -    MD0100PA00X+130299Y+137488X0180Y         S0      
317GND              VIA   -    MD0080PA00X+130153Y+138430X0160Y         S0      
317GND              VIA   -    MD0080PA00X+130153Y+137238X0160Y         S0      
317GND              VIA   -    MD0080PA00X+129717Y+136010X0160Y         S0      
317GND              VIA   -    MD0100PA00X+129570Y+135760X0180Y         S0      
317GND              VIA   -    MD0100PA00X+129570Y+136260X0180Y         S0      
317GND              VIA   -    MD0080PA00X+128929Y+136010X0160Y         S0      
317GND              VIA   -    MD0100PA00X+129075Y+135760X0180Y         S0      
317GND              VIA   -    MD0100PA00X+129075Y+136260X0180Y         S0      
317GND              VIA   -    MD0080PA00X+130153Y+136010X0160Y         S0      
317GND              VIA   -    MD0100PA00X+130299Y+135760X0180Y         S0      
317GND              VIA   -    MD0100PA00X+130299Y+136260X0180Y         S0      
317GND              VIA   -    MD0080PA00X+129717Y+134819X0160Y         S0      
317GND              VIA   -    MD0100PA00X+129570Y+134569X0180Y         S0      
317GND              VIA   -    MD0100PA00X+129570Y+135068X0180Y         S0      
317GND              VIA   -    MD0100PA00X+129075Y+134569X0180Y         S0      
317GND              VIA   -    MD0100PA00X+129075Y+135068X0180Y         S0      
317GND              VIA   -    MD0080PA00X+128929Y+134819X0160Y         S0      
317GND              VIA   -    MD0100PA00X+130299Y+135068X0180Y         S0      
317GND              VIA   -    MD0100PA00X+130299Y+134569X0180Y         S0      
317GND              VIA   -    MD0080PA00X+130153Y+134819X0160Y         S0      
317GND              VIA   -    MD0080PA00X+127269Y+140850X0160Y         S0      
317GND              VIA   -    MD0100PA00X+127122Y+140600X0180Y         S0      
317GND              VIA   -    MD0100PA00X+127122Y+141099X0180Y         S0      
317GND              VIA   -    MD0100PA00X+127851Y+140600X0180Y         S0      
317GND              VIA   -    MD0100PA00X+127851Y+141099X0180Y         S0      
317GND              VIA   -    MD0080PA00X+127705Y+140850X0160Y         S0      
317GND              VIA   -    MD0100PA00X+128346Y+140600X0180Y         S0      
317GND              VIA   -    MD0100PA00X+128346Y+141099X0180Y         S0      
317GND              VIA   -    MD0080PA00X+128493Y+140850X0160Y         S0      
317GND              VIA   -    MD0080PA00X+127269Y+139658X0160Y         S0      
317GND              VIA   -    MD0100PA00X+127122Y+138679X0180Y         S0      
317GND              VIA   -    MD0100PA00X+127122Y+139908X0180Y         S0      
317GND              VIA   -    MD0100PA00X+127122Y+139409X0180Y         S0      
317GND              VIA   -    MD0100PA00X+127851Y+139409X0180Y         S0      
317GND              VIA   -    MD0100PA00X+127851Y+139908X0180Y         S0      
317GND              VIA   -    MD0100PA00X+127851Y+138679X0180Y         S0      
317GND              VIA   -    MD0080PA00X+127705Y+139658X0160Y         S0      
317GND              VIA   -    MD0100PA00X+128346Y+139409X0180Y         S0      
317GND              VIA   -    MD0100PA00X+128346Y+139908X0180Y         S0      
317GND              VIA   -    MD0100PA00X+128346Y+138679X0180Y         S0      
317GND              VIA   -    MD0080PA00X+128493Y+139658X0160Y         S0      
317GND              VIA   -    MD0080PA00X+127269Y+137238X0160Y         S0      
317GND              VIA   -    MD0080PA00X+127269Y+138430X0160Y         S0      
317GND              VIA   -    MD0100PA00X+127122Y+138180X0180Y         S0      
317GND              VIA   -    MD0100PA00X+127122Y+137488X0180Y         S0      
317GND              VIA   -    MD0100PA00X+127122Y+136989X0180Y         S0      
317GND              VIA   -    MD0100PA00X+127851Y+137488X0180Y         S0      
317GND              VIA   -    MD0100PA00X+127851Y+136989X0180Y         S0      
317GND              VIA   -    MD0100PA00X+127851Y+138180X0180Y         S0      
317GND              VIA   -    MD0080PA00X+127705Y+138430X0160Y         S0      
317GND              VIA   -    MD0080PA00X+127705Y+137238X0160Y         S0      
317GND              VIA   -    MD0100PA00X+128346Y+137488X0180Y         S0      
317GND              VIA   -    MD0100PA00X+128346Y+136989X0180Y         S0      
317GND              VIA   -    MD0100PA00X+128346Y+138180X0180Y         S0      
317GND              VIA   -    MD0080PA00X+128493Y+138430X0160Y         S0      
317GND              VIA   -    MD0080PA00X+128493Y+137238X0160Y         S0      
317GND              VIA   -    MD0080PA00X+127269Y+136010X0160Y         S0      
317GND              VIA   -    MD0100PA00X+127122Y+135760X0180Y         S0      
317GND              VIA   -    MD0100PA00X+127122Y+136260X0180Y         S0      
317GND              VIA   -    MD0100PA00X+127851Y+136260X0180Y         S0      
317GND              VIA   -    MD0100PA00X+127851Y+135760X0180Y         S0      
317GND              VIA   -    MD0080PA00X+127705Y+136010X0160Y         S0      
317GND              VIA   -    MD0100PA00X+128346Y+135760X0180Y         S0      
317GND              VIA   -    MD0100PA00X+128346Y+136260X0180Y         S0      
317GND              VIA   -    MD0080PA00X+128493Y+136010X0160Y         S0      
317GND              VIA   -    MD0080PA00X+127269Y+134819X0160Y         S0      
317GND              VIA   -    MD0100PA00X+127122Y+135068X0180Y         S0      
317GND              VIA   -    MD0100PA00X+127122Y+134569X0180Y         S0      
317GND              VIA   -    MD0100PA00X+127851Y+135068X0180Y         S0      
317GND              VIA   -    MD0100PA00X+127851Y+134569X0180Y         S0      
317GND              VIA   -    MD0080PA00X+127705Y+134819X0160Y         S0      
317GND              VIA   -    MD0080PA00X+128493Y+134819X0160Y         S0      
317GND              VIA   -    MD0100PA00X+128346Y+135068X0180Y         S0      
317GND              VIA   -    MD0100PA00X+128346Y+134569X0180Y         S0      
317GND              VIA   -    MD0100PA00X+125898Y+141099X0180Y         S0      
317GND              VIA   -    MD0100PA00X+125898Y+140600X0180Y         S0      
317GND              VIA   -    MD0080PA00X+126045Y+140850X0160Y         S0      
317GND              VIA   -    MD0080PA00X+126481Y+140850X0160Y         S0      
317GND              VIA   -    MD0100PA00X+126627Y+140600X0180Y         S0      
317GND              VIA   -    MD0100PA00X+126627Y+141099X0180Y         S0      
317GND              VIA   -    MD0100PA00X+125898Y+139908X0180Y         S0      
317GND              VIA   -    MD0100PA00X+125898Y+138679X0180Y         S0      
317GND              VIA   -    MD0100PA00X+125898Y+139409X0180Y         S0      
317GND              VIA   -    MD0080PA00X+126045Y+139658X0160Y         S0      
317GND              VIA   -    MD0080PA00X+126481Y+139658X0160Y         S0      
317GND              VIA   -    MD0100PA00X+126627Y+138679X0180Y         S0      
317GND              VIA   -    MD0100PA00X+126627Y+139409X0180Y         S0      
317GND              VIA   -    MD0100PA00X+126627Y+139908X0180Y         S0      
317GND              VIA   -    MD0100PA00X+125898Y+137488X0180Y         S0      
317GND              VIA   -    MD0100PA00X+125898Y+136989X0180Y         S0      
317GND              VIA   -    MD0100PA00X+125898Y+138180X0180Y         S0      
317GND              VIA   -    MD0080PA00X+126045Y+138430X0160Y         S0      
317GND              VIA   -    MD0080PA00X+126045Y+137238X0160Y         S0      
317GND              VIA   -    MD0080PA00X+126481Y+138430X0160Y         S0      
317GND              VIA   -    MD0080PA00X+126481Y+137238X0160Y         S0      
317GND              VIA   -    MD0100PA00X+126627Y+138180X0180Y         S0      
317GND              VIA   -    MD0100PA00X+126627Y+137488X0180Y         S0      
317GND              VIA   -    MD0100PA00X+126627Y+136989X0180Y         S0      
317GND              VIA   -    MD0100PA00X+125898Y+135760X0180Y         S0      
317GND              VIA   -    MD0100PA00X+125898Y+136260X0180Y         S0      
317GND              VIA   -    MD0080PA00X+126045Y+136010X0160Y         S0      
317GND              VIA   -    MD0080PA00X+126481Y+136010X0160Y         S0      
317GND              VIA   -    MD0100PA00X+126627Y+135760X0180Y         S0      
317GND              VIA   -    MD0100PA00X+126627Y+136260X0180Y         S0      
317GND              VIA   -    MD0100PA00X+125898Y+134569X0180Y         S0      
317GND              VIA   -    MD0100PA00X+125898Y+135068X0180Y         S0      
317GND              VIA   -    MD0080PA00X+126045Y+134819X0160Y         S0      
317GND              VIA   -    MD0080PA00X+126481Y+134819X0160Y         S0      
317GND              VIA   -    MD0100PA00X+126627Y+135068X0180Y         S0      
317GND              VIA   -    MD0100PA00X+126627Y+134569X0180Y         S0      
317GND              VIA   -    MD0080PA00X+124821Y+140850X0160Y         S0      
317GND              VIA   -    MD0100PA00X+124674Y+140600X0180Y         S0      
317GND              VIA   -    MD0100PA00X+124674Y+141099X0180Y         S0      
317GND              VIA   -    MD0080PA00X+124033Y+140850X0160Y         S0      
317GND              VIA   -    MD0100PA00X+124179Y+140600X0180Y         S0      
317GND              VIA   -    MD0100PA00X+124179Y+141099X0180Y         S0      
317GND              VIA   -    MD0100PA00X+125403Y+140600X0180Y         S0      
317GND              VIA   -    MD0100PA00X+125403Y+141099X0180Y         S0      
317GND              VIA   -    MD0080PA00X+125257Y+140850X0160Y         S0      
317GND              VIA   -    MD0100PA00X+124674Y+138679X0180Y         S0      
317GND              VIA   -    MD0080PA00X+124821Y+139658X0160Y         S0      
317GND              VIA   -    MD0100PA00X+124674Y+139908X0180Y         S0      
317GND              VIA   -    MD0100PA00X+124674Y+139399X0180Y         S0      
317GND              VIA   -    MD0080PA00X+124033Y+139658X0160Y         S0      
317GND              VIA   -    MD0100PA00X+124179Y+138679X0180Y         S0      
317GND              VIA   -    MD0100PA00X+124179Y+139399X0180Y         S0      
317GND              VIA   -    MD0100PA00X+124179Y+139908X0180Y         S0      
317GND              VIA   -    MD0100PA00X+125403Y+139409X0180Y         S0      
317GND              VIA   -    MD0100PA00X+125403Y+139908X0180Y         S0      
317GND              VIA   -    MD0100PA00X+125403Y+138679X0180Y         S0      
317GND              VIA   -    MD0080PA00X+125257Y+139658X0160Y         S0      
317GND              VIA   -    MD0080PA00X+124821Y+138430X0160Y         S0      
317GND              VIA   -    MD0080PA00X+124821Y+137238X0160Y         S0      
317GND              VIA   -    MD0100PA00X+124674Y+138180X0180Y         S0      
317GND              VIA   -    MD0100PA00X+124674Y+136980X0180Y         S0      
317GND              VIA   -    MD0100PA00X+124674Y+137488X0180Y         S0      
317GND              VIA   -    MD0080PA00X+124033Y+137238X0160Y         S0      
317GND              VIA   -    MD0080PA00X+124033Y+138430X0160Y         S0      
317GND              VIA   -    MD0100PA00X+124179Y+138180X0180Y         S0      
317GND              VIA   -    MD0100PA00X+124179Y+136980X0180Y         S0      
317GND              VIA   -    MD0100PA00X+124179Y+137488X0180Y         S0      
317GND              VIA   -    MD0100PA00X+125403Y+136989X0180Y         S0      
317GND              VIA   -    MD0100PA00X+125403Y+137488X0180Y         S0      
317GND              VIA   -    MD0100PA00X+125403Y+138180X0180Y         S0      
317GND              VIA   -    MD0080PA00X+125257Y+138430X0160Y         S0      
317GND              VIA   -    MD0080PA00X+125257Y+137238X0160Y         S0      
317GND              VIA   -    MD0100PA00X+124674Y+135760X0180Y         S0      
317GND              VIA   -    MD0100PA00X+124674Y+136260X0180Y         S0      
317GND              VIA   -    MD0080PA00X+124821Y+136010X0160Y         S0      
317GND              VIA   -    MD0080PA00X+124033Y+136010X0160Y         S0      
317GND              VIA   -    MD0100PA00X+124179Y+135760X0180Y         S0      
317GND              VIA   -    MD0100PA00X+124179Y+136260X0180Y         S0      
317GND              VIA   -    MD0100PA00X+125403Y+136260X0180Y         S0      
317GND              VIA   -    MD0100PA00X+125403Y+135760X0180Y         S0      
317GND              VIA   -    MD0080PA00X+125257Y+136010X0160Y         S0      
317GND              VIA   -    MD0100PA00X+124674Y+135068X0180Y         S0      
317GND              VIA   -    MD0100PA00X+124674Y+134569X0180Y         S0      
317GND              VIA   -    MD0080PA00X+124821Y+134819X0160Y         S0      
317GND              VIA   -    MD0080PA00X+124033Y+134819X0160Y         S0      
317GND              VIA   -    MD0100PA00X+124179Y+135068X0180Y         S0      
317GND              VIA   -    MD0100PA00X+124179Y+134569X0180Y         S0      
317GND              VIA   -    MD0100PA00X+125403Y+134569X0180Y         S0      
317GND              VIA   -    MD0100PA00X+125403Y+135068X0180Y         S0      
317GND              VIA   -    MD0080PA00X+125257Y+134819X0160Y         S0      
317GND              VIA   -    MD0100PA00X+123450Y+138679X0180Y         S0      
317GND              VIA   -    MD0100PA00X+122955Y+138679X0180Y         S0      
317GND              VIA   -    MD0100PA00X+123450Y+138180X0180Y         S0      
317GND              VIA   -    MD0100PA00X+123450Y+137488X0180Y         S0      
317GND              VIA   -    MD0100PA00X+123450Y+136989X0180Y         S0      
317GND              VIA   -    MD0100PA00X+122955Y+138180X0180Y         S0      
317GND              VIA   -    MD0100PA00X+122955Y+137488X0180Y         S0      
317GND              VIA   -    MD0100PA00X+122955Y+136989X0180Y         S0      
317GND              VIA   -    MD0080PA00X+122809Y+138430X0160Y         S0      
317GND              VIA   -    MD0080PA00X+122809Y+137238X0160Y         S0      
317GND              VIA   -    MD0080PA00X+123597Y+138430X0160Y         S0      
317GND              VIA   -    MD0080PA00X+123597Y+137238X0160Y         S0      
317GND              VIA   -    MD0100PA00X+123450Y+136260X0180Y         S0      
317GND              VIA   -    MD0100PA00X+123450Y+135760X0180Y         S0      
317GND              VIA   -    MD0100PA00X+122955Y+135760X0180Y         S0      
317GND              VIA   -    MD0100PA00X+122955Y+136260X0180Y         S0      
317GND              VIA   -    MD0080PA00X+122809Y+136010X0160Y         S0      
317GND              VIA   -    MD0080PA00X+123597Y+136010X0160Y         S0      
317GND              VIA   -    MD0100PA00X+123450Y+135068X0180Y         S0      
317GND              VIA   -    MD0100PA00X+123450Y+134569X0180Y         S0      
317GND              VIA   -    MD0100PA00X+122955Y+134569X0180Y         S0      
317GND              VIA   -    MD0100PA00X+122955Y+135068X0180Y         S0      
317GND              VIA   -    MD0080PA00X+122809Y+134819X0160Y         S0      
317GND              VIA   -    MD0080PA00X+123597Y+134819X0160Y         S0      
317GND              VIA   -    MD0080PA00X+173944Y+138430X0160Y         S0      
317GND              VIA   -    MD0100PA00X+173798Y+138180X0180Y         S0      
317GND              VIA   -    MD0080PA00X+172720Y+138430X0160Y         S0      
317GND              VIA   -    MD0080PA00X+172720Y+137238X0160Y         S0      
317GND              VIA   -    MD0080PA00X+173156Y+139658X0160Y         S0      
317GND              VIA   -    MD0100PA00X+173302Y+138679X0180Y         S0      
317GND              VIA   -    MD0100PA00X+173302Y+139409X0180Y         S0      
317GND              VIA   -    MD0100PA00X+173302Y+139908X0180Y         S0      
317GND              VIA   -    MD0080PA00X+173944Y+139658X0160Y         S0      
317GND              VIA   -    MD0100PA00X+173798Y+138679X0180Y         S0      
317GND              VIA   -    MD0100PA00X+173798Y+139409X0180Y         S0      
317GND              VIA   -    MD0100PA00X+173798Y+139908X0180Y         S0      
317GND              VIA   -    MD0080PA00X+172720Y+139658X0160Y         S0      
317GND              VIA   -    MD0080PA00X+173156Y+140850X0160Y         S0      
317GND              VIA   -    MD0100PA00X+173302Y+141099X0180Y         S0      
317GND              VIA   -    MD0100PA00X+173302Y+140600X0180Y         S0      
317GND              VIA   -    MD0080PA00X+173944Y+140850X0160Y         S0      
317GND              VIA   -    MD0100PA00X+173798Y+141099X0180Y         S0      
317GND              VIA   -    MD0100PA00X+173798Y+140600X0180Y         S0      
317GND              VIA   -    MD0080PA00X+172720Y+140850X0160Y         S0      
317GND              VIA   -    MD0100PA00X+172574Y+136989X0180Y         S0      
317GND              VIA   -    MD0100PA00X+172574Y+137488X0180Y         S0      
317GND              VIA   -    MD0100PA00X+172574Y+138180X0180Y         S0      
317GND              VIA   -    MD0100PA00X+172078Y+137488X0180Y         S0      
317GND              VIA   -    MD0100PA00X+172078Y+138180X0180Y         S0      
317GND              VIA   -    MD0100PA00X+172078Y+136989X0180Y         S0      
317GND              VIA   -    MD0080PA00X+171932Y+138430X0160Y         S0      
317GND              VIA   -    MD0080PA00X+171932Y+137238X0160Y         S0      
317GND              VIA   -    MD0080PA00X+171496Y+137238X0160Y         S0      
317GND              VIA   -    MD0080PA00X+171496Y+138430X0160Y         S0      
317GND              VIA   -    MD0100PA00X+171350Y+138180X0180Y         S0      
317GND              VIA   -    MD0100PA00X+171350Y+136989X0180Y         S0      
317GND              VIA   -    MD0100PA00X+171350Y+137488X0180Y         S0      
317GND              VIA   -    MD0100PA00X+172574Y+139399X0180Y         S0      
317GND              VIA   -    MD0100PA00X+172574Y+139908X0180Y         S0      
317GND              VIA   -    MD0100PA00X+172574Y+138679X0180Y         S0      
317GND              VIA   -    MD0100PA00X+172078Y+139908X0180Y         S0      
317GND              VIA   -    MD0100PA00X+172078Y+139399X0180Y         S0      
317GND              VIA   -    MD0100PA00X+172078Y+138679X0180Y         S0      
317GND              VIA   -    MD0080PA00X+171932Y+139658X0160Y         S0      
317GND              VIA   -    MD0080PA00X+171496Y+139658X0160Y         S0      
317GND              VIA   -    MD0100PA00X+171350Y+138679X0180Y         S0      
317GND              VIA   -    MD0100PA00X+171350Y+139409X0180Y         S0      
317GND              VIA   -    MD0100PA00X+171350Y+139908X0180Y         S0      
317GND              VIA   -    MD0100PA00X+172574Y+141099X0180Y         S0      
317GND              VIA   -    MD0100PA00X+172574Y+140600X0180Y         S0      
317GND              VIA   -    MD0100PA00X+172078Y+141099X0180Y         S0      
317GND              VIA   -    MD0100PA00X+172078Y+140600X0180Y         S0      
317GND              VIA   -    MD0080PA00X+171932Y+140850X0160Y         S0      
317GND              VIA   -    MD0080PA00X+171496Y+140850X0160Y         S0      
317GND              VIA   -    MD0100PA00X+171350Y+141099X0180Y         S0      
317GND              VIA   -    MD0100PA00X+171350Y+140600X0180Y         S0      
317GND              VIA   -    MD0080PA00X+173156Y+134819X0160Y         S0      
317GND              VIA   -    MD0100PA00X+173302Y+135068X0180Y         S0      
317GND              VIA   -    MD0100PA00X+173302Y+134569X0180Y         S0      
317GND              VIA   -    MD0080PA00X+173944Y+134819X0160Y         S0      
317GND              VIA   -    MD0100PA00X+173798Y+134569X0180Y         S0      
317GND              VIA   -    MD0100PA00X+173798Y+135068X0180Y         S0      
317GND              VIA   -    MD0080PA00X+172720Y+134819X0160Y         S0      
317GND              VIA   -    MD0080PA00X+173156Y+136010X0160Y         S0      
317GND              VIA   -    MD0100PA00X+173302Y+135760X0180Y         S0      
317GND              VIA   -    MD0100PA00X+173302Y+136260X0180Y         S0      
317GND              VIA   -    MD0080PA00X+173944Y+136010X0160Y         S0      
317GND              VIA   -    MD0100PA00X+173798Y+135760X0180Y         S0      
317GND              VIA   -    MD0100PA00X+173798Y+136260X0180Y         S0      
317GND              VIA   -    MD0080PA00X+172720Y+136010X0160Y         S0      
317GND              VIA   -    MD0080PA00X+173156Y+137238X0160Y         S0      
317GND              VIA   -    MD0080PA00X+173156Y+138430X0160Y         S0      
317GND              VIA   -    MD0100PA00X+173302Y+137488X0180Y         S0      
317GND              VIA   -    MD0100PA00X+173302Y+138180X0180Y         S0      
317GND              VIA   -    MD0100PA00X+173302Y+136989X0180Y         S0      
317GND              VIA   -    MD0080PA00X+173944Y+137238X0160Y         S0      
317GND              VIA   -    MD0100PA00X+173798Y+137488X0180Y         S0      
317GND              VIA   -    MD0100PA00X+173798Y+136989X0180Y         S0      
317GND              VIA   -    MD0080PA00X+169484Y+136010X0160Y         S0      
317GND              VIA   -    MD0100PA00X+170854Y+138180X0180Y         S0      
317GND              VIA   -    MD0100PA00X+170854Y+136989X0180Y         S0      
317GND              VIA   -    MD0100PA00X+170854Y+137488X0180Y         S0      
317GND              VIA   -    MD0080PA00X+170708Y+137238X0160Y         S0      
317GND              VIA   -    MD0080PA00X+170708Y+138430X0160Y         S0      
317GND              VIA   -    MD0080PA00X+170272Y+138430X0160Y         S0      
317GND              VIA   -    MD0080PA00X+170272Y+137238X0160Y         S0      
317GND              VIA   -    MD0100PA00X+170126Y+137488X0180Y         S0      
317GND              VIA   -    MD0100PA00X+170126Y+138180X0180Y         S0      
317GND              VIA   -    MD0100PA00X+170126Y+136989X0180Y         S0      
317GND              VIA   -    MD0100PA00X+169630Y+138180X0180Y         S0      
317GND              VIA   -    MD0100PA00X+169630Y+136989X0180Y         S0      
317GND              VIA   -    MD0080PA00X+169484Y+137238X0160Y         S0      
317GND              VIA   -    MD0080PA00X+169484Y+138430X0160Y         S0      
317GND              VIA   -    MD0100PA00X+169630Y+137488X0180Y         S0      
317GND              VIA   -    MD0080PA00X+170708Y+139658X0160Y         S0      
317GND              VIA   -    MD0100PA00X+170854Y+138679X0180Y         S0      
317GND              VIA   -    MD0100PA00X+170854Y+139409X0180Y         S0      
317GND              VIA   -    MD0100PA00X+170854Y+139908X0180Y         S0      
317GND              VIA   -    MD0100PA00X+170126Y+139908X0180Y         S0      
317GND              VIA   -    MD0100PA00X+170126Y+139409X0180Y         S0      
317GND              VIA   -    MD0100PA00X+170126Y+138679X0180Y         S0      
317GND              VIA   -    MD0080PA00X+170272Y+139658X0160Y         S0      
317GND              VIA   -    MD0100PA00X+169630Y+139908X0180Y         S0      
317GND              VIA   -    MD0100PA00X+169630Y+139409X0180Y         S0      
317GND              VIA   -    MD0100PA00X+169630Y+138679X0180Y         S0      
317GND              VIA   -    MD0080PA00X+169484Y+139658X0160Y         S0      
317GND              VIA   -    MD0080PA00X+170708Y+140850X0160Y         S0      
317GND              VIA   -    MD0100PA00X+170854Y+141099X0180Y         S0      
317GND              VIA   -    MD0100PA00X+170854Y+140600X0180Y         S0      
317GND              VIA   -    MD0100PA00X+170126Y+141099X0180Y         S0      
317GND              VIA   -    MD0100PA00X+170126Y+140600X0180Y         S0      
317GND              VIA   -    MD0080PA00X+170272Y+140850X0160Y         S0      
317GND              VIA   -    MD0100PA00X+169630Y+141099X0180Y         S0      
317GND              VIA   -    MD0100PA00X+169630Y+140600X0180Y         S0      
317GND              VIA   -    MD0080PA00X+169484Y+140850X0160Y         S0      
317GND              VIA   -    MD0100PA00X+172574Y+134560X0180Y         S0      
317GND              VIA   -    MD0100PA00X+172574Y+135068X0180Y         S0      
317GND              VIA   -    MD0100PA00X+172078Y+134560X0180Y         S0      
317GND              VIA   -    MD0100PA00X+172078Y+135068X0180Y         S0      
317GND              VIA   -    MD0080PA00X+171932Y+134819X0160Y         S0      
317GND              VIA   -    MD0080PA00X+171496Y+134819X0160Y         S0      
317GND              VIA   -    MD0100PA00X+171350Y+134569X0180Y         S0      
317GND              VIA   -    MD0100PA00X+171350Y+135068X0180Y         S0      
317GND              VIA   -    MD0100PA00X+172574Y+136260X0180Y         S0      
317GND              VIA   -    MD0100PA00X+172574Y+135760X0180Y         S0      
317GND              VIA   -    MD0100PA00X+172078Y+136260X0180Y         S0      
317GND              VIA   -    MD0100PA00X+172078Y+135760X0180Y         S0      
317GND              VIA   -    MD0080PA00X+171932Y+136010X0160Y         S0      
317GND              VIA   -    MD0080PA00X+171496Y+136010X0160Y         S0      
317GND              VIA   -    MD0100PA00X+171350Y+136260X0180Y         S0      
317GND              VIA   -    MD0100PA00X+171350Y+135760X0180Y         S0      
317GND              VIA   -    MD0080PA00X+168260Y+134819X0160Y         S0      
317GND              VIA   -    MD0100PA00X+168406Y+134569X0180Y         S0      
317GND              VIA   -    MD0100PA00X+168406Y+135068X0180Y         S0      
317GND              VIA   -    MD0080PA00X+169048Y+134819X0160Y         S0      
317GND              VIA   -    MD0100PA00X+168902Y+135068X0180Y         S0      
317GND              VIA   -    MD0100PA00X+168902Y+134569X0180Y         S0      
317GND              VIA   -    MD0080PA00X+167824Y+134819X0160Y         S0      
317GND              VIA   -    MD0100PA00X+168406Y+136260X0180Y         S0      
317GND              VIA   -    MD0100PA00X+168406Y+135760X0180Y         S0      
317GND              VIA   -    MD0080PA00X+168260Y+136010X0160Y         S0      
317GND              VIA   -    MD0100PA00X+168902Y+135760X0180Y         S0      
317GND              VIA   -    MD0100PA00X+168902Y+136260X0180Y         S0      
317GND              VIA   -    MD0080PA00X+169048Y+136010X0160Y         S0      
317GND              VIA   -    MD0080PA00X+167824Y+136010X0160Y         S0      
317GND              VIA   -    MD0080PA00X+168260Y+137238X0160Y         S0      
317GND              VIA   -    MD0080PA00X+168260Y+138430X0160Y         S0      
317GND              VIA   -    MD0100PA00X+168406Y+137488X0180Y         S0      
317GND              VIA   -    MD0100PA00X+168406Y+138180X0180Y         S0      
317GND              VIA   -    MD0100PA00X+168406Y+136989X0180Y         S0      
317GND              VIA   -    MD0080PA00X+169048Y+137238X0160Y         S0      
317GND              VIA   -    MD0080PA00X+169048Y+138430X0160Y         S0      
317GND              VIA   -    MD0100PA00X+168902Y+137488X0180Y         S0      
317GND              VIA   -    MD0100PA00X+168902Y+138180X0180Y         S0      
317GND              VIA   -    MD0100PA00X+168902Y+136989X0180Y         S0      
317GND              VIA   -    MD0080PA00X+167824Y+138430X0160Y         S0      
317GND              VIA   -    MD0080PA00X+167824Y+137238X0160Y         S0      
317GND              VIA   -    MD0080PA00X+168260Y+139658X0160Y         S0      
317GND              VIA   -    MD0100PA00X+168406Y+138679X0180Y         S0      
317GND              VIA   -    MD0100PA00X+168406Y+139908X0180Y         S0      
317GND              VIA   -    MD0100PA00X+168406Y+139409X0180Y         S0      
317GND              VIA   -    MD0080PA00X+169048Y+139658X0160Y         S0      
317GND              VIA   -    MD0100PA00X+168902Y+138679X0180Y         S0      
317GND              VIA   -    MD0100PA00X+168902Y+139908X0180Y         S0      
317GND              VIA   -    MD0100PA00X+168902Y+139409X0180Y         S0      
317GND              VIA   -    MD0080PA00X+167824Y+139658X0160Y         S0      
317GND              VIA   -    MD0080PA00X+168260Y+140850X0160Y         S0      
317GND              VIA   -    MD0100PA00X+168406Y+141099X0180Y         S0      
317GND              VIA   -    MD0100PA00X+168406Y+140600X0180Y         S0      
317GND              VIA   -    MD0080PA00X+169048Y+140850X0160Y         S0      
317GND              VIA   -    MD0100PA00X+168902Y+141099X0180Y         S0      
317GND              VIA   -    MD0100PA00X+168902Y+140600X0180Y         S0      
317GND              VIA   -    MD0080PA00X+167824Y+140850X0160Y         S0      
317GND              VIA   -    MD0080PA00X+170708Y+134819X0160Y         S0      
317GND              VIA   -    MD0100PA00X+170854Y+135068X0180Y         S0      
317GND              VIA   -    MD0100PA00X+170854Y+134569X0180Y         S0      
317GND              VIA   -    MD0100PA00X+170126Y+134569X0180Y         S0      
317GND              VIA   -    MD0100PA00X+170126Y+135068X0180Y         S0      
317GND              VIA   -    MD0080PA00X+170272Y+134819X0160Y         S0      
317GND              VIA   -    MD0100PA00X+169630Y+134569X0180Y         S0      
317GND              VIA   -    MD0100PA00X+169630Y+135068X0180Y         S0      
317GND              VIA   -    MD0080PA00X+169484Y+134819X0160Y         S0      
317GND              VIA   -    MD0080PA00X+170708Y+136010X0160Y         S0      
317GND              VIA   -    MD0100PA00X+170854Y+135760X0180Y         S0      
317GND              VIA   -    MD0100PA00X+170854Y+136260X0180Y         S0      
317GND              VIA   -    MD0100PA00X+170126Y+136260X0180Y         S0      
317GND              VIA   -    MD0100PA00X+170126Y+135760X0180Y         S0      
317GND              VIA   -    MD0080PA00X+170272Y+136010X0160Y         S0      
317GND              VIA   -    MD0100PA00X+169630Y+136260X0180Y         S0      
317GND              VIA   -    MD0100PA00X+169630Y+135760X0180Y         S0      
317GND              VIA   -    MD0100PA00X+167678Y+135068X0180Y         S0      
317GND              VIA   -    MD0100PA00X+167678Y+134569X0180Y         S0      
317GND              VIA   -    MD0080PA00X+167036Y+134819X0160Y         S0      
317GND              VIA   -    MD0100PA00X+167182Y+135068X0180Y         S0      
317GND              VIA   -    MD0100PA00X+167182Y+134569X0180Y         S0      
317GND              VIA   -    MD0100PA00X+166454Y+134569X0180Y         S0      
317GND              VIA   -    MD0100PA00X+166454Y+135068X0180Y         S0      
317GND              VIA   -    MD0080PA00X+166600Y+134819X0160Y         S0      
317GND              VIA   -    MD0100PA00X+167678Y+136260X0180Y         S0      
317GND              VIA   -    MD0100PA00X+167678Y+135760X0180Y         S0      
317GND              VIA   -    MD0100PA00X+167182Y+136260X0180Y         S0      
317GND              VIA   -    MD0100PA00X+167182Y+135760X0180Y         S0      
317GND              VIA   -    MD0080PA00X+167036Y+136010X0160Y         S0      
317GND              VIA   -    MD0080PA00X+166600Y+136010X0160Y         S0      
317GND              VIA   -    MD0100PA00X+166454Y+136260X0180Y         S0      
317GND              VIA   -    MD0100PA00X+166454Y+135760X0180Y         S0      
317GND              VIA   -    MD0100PA00X+167678Y+138180X0180Y         S0      
317GND              VIA   -    MD0100PA00X+167678Y+137488X0180Y         S0      
317GND              VIA   -    MD0100PA00X+167678Y+136989X0180Y         S0      
317GND              VIA   -    MD0100PA00X+167182Y+136989X0180Y         S0      
317GND              VIA   -    MD0100PA00X+167182Y+138180X0180Y         S0      
317GND              VIA   -    MD0100PA00X+167182Y+137488X0180Y         S0      
317GND              VIA   -    MD0080PA00X+167036Y+138430X0160Y         S0      
317GND              VIA   -    MD0080PA00X+167036Y+137238X0160Y         S0      
317GND              VIA   -    MD0080PA00X+166600Y+137238X0160Y         S0      
317GND              VIA   -    MD0080PA00X+166600Y+138430X0160Y         S0      
317GND              VIA   -    MD0100PA00X+166454Y+138180X0180Y         S0      
317GND              VIA   -    MD0100PA00X+166454Y+136989X0180Y         S0      
317GND              VIA   -    MD0100PA00X+166454Y+137488X0180Y         S0      
317GND              VIA   -    MD0100PA00X+167678Y+139409X0180Y         S0      
317GND              VIA   -    MD0100PA00X+167678Y+139908X0180Y         S0      
317GND              VIA   -    MD0100PA00X+167678Y+138679X0180Y         S0      
317GND              VIA   -    MD0100PA00X+167182Y+139908X0180Y         S0      
317GND              VIA   -    MD0100PA00X+167182Y+139409X0180Y         S0      
317GND              VIA   -    MD0100PA00X+167182Y+138679X0180Y         S0      
317GND              VIA   -    MD0080PA00X+167036Y+139658X0160Y         S0      
317GND              VIA   -    MD0080PA00X+166600Y+139658X0160Y         S0      
317GND              VIA   -    MD0100PA00X+166454Y+138679X0180Y         S0      
317GND              VIA   -    MD0100PA00X+166454Y+139908X0180Y         S0      
317GND              VIA   -    MD0100PA00X+166454Y+139409X0180Y         S0      
317GND              VIA   -    MD0100PA00X+167678Y+141099X0180Y         S0      
317GND              VIA   -    MD0100PA00X+167678Y+140600X0180Y         S0      
317GND              VIA   -    MD0100PA00X+167182Y+141099X0180Y         S0      
317GND              VIA   -    MD0100PA00X+167182Y+140600X0180Y         S0      
317GND              VIA   -    MD0080PA00X+167036Y+140850X0160Y         S0      
317GND              VIA   -    MD0080PA00X+166600Y+140850X0160Y         S0      
317GND              VIA   -    MD0100PA00X+166454Y+141099X0180Y         S0      
317GND              VIA   -    MD0100PA00X+166454Y+140600X0180Y         S0      
317GND              VIA   -    MD0080PA00X+164152Y+140850X0160Y         S0      
317GND              VIA   -    MD0100PA00X+164006Y+141099X0180Y         S0      
317GND              VIA   -    MD0100PA00X+164006Y+140600X0180Y         S0      
317GND              VIA   -    MD0080PA00X+162928Y+140850X0160Y         S0      
317GND              VIA   -    MD0080PA00X+165812Y+134819X0160Y         S0      
317GND              VIA   -    MD0100PA00X+165958Y+134569X0180Y         S0      
317GND              VIA   -    MD0100PA00X+165958Y+135068X0180Y         S0      
317GND              VIA   -    MD0100PA00X+165230Y+134569X0180Y         S0      
317GND              VIA   -    MD0100PA00X+165230Y+135068X0180Y         S0      
317GND              VIA   -    MD0080PA00X+165376Y+134819X0160Y         S0      
317GND              VIA   -    MD0100PA00X+164734Y+134569X0180Y         S0      
317GND              VIA   -    MD0100PA00X+164734Y+135068X0180Y         S0      
317GND              VIA   -    MD0080PA00X+164588Y+134819X0160Y         S0      
317GND              VIA   -    MD0080PA00X+165812Y+136010X0160Y         S0      
317GND              VIA   -    MD0100PA00X+165958Y+135760X0180Y         S0      
317GND              VIA   -    MD0100PA00X+165958Y+136260X0180Y         S0      
317GND              VIA   -    MD0100PA00X+165230Y+136260X0180Y         S0      
317GND              VIA   -    MD0100PA00X+165230Y+135760X0180Y         S0      
317GND              VIA   -    MD0080PA00X+165376Y+136010X0160Y         S0      
317GND              VIA   -    MD0100PA00X+164734Y+136260X0180Y         S0      
317GND              VIA   -    MD0100PA00X+164734Y+135760X0180Y         S0      
317GND              VIA   -    MD0080PA00X+164588Y+136010X0160Y         S0      
317GND              VIA   -    MD0080PA00X+165812Y+137238X0160Y         S0      
317GND              VIA   -    MD0080PA00X+165812Y+138430X0160Y         S0      
317GND              VIA   -    MD0100PA00X+165958Y+138180X0180Y         S0      
317GND              VIA   -    MD0100PA00X+165958Y+136989X0180Y         S0      
317GND              VIA   -    MD0100PA00X+165958Y+137488X0180Y         S0      
317GND              VIA   -    MD0100PA00X+165230Y+136989X0180Y         S0      
317GND              VIA   -    MD0100PA00X+165230Y+137488X0180Y         S0      
317GND              VIA   -    MD0100PA00X+165230Y+138180X0180Y         S0      
317GND              VIA   -    MD0080PA00X+165376Y+138430X0160Y         S0      
317GND              VIA   -    MD0080PA00X+165376Y+137238X0160Y         S0      
317GND              VIA   -    MD0100PA00X+164734Y+136989X0180Y         S0      
317GND              VIA   -    MD0100PA00X+164734Y+137488X0180Y         S0      
317GND              VIA   -    MD0100PA00X+164734Y+138180X0180Y         S0      
317GND              VIA   -    MD0080PA00X+164588Y+137238X0160Y         S0      
317GND              VIA   -    MD0080PA00X+164588Y+138430X0160Y         S0      
317GND              VIA   -    MD0080PA00X+165812Y+139658X0160Y         S0      
317GND              VIA   -    MD0100PA00X+165958Y+138679X0180Y         S0      
317GND              VIA   -    MD0100PA00X+165958Y+139908X0180Y         S0      
317GND              VIA   -    MD0100PA00X+165958Y+139409X0180Y         S0      
317GND              VIA   -    MD0100PA00X+165230Y+139409X0180Y         S0      
317GND              VIA   -    MD0100PA00X+165230Y+139908X0180Y         S0      
317GND              VIA   -    MD0100PA00X+165230Y+138679X0180Y         S0      
317GND              VIA   -    MD0080PA00X+165376Y+139658X0160Y         S0      
317GND              VIA   -    MD0100PA00X+164734Y+139908X0180Y         S0      
317GND              VIA   -    MD0100PA00X+164734Y+139409X0180Y         S0      
317GND              VIA   -    MD0100PA00X+164734Y+138679X0180Y         S0      
317GND              VIA   -    MD0080PA00X+164588Y+139658X0160Y         S0      
317GND              VIA   -    MD0080PA00X+165812Y+140850X0160Y         S0      
317GND              VIA   -    MD0100PA00X+165958Y+141099X0180Y         S0      
317GND              VIA   -    MD0100PA00X+165958Y+140600X0180Y         S0      
317GND              VIA   -    MD0100PA00X+165230Y+141099X0180Y         S0      
317GND              VIA   -    MD0100PA00X+165230Y+140600X0180Y         S0      
317GND              VIA   -    MD0080PA00X+165376Y+140850X0160Y         S0      
317GND              VIA   -    MD0100PA00X+164734Y+141099X0180Y         S0      
317GND              VIA   -    MD0100PA00X+164734Y+140600X0180Y         S0      
317GND              VIA   -    MD0080PA00X+164588Y+140850X0160Y         S0      
317GND              VIA   -    MD0080PA00X+162140Y+138430X0160Y         S0      
317GND              VIA   -    MD0080PA00X+162140Y+137238X0160Y         S0      
317GND              VIA   -    MD0080PA00X+161704Y+137238X0160Y         S0      
317GND              VIA   -    MD0080PA00X+161704Y+138430X0160Y         S0      
317GND              VIA   -    MD0100PA00X+161558Y+136989X0180Y         S0      
317GND              VIA   -    MD0100PA00X+161558Y+137488X0180Y         S0      
317GND              VIA   -    MD0100PA00X+161558Y+138180X0180Y         S0      
317GND              VIA   -    MD0100PA00X+162782Y+139399X0180Y         S0      
317GND              VIA   -    MD0100PA00X+162782Y+139908X0180Y         S0      
317GND              VIA   -    MD0100PA00X+162782Y+138679X0180Y         S0      
317GND              VIA   -    MD0100PA00X+162286Y+139908X0180Y         S0      
317GND              VIA   -    MD0100PA00X+162286Y+139399X0180Y         S0      
317GND              VIA   -    MD0100PA00X+162286Y+138679X0180Y         S0      
317GND              VIA   -    MD0080PA00X+162140Y+139658X0160Y         S0      
317GND              VIA   -    MD0100PA00X+161558Y+138679X0180Y         S0      
317GND              VIA   -    MD0100PA00X+162782Y+141099X0180Y         S0      
317GND              VIA   -    MD0100PA00X+162782Y+140600X0180Y         S0      
317GND              VIA   -    MD0100PA00X+162286Y+141099X0180Y         S0      
317GND              VIA   -    MD0100PA00X+162286Y+140600X0180Y         S0      
317GND              VIA   -    MD0080PA00X+162140Y+140850X0160Y         S0      
317GND              VIA   -    MD0080PA00X+163364Y+134819X0160Y         S0      
317GND              VIA   -    MD0100PA00X+163510Y+135068X0180Y         S0      
317GND              VIA   -    MD0100PA00X+163510Y+134569X0180Y         S0      
317GND              VIA   -    MD0080PA00X+164152Y+134819X0160Y         S0      
317GND              VIA   -    MD0100PA00X+164006Y+135068X0180Y         S0      
317GND              VIA   -    MD0100PA00X+164006Y+134569X0180Y         S0      
317GND              VIA   -    MD0080PA00X+162928Y+134819X0160Y         S0      
317GND              VIA   -    MD0080PA00X+163364Y+136010X0160Y         S0      
317GND              VIA   -    MD0100PA00X+163510Y+135760X0180Y         S0      
317GND              VIA   -    MD0100PA00X+163510Y+136260X0180Y         S0      
317GND              VIA   -    MD0080PA00X+164152Y+136010X0160Y         S0      
317GND              VIA   -    MD0100PA00X+164006Y+136260X0180Y         S0      
317GND              VIA   -    MD0100PA00X+164006Y+135760X0180Y         S0      
317GND              VIA   -    MD0080PA00X+162928Y+136010X0160Y         S0      
317GND              VIA   -    MD0080PA00X+163364Y+137238X0160Y         S0      
317GND              VIA   -    MD0080PA00X+163364Y+138430X0160Y         S0      
317GND              VIA   -    MD0100PA00X+163510Y+138180X0180Y         S0      
317GND              VIA   -    MD0100PA00X+163510Y+137488X0180Y         S0      
317GND              VIA   -    MD0100PA00X+163510Y+136989X0180Y         S0      
317GND              VIA   -    MD0080PA00X+164152Y+137238X0160Y         S0      
317GND              VIA   -    MD0080PA00X+164152Y+138430X0160Y         S0      
317GND              VIA   -    MD0100PA00X+164006Y+138180X0180Y         S0      
317GND              VIA   -    MD0100PA00X+164006Y+137488X0180Y         S0      
317GND              VIA   -    MD0100PA00X+164006Y+136989X0180Y         S0      
317GND              VIA   -    MD0080PA00X+162928Y+137238X0160Y         S0      
317GND              VIA   -    MD0080PA00X+162928Y+138430X0160Y         S0      
317GND              VIA   -    MD0080PA00X+163364Y+139658X0160Y         S0      
317GND              VIA   -    MD0100PA00X+163510Y+138679X0180Y         S0      
317GND              VIA   -    MD0100PA00X+163510Y+139908X0180Y         S0      
317GND              VIA   -    MD0100PA00X+163510Y+139409X0180Y         S0      
317GND              VIA   -    MD0080PA00X+164152Y+139658X0160Y         S0      
317GND              VIA   -    MD0100PA00X+164006Y+138679X0180Y         S0      
317GND              VIA   -    MD0100PA00X+164006Y+139409X0180Y         S0      
317GND              VIA   -    MD0100PA00X+164006Y+139908X0180Y         S0      
317GND              VIA   -    MD0080PA00X+162928Y+139658X0160Y         S0      
317GND              VIA   -    MD0080PA00X+163364Y+140850X0160Y         S0      
317GND              VIA   -    MD0100PA00X+163510Y+141099X0180Y         S0      
317GND              VIA   -    MD0100PA00X+163510Y+140600X0180Y         S0      
317GND              VIA   -    MD0080PA00X+160916Y+134819X0160Y         S0      
317GND              VIA   -    MD0100PA00X+161062Y+135068X0180Y         S0      
317GND              VIA   -    MD0100PA00X+161062Y+134569X0180Y         S0      
317GND              VIA   -    MD0080PA00X+160916Y+136010X0160Y         S0      
317GND              VIA   -    MD0100PA00X+161062Y+136260X0180Y         S0      
317GND              VIA   -    MD0100PA00X+161062Y+135760X0180Y         S0      
317GND              VIA   -    MD0080PA00X+160916Y+137238X0160Y         S0      
317GND              VIA   -    MD0080PA00X+160916Y+138430X0160Y         S0      
317GND              VIA   -    MD0100PA00X+161062Y+136989X0180Y         S0      
317GND              VIA   -    MD0100PA00X+161062Y+137488X0180Y         S0      
317GND              VIA   -    MD0100PA00X+161062Y+138180X0180Y         S0      
317GND              VIA   -    MD0100PA00X+161062Y+138679X0180Y         S0      
317GND              VIA   -    MD0100PA00X+162782Y+134569X0180Y         S0      
317GND              VIA   -    MD0100PA00X+162782Y+135068X0180Y         S0      
317GND              VIA   -    MD0100PA00X+162286Y+134569X0180Y         S0      
317GND              VIA   -    MD0100PA00X+162286Y+135068X0180Y         S0      
317GND              VIA   -    MD0080PA00X+162140Y+134819X0160Y         S0      
317GND              VIA   -    MD0080PA00X+161704Y+134819X0160Y         S0      
317GND              VIA   -    MD0100PA00X+161558Y+135068X0180Y         S0      
317GND              VIA   -    MD0100PA00X+161558Y+134569X0180Y         S0      
317GND              VIA   -    MD0100PA00X+162782Y+136260X0180Y         S0      
317GND              VIA   -    MD0100PA00X+162782Y+135760X0180Y         S0      
317GND              VIA   -    MD0100PA00X+162286Y+136260X0180Y         S0      
317GND              VIA   -    MD0100PA00X+162286Y+135760X0180Y         S0      
317GND              VIA   -    MD0080PA00X+162140Y+136010X0160Y         S0      
317GND              VIA   -    MD0080PA00X+161704Y+136010X0160Y         S0      
317GND              VIA   -    MD0100PA00X+161558Y+136260X0180Y         S0      
317GND              VIA   -    MD0100PA00X+161558Y+135760X0180Y         S0      
317GND              VIA   -    MD0100PA00X+162782Y+137488X0180Y         S0      
317GND              VIA   -    MD0100PA00X+162782Y+136980X0180Y         S0      
317GND              VIA   -    MD0100PA00X+162782Y+138180X0180Y         S0      
317GND              VIA   -    MD0100PA00X+162286Y+137488X0180Y         S0      
317GND              VIA   -    MD0100PA00X+162286Y+136980X0180Y         S0      
317GND              VIA   -    MD0100PA00X+162286Y+138180X0180Y         S0      
327GND              U450  -2          A18X+089103Y+069411X0110Y0200R270 S2      
317GND              VIA   -    MD0100PA00X+093850Y+036220X0200Y    R090 S0      
317GND              VIA   -    MD0100PA00X+042978Y+154822X0200Y         S0      
327GND              C2622 -2          A01X+094168Y+035768X0198Y0197R270 S1      
327GND              Y5    -4          A01X+094845Y+036572X0360Y0400R270 S1      
327GND              Y5    -2          A01X+095514Y+036061X0360Y0400R270 S1      
327GND              Y8    -4          A01X+043407Y+155550X0360Y0400R090 S1      
327GND              C3636 -2          A01X+042456Y+155021X0198Y0197R180 S1      
327GND              Y8    -2          A01X+042738Y+156062X0360Y0400R090 S1      
317GND              H48   -1   MD2210PA00X+179501Y+002362X3940Y         S3      
327GND              C4502 -2          A01X+083624Y+083995X0198Y0197R180 S1      
327GND              C2571 -1   M      A01X+083273Y+084048X0198Y0197R090 S1      
327GND              R5531 -1          A18X+084273Y+083946X0198Y0197R180 S2      
327GND              R6836 -2          A01X+066444Y+022572X0198Y0197     S1      
327GND              R6826 -2          A01X+178334Y+022572X0198Y0197     S1      
327GND              R6827 -2          A01X+168097Y+022572X0198Y0197     S1      
327GND              R6828 -2          A01X+157861Y+022572X0198Y0197     S1      
327GND              R6829 -2          A01X+147625Y+022572X0198Y0197     S1      
327GND              R6830 -2          A01X+132625Y+022572X0198Y0197     S1      
327GND              R6831 -2          A01X+122389Y+022572X0198Y0197     S1      
327GND              R6832 -2          A01X+112152Y+022572X0198Y0197     S1      
327GND              R6833 -2          A01X+101916Y+022572X0198Y0197     S1      
327GND              C4497 -2          A01X+054778Y+074651X0198Y0197     S1      
327GND              C4496 -2          A01X+055576Y+073856X0198Y0197     S1      
327GND              C4499 -2          A01X+068873Y+070036X0198Y0197R270 S1      
327GND              C4498 -2   M      A01X+069316Y+070022X0198Y0197R090 S1      
317GND              VIA   -    MD0100PA00X+048530Y+068184X0200Y         S0      
327GND              C4501 -2          A01X+049391Y+068051X0198Y0197R090 S1      
327GND              C4500 -2   M      A01X+048874Y+068049X0198Y0197R090 S1      
327GND              R6837 -2          A01X+056208Y+022572X0198Y0197     S1      
327GND              R6838 -2          A01X+041208Y+022572X0198Y0197     S1      
327GND              R6839 -2          A01X+030971Y+022572X0198Y0197     S1      
327GND              R6840 -2          A01X+020735Y+022572X0198Y0197     S1      
327GND              R6841 -2          A01X+010499Y+022572X0198Y0197     S1      
317GND              VIA   -    MD0100PA00X+079372Y+146807X0200Y         S0      
317GND              VIA   -    MD0100PA00X+076643Y+158371X0200Y         S0      
327GND              C4493 -2          A01X+075917Y+158376X0198Y0197R270 S1      
327GND              C2844 -2   M      A01X+076314Y+158371X0198Y0197R270 S1      
327GND              R6820 -1          A18X+090057Y+088848X0198Y0197R180 S2      
317GND              VIA   -    MD0100PA00X+089969Y+089521X0200Y         S0      
327GND              C4487 -2   M      A18X+090059Y+089246X0198Y0197     S2      
327GND              R6817 -1          A18X+082549Y+089005X0198Y0197R090 S2      
327GND              C4491 -2   M      A18X+082985Y+089008X0198Y0197R270 S2      
317GND              VIA   -    MD0100PA00X+049232Y+037625X0200Y         S0      
317GND              VIA   -    MD0100PA00X+105125Y+129029X0200Y         S0      
317GND              VIA   -    MD0100PA00X+053022Y+036442X0200Y         S0      
317GND              VIA   -    MD0100PA00X+053303Y+035184X0200Y         S0      
317GND              VIA   -    MD0100PA00X+052421Y+035412X0200Y         S0      
317GND              VIA   -    MD0100PA00X+035730Y+119271X0200Y         S0      
327GND              R1253 -1          A01X+036240Y+119542X0198Y0197R090 S1      
317GND              VIA   -    MD0100PA00X+058769Y+150572X0200Y         S0      
327GND              R6770 -2          A01X+058454Y+150572X0198Y0197     S1      
327GND              PC6619-2          A18X+142636Y+108589X0400Y0500     S2      
327GND              PC6620-2          A18X+142650Y+109309X0400Y0500     S2      
327GND              PC6621-2          A18X+137795Y+109307X0400Y0500R180 S2      
327GND              PC6618-2          A18X+131236Y+108588X0400Y0500R180 S2      
327GND              PC6615-2          A18X+136092Y+109309X0400Y0500     S2      
327GND              PC6616-2          A18X+131236Y+109307X0400Y0500R180 S2      
327GND              PC6617-2          A01X+131236Y+108588X0400Y0500     S1      
317GND              VIA   -    MD0100PA00X+131309Y+109728X0200Y    R090 S0      
317GND              VIA   -    MD0100PA00X+131059Y+109728X0200Y    R090 S0      
317GND              VIA   -    MD0100PA00X+131346Y+108160X0200Y    R090 S0      
327GND              PC6622-2          A01X+142636Y+108589X0400Y0500R180 S1      
327GND              PC984 -2          A01X+133186Y+105464X0198Y0197R270 S1      
327GND              PC985 -2          A01X+142013Y+105493X0198Y0197R270 S1      
327GND              PC6613-2          A18X+051219Y+108589X0400Y0500     S2      
327GND              PC6612-2          A18X+051233Y+109309X0400Y0500     S2      
327GND              PC6611-2          A18X+046378Y+109307X0400Y0500R180 S2      
327GND              PC6608-2          A18X+039818Y+108588X0400Y0500R180 S2      
327GND              PC6607-2          A18X+039819Y+109307X0400Y0500R180 S2      
327GND              PC6609-2          A18X+044674Y+109309X0400Y0500     S2      
317GND              VIA   -    MD0100PA00X+039928Y+108160X0200Y    R090 S0      
327GND              PC6610-2          A01X+039818Y+108588X0400Y0500     S1      
327GND              PC6614-2          A01X+051219Y+108589X0400Y0500R180 S1      
327GND              R6780 -2          A01X+074759Y+163063X0198Y0197R270 S1      
327GND              PR92  -2          A01X+044552Y+102277X0198Y0197R180 S1      
327GND              PR84  -2          A01X+044552Y+103027X0198Y0197R180 S1      
327GND              PR7132-2          A01X+045252Y+104705X0198Y0197R180 S1      
327GND              PR7133-2          A01X+045259Y+104314X0198Y0197R180 S1      
327GND              PR7134-2          A18X+048412Y+102389X0198Y0197R090 S2      
327GND              PR7135-2          A18X+047891Y+102405X0198Y0197R090 S2      
327GND              PR102 -2          A01X+042253Y+109877X0198Y0197R270 S1      
327GND              PR106 -2          A01X+045466Y+109877X0198Y0197R270 S1      
327GND              PR110 -2          A01X+048812Y+109877X0198Y0197R270 S1      
327GND              PR114 -2          A01X+052025Y+109877X0198Y0197R270 S1      
327GND              PR133 -2          A01X+135969Y+103027X0198Y0197R180 S1      
327GND              PR7136-2          A01X+136669Y+104705X0198Y0197R180 S1      
327GND              PR7137-2          A01X+136677Y+104314X0198Y0197R180 S1      
327GND              PR7138-2          A18X+139829Y+102389X0198Y0197R090 S2      
327GND              PR7139-2          A18X+139308Y+102405X0198Y0197R090 S2      
327GND              PR7143-1          A18X+141058Y+102827X0198Y0197     S2      
327GND              PR151 -2          A01X+133671Y+109877X0198Y0197R270 S1      
327GND              PR155 -2          A01X+136883Y+109877X0198Y0197R270 S1      
327GND              PR159 -2          A01X+140229Y+109877X0198Y0197R270 S1      
327GND              PR163 -2          A01X+143442Y+109877X0198Y0197R270 S1      
327GND              PR198 -2          A01X+129941Y+037348X0198Y0197R270 S1      
327GND              PR206 -2          A01X+175650Y+037348X0198Y0197R270 S1      
327GND              PR205 -2          A01X+088474Y+038570X0198Y0197R270 S1      
327GND              PR197 -2          A01X+038524Y+037348X0198Y0197R270 S1      
327GND              PR194 -2          A01X+094257Y+054073X0198Y0197R180 S1      
327GND              PR201 -2          A01X+048548Y+054073X0198Y0197R180 S1      
327GND              PC327 -2          A01X+128744Y+037260X0198Y0197R270 S1      
327GND              PR202 -2          A01X+139966Y+054073X0198Y0197R180 S1      
327GND              PR210 -2          A01X+056208Y+021286X0198Y0197     S1      
327GND              PR218 -2          A01X+076680Y+021286X0198Y0197     S1      
327GND              PR213 -2          A01X+020735Y+021286X0198Y0197     S1      
327GND              PR221 -2          A01X+041208Y+021286X0198Y0197     S1      
327GND              PR217 -2          A01X+030972Y+021286X0198Y0197     S1      
327GND              PR222 -2          A01X+086916Y+021286X0198Y0197     S1      
327GND              PR214 -2          A01X+066444Y+021286X0198Y0197     S1      
327GND              PC362 -2          A01X+010499Y+020086X0198Y0197     S1      
327GND              PC387 -2          A01X+076680Y+020086X0198Y0197     S1      
327GND              PR238 -2          A01X+178334Y+021286X0198Y0197     S1      
327GND              PR234 -2          A01X+168098Y+021286X0198Y0197     S1      
327GND              PR233 -2          A01X+122389Y+021286X0198Y0197     S1      
327GND              PR226 -2          A01X+147625Y+021286X0198Y0197     S1      
327GND              PR237 -2          A01X+132625Y+021286X0198Y0197     S1      
327GND              PR229 -2          A01X+112153Y+021286X0198Y0197     S1      
327GND              PR225 -2          A01X+101916Y+021286X0198Y0197     S1      
327GND              PR230 -2          A01X+157861Y+021286X0198Y0197     S1      
327GND              PC410 -2          A01X+101916Y+020086X0198Y0197     S1      
327GND              PC411 -2          A01X+147625Y+020086X0198Y0197     S1      
327GND              PC422 -2          A01X+112153Y+020086X0198Y0197     S1      
327GND              PC423 -2          A01X+157861Y+020086X0198Y0197     S1      
327GND              PC434 -2          A01X+122389Y+020086X0198Y0197     S1      
327GND              PC435 -2          A01X+168098Y+020086X0198Y0197     S1      
327GND              PC446 -2          A01X+132625Y+020086X0198Y0197     S1      
327GND              PC447 -2          A01X+178334Y+020086X0198Y0197     S1      
327GND              PR253 -2          A01X+084833Y+047338X0198Y0197     S1      
327GND              PR245 -2          A01X+039124Y+047838X0198Y0197     S1      
327GND              PR250 -2          A01X+140949Y+048798X0198Y0197R180 S1      
327GND              PR241 -2          A01X+003823Y+048798X0198Y0197R180 S1      
327GND              PR249 -2          A01X+049532Y+048798X0198Y0197R180 S1      
327GND              PR246 -2          A01X+130542Y+047838X0198Y0197     S1      
327GND              PR254 -2          A01X+176250Y+047838X0198Y0197     S1      
327GND              PR242 -2          A01X+095240Y+048798X0198Y0197R180 S1      
327GND              PR6905-2   M      A01X+008382Y+028806X0198Y0197R090 S1      
327GND              PR6906-2   M      A01X+018618Y+028806X0198Y0197R090 S1      
327GND              PR6910-2   M      A01X+028854Y+028806X0198Y0197R090 S1      
327GND              PR6912-2   M      A01X+039090Y+028806X0198Y0197R090 S1      
327GND              PR7064-2          A01X+054091Y+028806X0198Y0197R090 S1      
327GND              PR7066-2          A01X+064327Y+028806X0198Y0197R090 S1      
327GND              PR7071-2          A01X+074563Y+028806X0198Y0197R090 S1      
327GND              PR7072-2          A01X+084799Y+028806X0198Y0197R090 S1      
327GND              PR7076-2          A01X+099799Y+028806X0198Y0197R090 S1      
327GND              PR7078-2          A01X+110035Y+028806X0198Y0197R090 S1      
327GND              PR7082-2          A01X+120272Y+028806X0198Y0197R090 S1      
327GND              PR7084-2          A01X+130508Y+028806X0198Y0197R090 S1      
327GND              PR7088-2          A01X+145508Y+028806X0198Y0197R090 S1      
327GND              PR7090-2          A01X+155744Y+028806X0198Y0197R090 S1      
327GND              PR7094-2          A01X+165980Y+028806X0198Y0197R090 S1      
327GND              PR7096-2          A01X+176216Y+028806X0198Y0197R090 S1      
327GND              PC983 -2          A01X+050596Y+105493X0198Y0197R270 S1      
327GND              C2145 -1          A18X+082815Y+085948X0198Y0197R180 S2      
327GND              PC106 -2          A01X+052826Y+110372X0198Y0197     S1      
327GND              PC108 -2          A01X+050998Y+109883X0198Y0197     S1      
327GND              PC122 -2          A01X+046004Y+109877X0198Y0197R270 S1      
327GND              PC75  -2          A01X+044439Y+109883X0198Y0197     S1      
327GND              PC96  -2          A01X+051233Y+109309X0400Y0500R180 S1      
327GND              PC111 -2          A01X+046378Y+109307X0400Y0500     S1      
327GND              PC80  -2          A01X+044674Y+109309X0400Y0500R180 S1      
327GND              PC61  -2          A01X+039819Y+109307X0400Y0500     S1      
327GND              PC97  -2          A01X+047125Y+105907X0630Y1380R180 S1      
327GND              PC64  -2          A01X+043824Y+105907X0630Y1380R180 S1      
327GND              PC982 -2          A01X+041768Y+105464X0198Y0197R270 S1      
327GND              PC202 -2          A01X+144243Y+110372X0198Y0197     S1      
327GND              PC188 -2          A01X+142415Y+109883X0198Y0197     S1      
327GND              PC166 -2          A01X+137422Y+109877X0198Y0197R270 S1      
327GND              PC156 -2          A01X+135857Y+109883X0198Y0197     S1      
327GND              PC175 -2          A01X+142650Y+109309X0400Y0500R180 S1      
327GND              PC190 -2          A01X+137795Y+109307X0400Y0500     S1      
327GND              PC142 -2          A01X+136092Y+109309X0400Y0500R180 S1      
327GND              PC158 -2          A01X+131236Y+109307X0400Y0500     S1      
327GND              PC177 -2          A01X+138542Y+105907X0630Y1380R180 S1      
327GND              PC144 -2          A01X+135242Y+105907X0630Y1380R180 S1      
317GND              VIA   -    MD0100PA00X+050598Y+105249X0200Y         S0      
317GND              VIA   -    MD0100PA00X+047865Y+106050X0200Y         S0      
317GND              VIA   -    MD0100PA00X+047865Y+106300X0200Y         S0      
317GND              VIA   -    MD0100PA00X+047615Y+106300X0200Y         S0      
317GND              VIA   -    MD0100PA00X+047615Y+106050X0200Y         S0      
317GND              VIA   -    MD0100PA00X+047865Y+105800X0200Y         S0      
317GND              VIA   -    MD0100PA00X+047865Y+105550X0200Y         S0      
317GND              VIA   -    MD0100PA00X+047615Y+105550X0200Y         S0      
317GND              VIA   -    MD0100PA00X+047615Y+105800X0200Y         S0      
317GND              VIA   -    MD0100PA00X+043071Y+106050X0200Y         S0      
317GND              VIA   -    MD0100PA00X+043071Y+106300X0200Y         S0      
317GND              VIA   -    MD0100PA00X+043321Y+106300X0200Y         S0      
317GND              VIA   -    MD0100PA00X+043321Y+106050X0200Y         S0      
317GND              VIA   -    MD0100PA00X+043321Y+105800X0200Y         S0      
317GND              VIA   -    MD0100PA00X+043071Y+105800X0200Y         S0      
317GND              VIA   -    MD0100PA00X+043071Y+105550X0200Y         S0      
317GND              VIA   -    MD0100PA00X+043321Y+105550X0200Y         S0      
317GND              VIA   -    MD0100PA00X+041768Y+105222X0200Y         S0      
317GND              VIA   -    MD0100PA00X+134488Y+106050X0200Y         S0      
317GND              VIA   -    MD0100PA00X+134488Y+106300X0200Y         S0      
317GND              VIA   -    MD0100PA00X+134738Y+106300X0200Y         S0      
317GND              VIA   -    MD0100PA00X+134738Y+106050X0200Y         S0      
317GND              VIA   -    MD0100PA00X+134488Y+105800X0200Y         S0      
317GND              VIA   -    MD0100PA00X+134488Y+105550X0200Y         S0      
317GND              VIA   -    MD0100PA00X+134738Y+105550X0200Y         S0      
317GND              VIA   -    MD0100PA00X+134738Y+105800X0200Y         S0      
317GND              VIA   -    MD0100PA00X+133189Y+105192X0200Y         S0      
317GND              VIA   -    MD0100PA00X+142011Y+105251X0200Y         S0      
317GND              VIA   -    MD0100PA00X+139282Y+106050X0200Y         S0      
317GND              VIA   -    MD0100PA00X+139282Y+106300X0200Y         S0      
317GND              VIA   -    MD0100PA00X+139032Y+106300X0200Y         S0      
317GND              VIA   -    MD0100PA00X+139032Y+106050X0200Y         S0      
317GND              VIA   -    MD0100PA00X+139282Y+105800X0200Y         S0      
317GND              VIA   -    MD0100PA00X+139282Y+105550X0200Y         S0      
317GND              VIA   -    MD0100PA00X+139032Y+105550X0200Y         S0      
317GND              VIA   -    MD0100PA00X+139032Y+105800X0200Y         S0      
327GND              C4486 -2          A01X+102412Y+133396X0198Y0197R090 S1      
317GND              VIA   -    MD0100PA00X+103451Y+133366X0200Y         S0      
327GND              U449  -2   M      A01X+103227Y+133032X0240Y0420R270 S1      
317GND              VIA   -    MD0100PA00X+102543Y+132061X0200Y         S0      
327GND              U448  -2          A01X+103230Y+131935X0240Y0420R270 S1      
317GND              VIA   -    MD0100PA00X+105222Y+133698X0200Y         S0      
327GND              C4484 -2          A01X+105151Y+132361X0198Y0197     S1      
317GND              VIA   -    MD0100PA00X+077382Y+162742X0200Y         S0      
327GND              C4477 -2          A01X+077382Y+163015X0198Y0197R270 S1      
317GND              VIA   -    MD0100PA00X+078229Y+162011X0200Y         S0      
327GND              U444  -2          A01X+078229Y+162388X0240Y0420R180 S1      
317GND              VIA   -    MD0100PA00X+077804Y+162254X0200Y         S0      
327GND              C4479 -2          A01X+077484Y+162254X0198Y0197R090 S1      
317GND              VIA   -    MD0100PA00X+076278Y+162942X0200Y         S0      
327GND              U443  -2          A01X+076278Y+163309X0240Y0420R180 S1      
317GND              VIA   -    MD0100PA00X+074759Y+162787X0200Y         S0      
317GND              VIA   -    MD0100PA00X+075215Y+162787X0200Y         S0      
327GND              C4478 -2          A01X+075215Y+163066X0198Y0197R270 S1      
327GND              PU68  -6          A01X+171040Y+021324X0110Y0240     S1      
327GND              PU21  -6          A01X+044280Y+049372X0110Y0240R270 S1      
327GND              PU22  -6          A01X+005014Y+054436X0110Y0240R090 S1      
327GND              PU24  -6          A01X+037946Y+039554X0110Y0240R180 S1      
327GND              PU26  -6          A01X+050722Y+054436X0110Y0240R090 S1      
327GND              PU28  -6          A01X+087479Y+040888X0110Y0240R180 S1      
327GND              PU23  -6          A01X+096431Y+054436X0110Y0240R090 S1      
327GND              PU25  -6          A01X+129363Y+039554X0110Y0240R180 S1      
327GND              PU27  -6          A01X+142140Y+054436X0110Y0240R090 S1      
327GND              PU29  -6          A01X+175072Y+039554X0110Y0240R180 S1      
327GND              PU30  -6          A01X+008326Y+020923X0110Y0240R270 S1      
327GND              PU32  -6          A01X+018562Y+020923X0110Y0240R270 S1      
327GND              PU34  -6          A01X+028798Y+020923X0110Y0240R270 S1      
327GND              PU36  -6          A01X+039034Y+020923X0110Y0240R270 S1      
327GND              PU31  -6          A01X+054034Y+020923X0110Y0240R270 S1      
327GND              PU33  -6          A01X+064270Y+020923X0110Y0240R270 S1      
327GND              PU35  -6          A01X+074507Y+020923X0110Y0240R270 S1      
327GND              PU37  -6          A01X+084743Y+020923X0110Y0240R270 S1      
327GND              PU38  -6          A01X+099743Y+020923X0110Y0240R270 S1      
327GND              PU39  -6          A01X+145452Y+020923X0110Y0240R270 S1      
327GND              PU40  -6          A01X+109979Y+020923X0110Y0240R270 S1      
327GND              PU41  -6          A01X+155688Y+020923X0110Y0240R270 S1      
327GND              PU42  -6          A01X+120215Y+020923X0110Y0240R270 S1      
327GND              PU43  -6          A01X+165924Y+020923X0110Y0240R270 S1      
327GND              PU44  -6          A01X+130452Y+020923X0110Y0240R270 S1      
327GND              PU46  -6          A01X+005997Y+049762X0110Y0240R090 S1      
327GND              PU47  -6          A01X+097414Y+049762X0110Y0240R090 S1      
327GND              PU50  -6          A01X+051705Y+049762X0110Y0240R090 S1      
327GND              PU51  -6          A01X+143123Y+049762X0110Y0240R090 S1      
327GND              PU54  -6          A01X+003205Y+021324X0110Y0240     S1      
327GND              PU55  -6          A01X+048914Y+021324X0110Y0240     S1      
327GND              PU56  -6          A01X+013441Y+021324X0110Y0240     S1      
327GND              PU57  -6          A01X+059150Y+021324X0110Y0240     S1      
327GND              PU59  -6          A01X+023678Y+021324X0110Y0240     S1      
327GND              PU58  -6          A01X+069386Y+021324X0110Y0240     S1      
327GND              PU60  -6          A01X+033914Y+021324X0110Y0240     S1      
327GND              PU61  -6          A01X+079622Y+021324X0110Y0240     S1      
327GND              PU62  -6          A01X+094689Y+019841X0110Y0240     S1      
327GND              PU63  -6          A01X+140331Y+021324X0110Y0240     S1      
327GND              PU64  -6          A01X+104859Y+021324X0110Y0240     S1      
327GND              PU65  -6          A01X+150567Y+021324X0110Y0240     S1      
327GND              PU67  -6          A01X+160804Y+021324X0110Y0240     S1      
327GND              PU66  -6          A01X+115095Y+021324X0110Y0240     S1      
327GND              PU69  -6          A01X+125331Y+021324X0110Y0240     S1      
327GND              PU45  -6          A01X+176160Y+020923X0110Y0240R270 S1      
317GND              VIA   -    MD0100PA00X+143356Y+155537X0200Y         S0      
317GND              VIA   -    MD0100PA00X+126298Y+151946X0200Y         S0      
327GND              R6771 -2          A01X+126021Y+151946X0198Y0197     S1      
317GND              H49   -1   MD2210PA00X+046339Y+028622X3940Y         S3      
317GND              H50   -1   MD2210PA00X+040949Y+160472X3940Y         S3      
317GND              H51   -1   MD2210PA00X+043313Y+007087X3940Y         S3      
317GND              H52   -1   MD2210PA00X+066167Y+002362X3940Y    R090 S3      
317GND              H53   -1   MD2210PA00X+002362Y+160472X3940Y         S3      
317GND              H47   -1   MD2210PA00X+007402Y+033346X3940Y         S3      
317GND              H46   -1   MD2210PA00X+105590Y+154764X3940Y         S3      
317GND              H54   -1   MD2210PA00X+134730Y+007087X3940Y         S3      
317GND              H55   -1   MD2210PA00X+046339Y+076520X3940Y         S3      
317GND              H56   -1   MD2210PA00X+177874Y+076520X3940Y         S3      
317GND              H58   -1   MD2210PA00X+078504Y+154764X3940Y         S3      
317GND              H59   -1   MD2210PA00X+143146Y+160472X3940Y         S3      
317GND              H60   -1   MD2210PA00X+137756Y+028622X3940Y         S3      
317GND              H61   -1   MD2210PA00X+181732Y+160472X3940Y         S3      
317GND              H62   -1   MD2210PA00X+111876Y+002362X3940Y         S3      
317GND              H63   -1   MD2210PA00X+089022Y+002362X3940Y         S3      
317GND              H64   -1   MD2210PA00X+157585Y+002362X3940Y         S3      
317GND              H67   -1   MD2210PA00X+006220Y+076520X3940Y         S3      
317GND              H68   -1   MD2210PA00X+137756Y+076520X3940Y         S3      
317GND              H69   -1   MD2210PA00X+092047Y+076520X3940Y         S3      
317GND              H70   -1   MD2210PA00X+176693Y+033346X3940Y         S3      
317GND              H71   -1   MD2210PA00X+010222Y+007087X3940Y         S3      
327GND              PU5   -4          A01X+043809Y+063139X0070Y0320R270 S1      
327GND              PU5   -6          A01X+043809Y+063454X0070Y0320R270 S1      
327GND              PU5   -11_1       A01X+042795Y+063404X0315Y1240R180 S1      
327GND              PU5   -2          A01X+043809Y+062824X0070Y0320R270 S1      
327GND              PU16  -4          A01X+004576Y+120426X0070Y0320R270 S1      
327GND              PU16  -11_1       A01X+003562Y+120692X0315Y1240R180 S1      
327GND              PU16  -2          A01X+004576Y+120111X0070Y0320R270 S1      
327GND              PU17  -4          A01X+088944Y+121326X0070Y0320R270 S1      
327GND              PU17  -11_1       A01X+087931Y+121592X0315Y1240R180 S1      
327GND              PU17  -2          A01X+088944Y+121011X0070Y0320R270 S1      
327GND              PU18  -4          A01X+095342Y+121326X0070Y0320R270 S1      
327GND              PU18  -11_1       A01X+094328Y+121592X0315Y1240R180 S1      
327GND              PU18  -2          A01X+095342Y+121011X0070Y0320R270 S1      
327GND              PU19  -4          A01X+179740Y+121375X0070Y0320R270 S1      
327GND              PU19  -11_1       A01X+178726Y+121641X0315Y1240R180 S1      
327GND              PU19  -2          A01X+179740Y+121060X0070Y0320R270 S1      
327GND              PU20  -4          A01X+041094Y+087837X0070Y0320R090 S1      
327GND              PU20  -6          A01X+041094Y+087522X0070Y0320R090 S1      
327GND              PU20  -11_1       A01X+042108Y+087572X0315Y1240     S1      
327GND              PU20  -2          A01X+041094Y+088152X0070Y0320R090 S1      
327GND              PC326 -2          A01X+037326Y+037260X0180Y0200R090 S1      
327GND              PC338 -2          A01X+048548Y+055273X0180Y0200     S1      
327GND              PC350 -2          A01X+087274Y+038570X0180Y0200R090 S1      
327GND              PC315 -2          A01X+094257Y+055273X0180Y0200     S1      
327GND              PC339 -2          A01X+139966Y+055273X0180Y0200     S1      
327GND              PC351 -2          A01X+174452Y+037260X0180Y0200R090 S1      
327GND              PC374 -2          A01X+020735Y+020086X0180Y0200R180 S1      
327GND              PC386 -2          A01X+030972Y+020086X0180Y0200R180 S1      
327GND              PC398 -2          A01X+041208Y+020086X0180Y0200R180 S1      
327GND              PC363 -2          A01X+056208Y+020086X0180Y0200R180 S1      
327GND              PC375 -2          A01X+066444Y+020086X0180Y0200R180 S1      
327GND              PC399 -2          A01X+086916Y+020086X0180Y0200R180 S1      
327GND              PU48  -6          A01X+036918Y+047261X0110Y0240R270 S1      
327GND              PU52  -6          A01X+082626Y+046761X0110Y0240R270 S1      
327GND              PU49  -6          A01X+128335Y+047261X0110Y0240R270 S1      
327GND              PU53  -6          A01X+174044Y+047261X0110Y0240R270 S1      
327GND              J2    -A12        A01X+091542Y+025748X0150Y0530R090 S1      
327GND              J2    -A16        A01X+091542Y+026693X0150Y0530R090 S1      
327GND              J2    -A10        A01X+091542Y+025276X0150Y0530R090 S1      
327GND              J2    -A4         A01X+091542Y+023858X0150Y0530R090 S1      
327GND              J2    -B1         A01X+090330Y+023150X0150Y0530R090 S1      
327GND              J2    -B4         A01X+090330Y+023858X0150Y0530R090 S1      
327GND              J2    -B7         A01X+090330Y+024567X0150Y0530R090 S1      
327GND              J2    -B10        A01X+090330Y+025276X0150Y0530R090 S1      
327GND              J2    -B13        A01X+090330Y+025984X0150Y0530R090 S1      
327GND              J2    -B16        A01X+090330Y+026693X0150Y0530R090 S1      
327GND              J2    -B19        A01X+090330Y+027402X0150Y0530R090 S1      
327GND              C2798 -2          A18X+088963Y+057153X0198Y0197R180 S2      
327GND              PU13  -2   M      A01X+137296Y+111446X0090Y0240R270 S1      
327GND              PC155 -2          A01X+137759Y+111032X0198Y0197R270 S1      
327GND              PU13  -5   M      A01X+137296Y+111978X0090Y0240R270 S1      
327GND              PC154 -2          A01X+137759Y+112397X0198Y0197R090 S1      
327GND              PU12  -2   M      A01X+134083Y+111446X0090Y0240R270 S1      
327GND              PC145 -2          A01X+134546Y+111032X0198Y0197R270 S1      
327GND              PU12  -5   M      A01X+134083Y+111978X0090Y0240R270 S1      
327GND              PC137 -2          A01X+134546Y+112397X0198Y0197R090 S1      
327GND              PC157 -2          A01X+134946Y+112297X0198Y0197R090 S1      
327GND              PC139 -2          A01X+131733Y+112297X0198Y0197R090 S1      
327GND              PC196 -2          A01X+144245Y+115518X0198Y0197R270 S1      
327GND              PU15  -2   M      A01X+143855Y+111446X0090Y0240R270 S1      
327GND              PC194 -2          A01X+144317Y+111032X0198Y0197R270 S1      
327GND              PU15  -5   M      A01X+143855Y+111978X0090Y0240R270 S1      
327GND              PC187 -2          A01X+144317Y+112397X0198Y0197R090 S1      
327GND              PU14  -2   M      A01X+140642Y+111446X0090Y0240R270 S1      
327GND              PC178 -2          A01X+141105Y+111032X0198Y0197R270 S1      
327GND              PU14  -5   M      A01X+140642Y+111978X0090Y0240R270 S1      
327GND              PC170 -2          A01X+141105Y+112397X0198Y0197R090 S1      
327GND              PC189 -2          A01X+141505Y+112297X0198Y0197R090 S1      
327GND              PC181 -2          A18X+141274Y+115204X0400Y0500R270 S2      
327GND              PC184 -2          A18X+142665Y+114354X0950Y1110R090 S2      
327GND              PC200 -2          A18X+139882Y+114354X0950Y1110R090 S2      
327GND              PC193 -2          A18X+142512Y+112475X0400Y0500R090 S2      
327GND              PC176 -2          A18X+141712Y+112475X0400Y0500R090 S2      
327GND              PC191 -2          A18X+139299Y+112475X0400Y0500R090 S2      
327GND              PC148 -2          A18X+134715Y+115204X0400Y0500R270 S2      
327GND              PC151 -2          A18X+136106Y+114354X0950Y1110R090 S2      
327GND              PC165 -2          A18X+133324Y+114354X0950Y1110R090 S2      
327GND              PC143 -2          A18X+135953Y+112475X0400Y0500R090 S2      
327GND              PC161 -2          A18X+135153Y+112475X0400Y0500R090 S2      
327GND              PC159 -2          A18X+132740Y+112475X0400Y0500R090 S2      
327GND              PC140 -2          A18X+131940Y+112475X0400Y0500R090 S2      
327GND              PC103 -2          A18X+049856Y+115204X0400Y0500R270 S2      
327GND              PC86  -2          A18X+043298Y+115204X0400Y0500R270 S2      
327GND              PC104 -2          A18X+051248Y+114354X0950Y1110R090 S2      
327GND              PC118 -2          A18X+048465Y+114354X0950Y1110R090 S2      
327GND              PC71  -2          A18X+044689Y+114354X0950Y1110R090 S2      
327GND              PC87  -2          A18X+041906Y+114354X0950Y1110R090 S2      
327GND              PC114 -2          A18X+051095Y+112475X0400Y0500R090 S2      
327GND              PC110 -2          A18X+050295Y+112475X0400Y0500R090 S2      
327GND              PC94  -2          A18X+047882Y+112475X0400Y0500R090 S2      
327GND              PC93  -2          A18X+047082Y+112475X0400Y0500R090 S2      
327GND              PC60  -2          A18X+044536Y+112475X0400Y0500R090 S2      
327GND              PC79  -2          A18X+043736Y+112475X0400Y0500R090 S2      
327GND              PC77  -2          A18X+041323Y+112475X0400Y0500R090 S2      
327GND              PC62  -2          A18X+040523Y+112475X0400Y0500R090 S2      
327GND              PC116 -2          A01X+052827Y+115518X0198Y0197R270 S1      
327GND              PU10  -2   M      A01X+052438Y+111446X0090Y0240R270 S1      
327GND              PC113 -2          A01X+052900Y+111032X0198Y0197R270 S1      
327GND              PU10  -5   M      A01X+052438Y+111978X0090Y0240R270 S1      
327GND              PC90  -2          A01X+052900Y+112397X0198Y0197R090 S1      
327GND              PU9   -2   M      A01X+049225Y+111446X0090Y0240R270 S1      
327GND              PC98  -2          A01X+049687Y+111032X0198Y0197R270 S1      
327GND              PU9   -5   M      A01X+049225Y+111978X0090Y0240R270 S1      
327GND              PC107 -2          A01X+049687Y+112397X0198Y0197R090 S1      
327GND              PC109 -2          A01X+050087Y+112297X0198Y0197R090 S1      
327GND              PC83  -2          A01X+040326Y+115518X0198Y0197R270 S1      
327GND              PU8   -2   M      A01X+045879Y+111446X0090Y0240R270 S1      
327GND              PC81  -2          A01X+046341Y+111032X0198Y0197R270 S1      
327GND              PU8   -5   M      A01X+045879Y+111978X0090Y0240R270 S1      
327GND              PC57  -2          A01X+046341Y+112397X0198Y0197R090 S1      
327GND              PU7   -2   M      A01X+042666Y+111446X0090Y0240R270 S1      
327GND              PC65  -2          A01X+043128Y+111032X0198Y0197R270 S1      
327GND              PU7   -5   M      A01X+042666Y+111978X0090Y0240R270 S1      
327GND              PC74  -2          A01X+043128Y+112397X0198Y0197R090 S1      
327GND              PC76  -2          A01X+043529Y+112297X0198Y0197R090 S1      
327GND              PC59  -2          A01X+040316Y+112297X0198Y0197R090 S1      
327GND              R6291 -2          A01X+042028Y+152330X0198Y0197     S1      
327GND              R6292 -2          A01X+041063Y+152330X0198Y0197R180 S1      
327GND              R6760 -2          A01X+095514Y+089989X0198Y0197     S1      
327GND              R6761 -2          A01X+094484Y+089989X0198Y0197R180 S1      
327GND              R6751 -2          A01X+005434Y+149105X0198Y0197R090 S1      
327GND              R6752 -2          A01X+005435Y+148081X0198Y0197R270 S1      
327GND              R6747 -2          A01X+001177Y+152220X0198Y0197R270 S1      
327GND              R6748 -2          A01X+001178Y+153246X0198Y0197R090 S1      
327GND              PR7170-1          A01X+141834Y+102025X0198Y0197R180 S1      
327GND              PR7165-1          A01X+050403Y+102026X0198Y0197R180 S1      
317GND              VIA   -    MD0100PA00X+022225Y+143848X0200Y         S0      
317GND              VIA   -    MD0100PA00X+021330Y+143822X0200Y         S0      
327GND              R6746 -1          A01X+005611Y+155327X0198Y0197R270 S1      
317GND              VIA   -    MD0100PA00X+005611Y+155606X0200Y         S0      
327GND              R6745 -1          A01X+005205Y+155327X0198Y0197R270 S1      
317GND              VIA   -    MD0100PA00X+005205Y+155606X0200Y         S0      
317GND              VIA   -    MD0100PA00X+003585Y+155610X0200Y         S0      
327GND              R6739 -1          A01X+003585Y+155330X0198Y0197R270 S1      
327GND              C4462 -2          A18X+002154Y+151557X0198Y0197R270 S2      
327GND              C4461 -2          A18X+001804Y+151557X0198Y0197R270 S2      
317GND              VIA   -    MD0100PA00X+001200Y+153513X0200Y         S0      
317GND              VIA   -    MD0100PA00X+001233Y+151920X0200Y         S0      
317GND              VIA   -    MD0100PA00X+002228Y+146461X0200Y         S0      
327GND              R6759 -2          A01X+001945Y+146461X0198Y0197     S1      
317GND              VIA   -    MD0100PA00X+002008Y+142935X0200Y         S0      
327GND              Q250  -S          A01X+002008Y+143383X0320Y0360     S1      
317GND              VIA   -    MD0100PA00X+041063Y+152599X0200Y         S0      
317GND              VIA   -    MD0100PA00X+042028Y+152598X0200Y         S0      
317GND              VIA   -    MD0100PA00X+041947Y+151971X0200Y         S0      
317GND              VIA   -    MD0100PA00X+041135Y+151944X0200Y         S0      
317GND              VIA   -    MD0100PA00X+021780Y+143368X0200Y         S0      
317GND              VIA   -    MD0100PA00X+021794Y+142392X0200Y         S0      
327GND              C4475 -2          A01X+000656Y+155069X0198Y0197R090 S1      
317GND              VIA   -    MD0100PA00X+005718Y+148081X0200Y         S0      
317GND              VIA   -    MD0100PA00X+005714Y+149105X0200Y         S0      
317GND              VIA   -    MD0100PA00X+040405Y+151367X0200Y         S0      
327GND              R6294 -2          A01X+040405Y+151656X0180Y0200R180 S1      
317GND              VIA   -    MD0100PA00X+039400Y+150810X0200Y         S0      
327GND              R6293 -2          A01X+039047Y+151645X0180Y0200     S1      
317GND              VIA   -    MD0100PA00X+004100Y+146770X0200Y    R270 S0      
317GND              VIA   -    MD0100PA00X+003354Y+146748X0200Y    R270 S0      
317GND              VIA   -    MD0100PA00X+000804Y+152220X0200Y    R270 S0      
317GND              VIA   -    MD0100PA00X+000792Y+153249X0200Y    R270 S0      
317GND              VIA   -    MD0100PA00X+041982Y+147494X0200Y         S0      
317GND              VIA   -    MD0100PA00X+041115Y+147499X0200Y         S0      
317GND              VIA   -    MD0100PA00X+041510Y+150275X0200Y         S0      
317GND              VIA   -    MD0100PA00X+041524Y+149299X0200Y         S0      
317GND              VIA   -    MD0100PA00X+039722Y+152121X0200Y         S0      
317GND              VIA   -    MD0100PA00X+039724Y+151164X0200Y         S0      
317GND              VIA   -    MD0100PA00X+001841Y+155420X0200Y         S0      
327GND              R6754 -2          A01X+001843Y+155176X0198Y0197R090 S1      
317GND              VIA   -    MD0100PA00X+001438Y+155312X0200Y         S0      
327GND              R6736 -1          A01X+001438Y+155065X0198Y0197R270 S1      
327GND              C4473 -2          A18X+006358Y+151860X0198Y0197R180 S2      
327GND              C4468 -2          A18X+006355Y+152571X0198Y0197R180 S2      
327GND              C4470 -2          A18X+006353Y+153180X0198Y0197R180 S2      
327GND              C4472 -2          A18X+002345Y+153415X0198Y0197R090 S2      
327GND              C4465 -2          A18X+002477Y+150357X0400Y0500     S2      
327GND              C4463 -2          A18X+002886Y+152993X0198Y0197R180 S2      
327GND              C4469 -2          A18X+004387Y+149826X0198Y0197R090 S2      
327GND              C4476 -2          A18X+006207Y+151174X0198Y0197R180 S2      
327GND              C4464 -2          A18X+005145Y+149852X0198Y0197R090 S2      
327GND              C4471 -2          A18X+003574Y+149826X0198Y0197R090 S2      
327GND              C4467 -2          A18X+002886Y+152277X0198Y0197R180 S2      
327GND              C4474 -2          A18X+004408Y+152938X0400Y0500R270 S2      
327GND              U442  -TH  M      A01X+004008Y+152164X2362Y2362R090 S1      
317GND              VIA   -    MD0100PA00X+004808Y+152164X0200Y         S0      
317GND              VIA   -    MD0100PA00X+004808Y+152964X0200Y         S0      
317GND              VIA   -    MD0100PA00X+003924Y+153210X0200Y    R180 S0      
317GND              VIA   -    MD0100PA00X+004808Y+152564X0200Y         S0      
317GND              VIA   -    MD0100PA00X+003208Y+151764X0200Y    R090 S0      
317GND              VIA   -    MD0100PA00X+003208Y+152164X0200Y    R180 S0      
317GND              VIA   -    MD0100PA00X+003124Y+153210X0200Y    R180 S0      
317GND              VIA   -    MD0100PA00X+003208Y+152564X0200Y         S0      
317GND              VIA   -    MD0100PA00X+003524Y+153210X0200Y         S0      
317GND              VIA   -    MD0100PA00X+004020Y+151128X0200Y    R270 S0      
317GND              VIA   -    MD0100PA00X+004820Y+151128X0200Y         S0      
317GND              VIA   -    MD0100PA00X+004420Y+151128X0200Y    R180 S0      
317GND              VIA   -    MD0100PA00X+003220Y+151128X0200Y    R180 S0      
317GND              VIA   -    M      A01X+002567Y+148629X0200Y    R180 S2      
017GND              VIA   -    M      A18X+002567Y+148629X0260Y    R180 S2      
017GND                    -    MD0100PA00X+002567Y+148629                       
327GND              R6737 -2          A01X+002567Y+148872X0198Y0197R270 S1      
327GND              Y9    -4          A01X+001764Y+148965X0480Y0560     S1      
327GND              Y9    -2          A01X+001095Y+148099X0480Y0560     S1      
327GND              C4459 -2          A01X+001936Y+149678X0198Y0197     S1      
317GND              VIA   -    MD0100PA00X+002154Y+148965X0200Y    R270 S0      
317GND              VIA   -    MD0100PA00X+001936Y+149430X0200Y    R180 S0      
317GND              VIA   -    MD0100PA00X+002154Y+147966X0200Y    R270 S0      
317GND              VIA   -    MD0100PA00X+001361Y+147671X0200Y    R180 S0      
327GND              C4460 -2          A01X+000912Y+149678X0198Y0197R180 S1      
317GND              VIA   -    MD0100PA00X+000669Y+149678X0200Y    R090 S0      
317GND              VIA   -    MD0100PA00X+000657Y+155422X0200Y         S0      
327GND              R6288 -2          A01X+092390Y+032960X0180Y0200R180 S1      
327GND              R6287 -2          A01X+091208Y+032960X0180Y0200     S1      
317GND              VIA   -    MD0100PA00X+097690Y+084714X0200Y         S0      
317GND              VIA   -    MD0100PA00X+094512Y+032644X0200Y    R090 S0      
317GND              VIA   -    MD0100PA00X+093661Y+032606X0200Y    R090 S0      
317GND              VIA   -    MD0100PA00X+092390Y+033241X0200Y         S0      
317GND              VIA   -    MD0100PA00X+091208Y+033234X0200Y         S0      
317GND              VIA   -    MD0100PA00X+091791Y+032167X0200Y    R090 S0      
317GND              VIA   -    MD0100PA00X+091786Y+033145X0200Y    R090 S0      
317GND              VIA   -    MD0100PA00X+093262Y+033682X0200Y         S0      
327GND              R6285 -2          A01X+093514Y+033682X0180Y0200     S1      
317GND              VIA   -    MD0100PA00X+094981Y+033682X0200Y         S0      
327GND              R6286 -2          A01X+094694Y+033682X0180Y0200R180 S1      
317GND              VIA   -    MD0100PA00X+094097Y+033824X0200Y    R090 S0      
317GND              VIA   -    MD0100PA00X+094092Y+032896X0200Y    R090 S0      
317GND              VIA   -    MD0100PA00X+094560Y+034538X0200Y    R090 S0      
317GND              VIA   -    MD0100PA00X+093645Y+034534X0200Y    R090 S0      
317GND              VIA   -    MD0100PA00X+093040Y+034205X0200Y    R090 S0      
317GND              VIA   -    MD0100PA00X+092220Y+034205X0200Y    R090 S0      
317GND              VIA   -    MD0100PA00X+094958Y+033052X0200Y         S0      
327GND              R6723 -2          A01X+094694Y+033052X0180Y0200R180 S1      
317GND              VIA   -    MD0100PA00X+093239Y+033052X0200Y         S0      
327GND              R6724 -2          A01X+093514Y+033052X0180Y0200     S1      
317GND              VIA   -    MD0100PA00X+090942Y+032330X0200Y         S0      
327GND              R6725 -2          A01X+091208Y+032330X0180Y0200     S1      
317GND              VIA   -    MD0100PA00X+092680Y+032330X0200Y         S0      
327GND              R6726 -2          A01X+092390Y+032330X0180Y0200R180 S1      
317GND              VIA   -    MD0100PA00X+093961Y+031052X0200Y    R090 S0      
317GND              VIA   -    MD0100PA00X+093965Y+031747X0200Y    R090 S0      
317GND              VIA   -    MD0100PA00X+091321Y+033649X0200Y    R090 S0      
317GND              VIA   -    MD0100PA00X+092263Y+033661X0200Y    R090 S0      
317GND              VIA   -    MD0100PA00X+092185Y+034662X0200Y    R270 S0      
317GND              VIA   -    MD0100PA00X+091228Y+034388X0200Y    R270 S0      
317GND              VIA   -    MD0100PA00X+143250Y+151218X0200Y         S0      
327GND              Q247  -1          A01X+143250Y+151541X0240Y0240R180 S1      
317GND              VIA   -    MD0100PA00X+142306Y+150833X0200Y         S0      
327GND              Q247  -4          A01X+142659Y+150833X0240Y0240R180 S1      
317GND              VIA   -    MD0100PA00X+142526Y+155807X0200Y         S0      
327GND              Q246  -1          A01X+142808Y+155807X0240Y0240R090 S1      
317GND              VIA   -    MD0100PA00X+142370Y+156398X0200Y         S0      
327GND              Q246  -4          A01X+142100Y+156398X0240Y0240R090 S1      
317GND              VIA   -    MD0100PA00X+142556Y+153743X0200Y         S0      
327GND              Q245  -1          A01X+142845Y+153743X0240Y0240R090 S1      
317GND              VIA   -    MD0100PA00X+142424Y+154334X0200Y         S0      
327GND              Q245  -4          A01X+142137Y+154334X0240Y0240R090 S1      
317GND              VIA   -    MD0100PA00X+178656Y+147886X0200Y         S0      
327GND              Q243  -1          A01X+178306Y+147886X0240Y0240R270 S1      
317GND              VIA   -    MD0100PA00X+179388Y+147295X0200Y         S0      
327GND              Q243  -4          A01X+179014Y+147295X0240Y0240R270 S1      
317GND              VIA   -    MD0100PA00X+177987Y+144667X0200Y         S0      
327GND              Q244  -1          A01X+178318Y+144667X0240Y0240R270 S1      
317GND              VIA   -    MD0100PA00X+179398Y+144076X0200Y         S0      
327GND              Q244  -4          A01X+179026Y+144076X0240Y0240R270 S1      
317GND              VIA   -    MD0100PA00X+159746Y+145256X0200Y         S0      
327GND              Q242  -4          A01X+159746Y+145628X0240Y0240R180 S1      
317GND              VIA   -    MD0100PA00X+160336Y+146057X0200Y         S0      
327GND              Q242  -1          A01X+160336Y+146336X0240Y0240R180 S1      
317GND              VIA   -    MD0100PA00X+073558Y+086178X0200Y    R090 S0      
317GND              VIA   -    MD0100PA00X+155110Y+095910X0200Y         S0      
317GND              H143  -1   MD1660PA00X+084944Y+136772X3150Y    R090 S3      
317GND              VIA   -    MD0100PA00X+094907Y+136772X0200Y         S0      
317GND              VIA   -    MD0100PA00X+098186Y+136094X0200Y    R180 S0      
317GND              VIA   -    MD0100PA00X+098350Y+136968X0200Y         S0      
317GND              VIA   -    MD0100PA00X+098194Y+141386X0200Y    R180 S0      
317GND              VIA   -    MD0100PA00X+100461Y+155225X0200Y    R180 S0      
317GND              VIA   -    MD0100PA00X+100461Y+155525X0200Y    R180 S0      
317GND              VIA   -    MD0100PA00X+100461Y+155825X0200Y    R180 S0      
317GND              VIA   -    MD0100PA00X+100461Y+156125X0200Y    R180 S0      
317GND              VIA   -    MD0100PA00X+100761Y+155225X0200Y    R180 S0      
317GND              VIA   -    MD0100PA00X+100761Y+155525X0200Y    R180 S0      
317GND              VIA   -    MD0100PA00X+100761Y+155825X0200Y    R180 S0      
317GND              VIA   -    MD0100PA00X+100761Y+156125X0200Y    R180 S0      
317GND              VIA   -    MD0100PA00X+101965Y+157167X0200Y    R090 S0      
317GND              VIA   -    MD0100PA00X+101665Y+157167X0200Y    R090 S0      
317GND              VIA   -    MD0100PA00X+101365Y+157167X0200Y    R090 S0      
317GND              VIA   -    MD0100PA00X+101961Y+154782X0200Y    R090 S0      
317GND              VIA   -    MD0100PA00X+101661Y+154782X0200Y    R090 S0      
317GND              VIA   -    MD0100PA00X+101361Y+154782X0200Y    R090 S0      
317GND              VIA   -    MD0100PA00X+101065Y+157167X0200Y    R090 S0      
317GND              VIA   -    MD0100PA00X+101061Y+154782X0200Y    R090 S0      
327GND              C2848 -2          A01X+101878Y+084868X0198Y0197     S1      
327GND              C2849 -2          A01X+102170Y+084316X0400Y0500R180 S1      
327GND              U342  -TH         A01X+100134Y+084226X0690Y1050     S1      
327GND              C2851 -2          A01X+097955Y+084860X0198Y0197R180 S1      
327GND              C2850 -2          A01X+097670Y+084266X0400Y0500     S1      
327GND              C2491 -2          A01X+101828Y+083366X0198Y0197     S1      
327GND              R4434 -2          A01X+098163Y+083716X0198Y0197R180 S1      
317GND              VIA   -    MD0100PA00X+102524Y+084507X0200Y         S0      
317GND              VIA   -    MD0100PA00X+102522Y+084216X0200Y         S0      
317GND              VIA   -    M      A01X+102122Y+084871X0200Y         S2      
017GND              VIA   -    M      A18X+102122Y+084871X0260Y         S2      
017GND                    -    MD0100PA00X+102122Y+084871                       
317GND              VIA   -    MD0100PA00X+102070Y+083366X0200Y         S0      
317GND              VIA   -    MD0100PA00X+100037Y+083434X0200Y         S0      
317GND              VIA   -    MD0100PA00X+100289Y+083434X0200Y         S0      
317GND              VIA   -    MD0100PA00X+097920Y+083716X0200Y         S0      
317GND              VIA   -    MD0100PA00X+097428Y+083801X0200Y         S0      
317GND              VIA   -    MD0100PA00X+097680Y+083801X0200Y         S0      
327GND              U5    -E3         A01X+092074Y+085002X0160Y    R180 S1      
317GND              VIA   -    MD0100PA00X+040796Y+077020X0200Y    R270 S0      
317GND              VIA   -    MD0100PA00X+040830Y+075549X0200Y    R270 S0      
317GND              VIA   -    MD0100PA00X+041570Y+076247X0200Y    R270 S0      
317GND              VIA   -    MD0100PA00X+040091Y+076268X0200Y    R270 S0      
317GND              VIA   -    MD0100PA00X+178840Y+089507X0200Y    R270 S0      
317GND              VIA   -    MD0100PA00X+178066Y+090280X0200Y    R270 S0      
317GND              VIA   -    MD0100PA00X+177361Y+089528X0200Y    R270 S0      
317GND              VIA   -    MD0100PA00X+178100Y+088809X0200Y    R270 S0      
317GND              VIA   -    MD0100PA00X+097664Y+083502X0200Y         S0      
327GND              J69   -12         A01X+097251Y+136968X0240Y0950R270 S1      
317GND              VIA   -    MD0100PA00X+098050Y+136968X0200Y         S0      
327GND              J69   -1          A01X+095897Y+136772X0240Y0950R090 S1      
317GND              VIA   -    MD0100PA00X+095207Y+136772X0200Y         S0      
327GND              C4447 -2          A01X+101967Y+134492X0198Y0197R270 S1      
327GND              R6650 -2          A01X+101091Y+137273X0198Y0197R180 S1      
327GND              R6651 -2          A01X+101089Y+136353X0198Y0197R180 S1      
327GND              R6654 -2          A01X+101090Y+137675X0198Y0197R180 S1      
327GND              J69   -G2         A01X+096574Y+141386X0551Y2303R270 S1      
327GND              J69   -G1         A01X+096574Y+136094X0551Y2303R270 S1      
317GND              VIA   -    MD0100PA00X+100831Y+136353X0200Y         S0      
317GND              VIA   -    MD0100PA00X+100848Y+137273X0200Y         S0      
317GND              VIA   -    MD0100PA00X+100845Y+137675X0200Y         S0      
317GND              VIA   -    MD0100PA00X+102162Y+137322X0200Y         S0      
327GND              U437  -S          A01X+102547Y+137322X0320Y0360R270 S1      
317GND              VIA   -    MD0100PA00X+104259Y+134582X0200Y         S0      
327GND              U436  -2          A01X+103788Y+134820X0250Y0480R270 S1      
317GND              VIA   -    MD0100PA00X+101529Y+134492X0200Y         S0      
317GND              VIA   -    MD0100PA00X+049132Y+066729X0200Y         S0      
327GND              U438  -2          A01X+049132Y+067120X0140Y0440R180 S1      
317GND              VIA   -    MD0100PA00X+049463Y+065462X0200Y         S0      
327GND              C4451 -1          A01X+049137Y+065462X0198Y0197R090 S1      
317GND              VIA   -    MD0100PA00X+070360Y+069965X0200Y         S0      
327GND              U439  -2   M      A01X+069979Y+069965X0140Y0440R270 S1      
317GND              VIA   -    MD0100PA00X+071635Y+069948X0200Y         S0      
327GND              C4450 -1          A01X+071635Y+069672X0198Y0197R180 S1      
317GND              VIA   -    MD0100PA00X+057058Y+074980X0200Y         S0      
327GND              C4449 -1          A01X+057058Y+074708X0198Y0197R180 S1      
317GND              VIA   -    MD0100PA00X+055781Y+074781X0200Y         S0      
327GND              U440  -2   M      A01X+055396Y+074716X0140Y0440R270 S1      
317GND              VIA   -    MD0100PA00X+052016Y+075883X0200Y         S0      
327GND              C4448 -1          A01X+051741Y+075883X0198Y0197R090 S1      
317GND              VIA   -    MD0100PA00X+051719Y+077323X0200Y         S0      
327GND              U441  -2          A01X+051719Y+077713X0140Y0440R180 S1      
317GND              VIA   -    MD0100PA00X+142381Y+152425X0200Y    R270 S0      
327GND              R6711 -2          A01X+142637Y+152425X0198Y0197R180 S1      
317GND              VIA   -    MD0100PA00X+142218Y+149120X0200Y    R270 S0      
327GND              C4457 -2          A01X+142445Y+149120X0120Y0150R180 S1      
327GND              R6699 -2          A01X+143729Y+154356X0198Y0197R090 S1      
317GND              VIA   -    MD0100PA00X+143729Y+154612X0200Y    R180 S0      
327GND              C4455 -2          A01X+140424Y+154548X0120Y0150R090 S1      
317GND              VIA   -    MD0100PA00X+140424Y+154776X0200Y    R180 S0      
327GND              R6705 -2          A01X+143680Y+156624X0198Y0197R090 S1      
317GND              VIA   -    MD0100PA00X+143680Y+156880X0200Y    R180 S0      
327GND              C4456 -2          A01X+140375Y+156816X0120Y0150R090 S1      
317GND              VIA   -    MD0100PA00X+140375Y+157043X0200Y    R180 S0      
327GND              C4454 -2          A01X+180739Y+143862X0120Y0150R270 S1      
327GND              R6693 -2          A01X+177434Y+144054X0198Y0197R270 S1      
317GND              VIA   -    MD0100PA00X+180739Y+143634X0200Y         S0      
317GND              VIA   -    MD0100PA00X+177434Y+143798X0200Y         S0      
317GND              VIA   -    MD0100PA00X+180727Y+146854X0200Y         S0      
317GND              VIA   -    MD0100PA00X+177422Y+147016X0200Y         S0      
327GND              R6687 -2          A01X+177422Y+147272X0198Y0197R270 S1      
317GND              VIA   -    MD0100PA00X+083208Y+146107X0200Y         S0      
327GND              PC1   -2          A01X+082898Y+146246X0198Y0197     S1      
317GND              VIA   -    MD0100PA00X+160674Y+147424X0200Y         S0      
327GND              R6682 -2          A01X+160469Y+147197X0198Y0197     S1      
317GND              VIA   -    MD0100PA00X+159722Y+143701X0200Y         S0      
327GND              C4452 -2          A01X+159394Y+143701X0120Y0150R270 S1      
327GND              Q240  -S          A01X+071494Y+074191X0320Y0360R090 S1      
327GND              U52   -3          A01X+074036Y+074368X0240Y0420R090 S1      
327GND              Q241  -S          A18X+113962Y+077543X0320Y0360R090 S2      
327GND              R6580 -2          A01X+103372Y+094981X0198Y0197R090 S1      
327GND              R6586 -2          A01X+180836Y+098065X0198Y0197R090 S1      
327GND              R6567 -2          A01X+007505Y+083871X0198Y0197R090 S1      
327GND              R6574 -2          A01X+059210Y+095280X0198Y0197R090 S1      
327GND              R6590 -2          A01X+095400Y+085358X0198Y0197R090 S1      
327GND              R6592 -2          A01X+094720Y+083852X0198Y0197R270 S1      
327GND              R6595 -2          A01X+093272Y+089818X0198Y0197R090 S1      
327GND              R6596 -2   M      A01X+093630Y+088751X0198Y0197R180 S1      
317GND              H78   -9   MD0220PA00X+108051Y+148091X0300Y         S3      
317GND              H78   -8   MD0220PA00X+107047Y+147675X0300Y         S3      
317GND              H78   -7   MD0220PA00X+106043Y+148091X0300Y         S3      
317GND              H78   -6   MD0220PA00X+105627Y+149094X0300Y         S3      
317GND              H78   -5   MD0220PA00X+106043Y+150098X0300Y         S3      
317GND              H78   -4   MD0220PA00X+107047Y+150514X0300Y         S3      
317GND              H78   -3   MD0220PA00X+108051Y+150098X0300Y         S3      
317GND              H78   -2   MD0220PA00X+108467Y+149094X0300Y         S3      
317GND              H80   -9   MD0220PA00X+078051Y+148091X0300Y         S3      
317GND              H80   -8   MD0220PA00X+077047Y+147675X0300Y         S3      
317GND              H80   -7   MD0220PA00X+076043Y+148091X0300Y         S3      
317GND              H80   -2   MD0220PA00X+078467Y+149094X0300Y         S3      
317GND              H80   -6   MD0220PA00X+075627Y+149094X0300Y         S3      
317GND              H80   -3   MD0220PA00X+078051Y+150098X0300Y         S3      
317GND              H80   -4   MD0220PA00X+077047Y+150514X0300Y         S3      
317GND              H80   -5   MD0220PA00X+076043Y+150098X0300Y         S3      
327GND              PD1   -A          A01X+101564Y+155627X0950Y1300     S1      
317GND              VIA   -    MD0100PA00X+074266Y+144573X0200Y         S0      
327GND              PJ1   -1          A01X+073670Y+145166X0400Y1090R270 S1      
317GND              VIA   -    MD0100PA00X+080070Y+142678X0200Y         S0      
327GND              R495  -2          A18X+080306Y+142914X0198Y0197     S2      
317GND              VIA   -    MD0100PA00X+101966Y+156577X0200Y    R090 S0      
317GND              VIA   -    MD0100PA00X+101666Y+156577X0200Y    R090 S0      
317GND              VIA   -    MD0100PA00X+101366Y+156577X0200Y    R090 S0      
317GND              VIA   -    MD0100PA00X+101066Y+156577X0200Y    R090 S0      
317GND              VIA   -    MD0100PA00X+101966Y+156877X0200Y    R090 S0      
317GND              VIA   -    MD0100PA00X+101666Y+156877X0200Y    R090 S0      
317GND              VIA   -    MD0100PA00X+101366Y+156877X0200Y    R090 S0      
317GND              VIA   -    MD0100PA00X+101066Y+156877X0200Y    R090 S0      
327GND              PR1   -1          A01X+078019Y+144344X0198Y0197     S1      
317GND              VIA   -    MD0100PA00X+077711Y+144227X0200Y         S0      
327GND              C2405 -1          A18X+098595Y+087661X0198Y0197     S2      
327GND              C2406 -1          A18X+100974Y+087919X0198Y0197R180 S2      
317GND              VIA   -    MD0100PA00X+148145Y+091157X0200Y         S0      
327GND              PR286 -2          A01X+124922Y+023611X0198Y0197R090 S1      
327GND              R6255 -1          A01X+079697Y+139460X0198Y0197R090 S1      
317GND              VIA   -    MD0100PA00X+080063Y+139275X0200Y         S0      
317GND              VIA   -    MD0100PA00X+108348Y+152343X0200Y    R270 S0      
327GND              PC6604-2          A01X+108611Y+152343X0198Y0197R270 S1      
317GND              VIA   -    MD0100PA00X+097886Y+136094X0200Y    R180 S0      
317GND              VIA   -    MD0100PA00X+078938Y+133123X0200Y         S0      
317GND              VIA   -    MD0100PA00X+078938Y+133403X0200Y         S0      
317GND              VIA   -    MD0100PA00X+079218Y+133123X0200Y         S0      
317GND              VIA   -    MD0100PA00X+079218Y+133403X0200Y         S0      
317GND              VIA   -    MD0100PA00X+024760Y+084850X0200Y         S0      
317GND              VIA   -    MD0100PA00X+026970Y+088460X0200Y         S0      
317GND              VIA   -    MD0100PA00X+026990Y+091420X0200Y         S0      
317GND              VIA   -    MD0100PA00X+027010Y+094650X0200Y         S0      
327GND              J72   -1   M      A01X+023806Y+091420X0500Y1350R090 S1      
327GND              J73   -1   M      A01X+031946Y+094940X0500Y1350R090 S1      
327GND              J70   -1   M      A01X+031846Y+087890X0500Y1350R090 S1      
317GND              VIA   -    MD0100PA00X+040928Y+074132X0200Y         S0      
327GND              U435  -25         A01X+040928Y+074528X0110Y0340     S1      
317GND              VIA   -    MD0100PA00X+040090Y+075540X0200Y    R180 S0      
317GND              VIA   -    MD0100PA00X+041570Y+077020X0200Y    R180 S0      
317GND              VIA   -    MD0100PA00X+040090Y+077010X0200Y    R180 S0      
317GND              VIA   -    MD0100PA00X+041570Y+075540X0200Y    R180 S0      
327GND              U435  -TH  M      A01X+040830Y+076280X1680Y1680     S1      
317GND              VIA   -    MD0100PA00X+040660Y+078900X0200Y    R270 S0      
317GND              VIA   -    MD0100PA00X+040840Y+079220X0200Y    R270 S0      
327GND              C4445 -2          A01X+040510Y+079380X0280Y0320R270 S1      
327GND              C4446 -2          A01X+040378Y+078900X0198Y0197     S1      
327GND              U435  -59         A01X+040338Y+078032X0110Y0340R180 S1      
317GND              VIA   -    MD0100PA00X+040840Y+079520X0200Y    R270 S0      
317GND              VIA   -    MD0100PA00X+037980Y+077800X0200Y    R180 S0      
317GND              VIA   -    MD0100PA00X+037630Y+077980X0200Y    R180 S0      
317GND              VIA   -    MD0100PA00X+037310Y+077961X0200Y    R180 S0      
327GND              C4444 -2          A01X+037980Y+077518X0198Y0197R090 S1      
327GND              U435  -2          A01X+039078Y+077560X0110Y0340R270 S1      
327GND              C4443 -2          A01X+037480Y+077650X0280Y0320     S1      
317GND              VIA   -    MD0100PA00X+039355Y+079006X0200Y    R180 S0      
317GND              VIA   -    MD0100PA00X+038769Y+079006X0200Y    R180 S0      
327GND              J71   -1   M      A01X+023806Y+084690X0500Y1350R090 S1      
317GND              VIA   -    MD0100PA00X+110762Y+160675X0200Y         S0      
317GND              VIA   -    MD0100PA00X+097894Y+141386X0200Y    R180 S0      
317GND              VIA   -    MD0100PA00X+103034Y+138860X0200Y         S0      
317GND              VIA   -    MD0100PA00X+103034Y+139160X0200Y         S0      
317GND              VIA   -    MD0100PA00X+102434Y+138860X0200Y         S0      
317GND              VIA   -    MD0100PA00X+102434Y+139160X0200Y         S0      
317GND              VIA   -    MD0100PA00X+102734Y+139160X0200Y         S0      
317GND              VIA   -    MD0100PA00X+102734Y+138860X0200Y         S0      
317GND              VIA   -    MD0100PA00X+101834Y+138860X0200Y         S0      
317GND              VIA   -    MD0100PA00X+101834Y+139160X0200Y         S0      
317GND              VIA   -    MD0100PA00X+102134Y+139160X0200Y         S0      
317GND              VIA   -    MD0100PA00X+102134Y+138860X0200Y         S0      
317GND              VIA   -    MD0100PA00X+101534Y+138860X0200Y         S0      
317GND              VIA   -    MD0100PA00X+101534Y+139160X0200Y         S0      
317GND              VIA   -    MD0100PA00X+101234Y+139160X0200Y         S0      
317GND              VIA   -    MD0100PA00X+101234Y+138860X0200Y         S0      
317GND              VIA   -    MD0100PA00X+100934Y+138860X0200Y         S0      
317GND              VIA   -    MD0100PA00X+100934Y+139160X0200Y         S0      
327GND              PD2   -1          A01X+102386Y+139614X0500Y0560R270 S1      
327GND              PD2   -2          A01X+101567Y+139614X0500Y0560R270 S1      
317GND              VIA   -    MD0100PA00X+100621Y+139766X0200Y         S0      
327GND              PC6606-2   M      A01X+100205Y+139766X0280Y0320R180 S1      
327GND              J66   -1          A01X+163458Y+096212X0500Y1350R090 S1      
327GND              J65   -1          A01X+158478Y+092661X0500Y1350R090 S1      
327GND              J68   -1          A01X+163515Y+089135X0500Y1350R090 S1      
317GND              VIA   -    MD0100PA00X+164513Y+092926X0200Y         S0      
317GND              VIA   -    MD0100PA00X+164430Y+089135X0200Y         S0      
317GND              VIA   -    MD0100PA00X+164534Y+096212X0200Y         S0      
317GND              VIA   -    MD0100PA00X+178431Y+092460X0200Y    R090 S0      
317GND              VIA   -    MD0100PA00X+178626Y+093063X0200Y    R090 S0      
317GND              VIA   -    MD0100PA00X+178626Y+092763X0200Y    R090 S0      
327GND              C4441 -2          A01X+178305Y+092925X0280Y0320R270 S1      
327GND              C4439 -2          A01X+178154Y+092455X0198Y0197     S1      
327GND              U434  -59         A01X+177608Y+091292X0110Y0340R180 S1      
317GND              VIA   -    MD0100PA00X+175075Y+091078X0200Y         S0      
327GND              C4442 -2          A01X+174627Y+090921X0280Y0320     S1      
327GND              C4440 -2          A01X+175090Y+090798X0198Y0197R090 S1      
327GND              U434  -2          A01X+176348Y+090820X0110Y0340R270 S1      
317GND              VIA   -    MD0100PA00X+174794Y+091252X0200Y         S0      
317GND              VIA   -    MD0100PA00X+174494Y+091252X0200Y         S0      
317GND              VIA   -    MD0100PA00X+176382Y+092624X0200Y    R180 S0      
317GND              VIA   -    MD0100PA00X+177068Y+092632X0200Y    R180 S0      
317GND              VIA   -    MD0100PA00X+109990Y+153570X0200Y         S0      
327GND              PU6601-5          A01X+109934Y+154015X0170Y0590     S1      
317GND              VIA   -    MD0100PA00X+178260Y+087450X0200Y         S0      
327GND              U434  -25         A01X+178198Y+087788X0110Y0340     S1      
317GND              VIA   -    MD0100PA00X+177360Y+088810X0200Y    R270 S0      
317GND              VIA   -    MD0100PA00X+178830Y+090280X0200Y    R270 S0      
317GND              VIA   -    MD0100PA00X+177360Y+090280X0200Y    R270 S0      
327GND              U434  -TH  M      A01X+178100Y+089540X1680Y1680     S1      
317GND              VIA   -    MD0100PA00X+178840Y+088810X0200Y    R270 S0      
327GND              PC258 -2          A01X+092198Y+112564X0630Y1190R270 S1      
327GND              PC259 -2          A01X+097161Y+111910X0630Y1190R090 S1      
327GND              PC238 -2          A01X+085800Y+112564X0630Y1190R270 S1      
327GND              PC239 -2          A01X+090750Y+111910X0630Y1190R090 S1      
327GND              PC217 -2          A01X+001131Y+111663X0630Y1190R270 S1      
327GND              PC218 -2          A01X+006094Y+111010X0630Y1190R090 S1      
327GND              C4006 -2          A01X+079161Y+159644X0198Y0197R270 S1      
317GND              VIA   -    MD0100PA00X+079161Y+159371X0200Y    R180 S0      
327GND              Q123  -1          A01X+077594Y+159826X0170Y0240     S1      
317GND              VIA   -    MD0100PA00X+077466Y+160101X0200Y    R180 S0      
327GND              Q123  -4          A01X+078106Y+160574X0170Y0240     S1      
317GND              VIA   -    MD0100PA00X+078154Y+160284X0200Y    R180 S0      
327GND              C3990 -1          A01X+077703Y+159257X0198Y0197R270 S1      
317GND              VIA   -    MD0100PA00X+077703Y+159522X0200Y    R180 S0      
327GND              R6253 -2          A01X+078745Y+159646X0198Y0197R270 S1      
317GND              VIA   -    MD0100PA00X+078745Y+159359X0200Y    R180 S0      
327GND              Q125  -S          A01X+073936Y+161701X0240Y0320R090 S1      
317GND              VIA   -    MD0100PA00X+073588Y+161701X0200Y    R180 S0      
327GND              R4419 -1          A01X+074892Y+161494X0198Y0197R270 S1      
317GND              VIA   -    MD0100PA00X+074892Y+161771X0200Y    R180 S0      
317GND              VIA   -    MD0100PA00X+074064Y+158688X0200Y    R180 S0      
327GND              U338  -2          A01X+074596Y+159442X0250Y0480R180 S1      
327GND              R4418 -1          A01X+075114Y+158374X0198Y0197R090 S1      
317GND              VIA   -    MD0100PA00X+075114Y+158134X0200Y    R180 S0      
327GND              U340  -3          A01X+076728Y+159501X0220Y0530     S1      
317GND              VIA   -    M      A01X+076731Y+159916X0200Y    R090 S2      
017GND              VIA   -    M      A18X+076731Y+159916X0260Y    R090 S2      
017GND                    -    MD0100PA00X+076731Y+159916                       
317GND              VIA   -    M      A01X+075636Y+161692X0200Y    R090 S2      
017GND              VIA   -    M      A18X+075636Y+161692X0260Y    R090 S2      
017GND                    -    MD0100PA00X+075636Y+161692                       
327GND              C2846 -2          A01X+075945Y+161692X0198Y0197R090 S1      
317GND              VIA   -    MD0100PA00X+081665Y+137761X0200Y    R270 S0      
327GND              C3869 -2          A01X+081415Y+137761X0198Y0197R270 S1      
317GND              VIA   -    MD0100PA00X+080632Y+140166X0200Y    R270 S0      
327GND              U415  -3          A01X+080632Y+139751X0220Y0530R180 S1      
317GND              VIA   -    MD0100PA00X+109371Y+158558X0200Y    R090 S0      
327GND              C2704 -1          A01X+109623Y+158558X0198Y0197R270 S1      
327GND              U146  -2          A01X+109626Y+156693X0140Y0440     S1      
317GND              VIA   -    MD0100PA00X+109626Y+156228X0200Y    R090 S0      
327GND              U308  -4          A01X+109117Y+162152X0140Y0520R180 S1      
317GND              VIA   -    MD0100PA00X+109075Y+161742X0200Y    R090 S0      
327GND              PR7141-1          A18X+049650Y+102816X0198Y0197     S2      
317GND              VIA   -    MD0100PA00X+183191Y+099288X0200Y         S0      
317GND              VIA   -    MD0100PA00X+182307Y+099283X0200Y         S0      
327GND              C3561 -2          A01X+151686Y+103017X0280Y0320R270 S1      
327GND              C3567 -2          A01X+151686Y+101757X0280Y0320R270 S1      
327GND              C3576 -2          A01X+149334Y+101249X0120Y0150R270 S1      
327GND              C3596 -2          A01X+148152Y+101486X0280Y0320R180 S1      
327GND              C3559 -2          A01X+148893Y+101146X0280Y0320R180 S1      
327GND              C3572 -2          A01X+149844Y+101037X0280Y0320R090 S1      
327GND              C3587 -2          A01X+148042Y+100535X0280Y0320R270 S1      
327GND              C3588 -2          A01X+147940Y+100976X0120Y0150     S1      
327GND              C4426 -2          A01X+102182Y+093372X0400Y0500     S1      
327GND              U432  -TH         A01X+102122Y+094472X0690Y1050R180 S1      
327GND              C4416 -2          A01X+006315Y+082262X0400Y0500     S1      
327GND              U430  -TH         A01X+006255Y+083361X0690Y1050R180 S1      
327GND              C4421 -2          A01X+058020Y+093671X0400Y0500     S1      
327GND              U431  -TH         A01X+057960Y+094770X0690Y1050R180 S1      
327GND              C3245 -2          A01X+055540Y+103509X0120Y0150R090 S1      
327GND              C3244 -2          A01X+055396Y+102766X0280Y0320R090 S1      
327GND              C3420 -2          A01X+101717Y+103509X0120Y0150R090 S1      
327GND              C3419 -2          A01X+101252Y+103509X0120Y0150R090 S1      
327GND              C3418 -2          A01X+101104Y+102766X0280Y0320R090 S1      
327GND              C3071 -2          A18X+009784Y+102414X0120Y0150     S2      
327GND              C3072 -2          A18X+009791Y+102103X0120Y0150     S2      
317GND              VIA   -    MD0100PA00X+092961Y+085867X0180Y    R270 S0      
317GND              VIA   -    MD0100PA00X+180586Y+098076X0200Y    R270 S0      
317GND              VIA   -    MD0100PA00X+179226Y+096296X0200Y    R270 S0      
317GND              VIA   -    MD0100PA00X+178476Y+096466X0200Y    R270 S0      
317GND              VIA   -    M      A01X+178126Y+096466X0200Y    R270 S2      
017GND              VIA   -    M      A18X+178126Y+096466X0260Y    R270 S2      
017GND                    -    MD0100PA00X+178126Y+096466                       
317GND              VIA   -    MD0100PA00X+179796Y+096876X0200Y    R270 S0      
317GND              VIA   -    MD0100PA00X+179416Y+096876X0200Y    R270 S0      
317GND              VIA   -    MD0100PA00X+179356Y+098236X0200Y    R270 S0      
317GND              VIA   -    MD0100PA00X+179816Y+098236X0200Y    R270 S0      
327GND              C4432 -2          A18X+179849Y+096466X0198Y0197     S2      
317GND              VIA   -    M      A01X+100662Y+093382X0200Y    R270 S2      
017GND              VIA   -    M      A18X+100662Y+093382X0260Y    R270 S2      
017GND                    -    MD0100PA00X+100662Y+093382                       
317GND              VIA   -    MD0100PA00X+101012Y+093382X0200Y    R270 S0      
317GND              VIA   -    MD0100PA00X+101762Y+093212X0200Y    R270 S0      
317GND              VIA   -    MD0100PA00X+102332Y+093792X0200Y    R270 S0      
317GND              VIA   -    MD0100PA00X+101952Y+093792X0200Y    R270 S0      
327GND              C4427 -2          A18X+102384Y+093382X0198Y0197     S2      
317GND              VIA   -    MD0100PA00X+101892Y+095152X0200Y    R270 S0      
327GND              C4428 -2          A01X+101799Y+095422X0198Y0197     S1      
327GND              C4425 -2          A01X+100762Y+093782X0400Y0500R090 S1      
327GND              C4424 -2          A01X+101482Y+093234X0198Y0197R270 S1      
317GND              VIA   -    MD0100PA00X+102352Y+095152X0200Y    R270 S0      
317GND              VIA   -    MD0100PA00X+103122Y+094992X0200Y    R270 S0      
317GND              VIA   -    M      A01X+056500Y+093681X0200Y    R270 S2      
017GND              VIA   -    M      A18X+056500Y+093681X0260Y    R270 S2      
017GND                    -    MD0100PA00X+056500Y+093681                       
317GND              VIA   -    MD0100PA00X+056850Y+093681X0200Y    R270 S0      
317GND              VIA   -    MD0100PA00X+057600Y+093511X0200Y    R270 S0      
317GND              VIA   -    MD0100PA00X+058170Y+094091X0200Y    R270 S0      
317GND              VIA   -    MD0100PA00X+057790Y+094091X0200Y    R270 S0      
327GND              C4422 -2          A18X+058223Y+093681X0198Y0197     S2      
317GND              VIA   -    MD0100PA00X+057730Y+095451X0200Y    R270 S0      
327GND              C4423 -2          A01X+057638Y+095721X0198Y0197     S1      
327GND              C4420 -2          A01X+056600Y+094081X0400Y0500R090 S1      
327GND              C4419 -2          A01X+057320Y+093532X0198Y0197R270 S1      
317GND              VIA   -    MD0100PA00X+058190Y+095451X0200Y    R270 S0      
317GND              VIA   -    MD0100PA00X+058960Y+095291X0200Y    R270 S0      
317GND              VIA   -    M      A01X+004795Y+082272X0200Y    R270 S2      
017GND              VIA   -    M      A18X+004795Y+082272X0260Y    R270 S2      
017GND                    -    MD0100PA00X+004795Y+082272                       
317GND              VIA   -    MD0100PA00X+005145Y+082272X0200Y    R270 S0      
317GND              VIA   -    MD0100PA00X+005895Y+082102X0200Y    R270 S0      
317GND              VIA   -    MD0100PA00X+006465Y+082682X0200Y    R270 S0      
317GND              VIA   -    MD0100PA00X+006085Y+082682X0200Y    R270 S0      
327GND              C4417 -2          A18X+006517Y+082272X0198Y0197     S2      
317GND              VIA   -    MD0100PA00X+006025Y+084042X0200Y    R270 S0      
327GND              C4418 -2          A01X+005932Y+084312X0198Y0197     S1      
327GND              C4415 -2          A01X+004895Y+082672X0400Y0500R090 S1      
327GND              C4414 -2          A01X+005615Y+082123X0198Y0197R270 S1      
317GND              VIA   -    MD0100PA00X+006485Y+084042X0200Y    R270 S0      
317GND              VIA   -    MD0100PA00X+007255Y+083882X0200Y    R270 S0      
317GND              VIA   -    MD0100PA00X+093370Y+088751X0200Y         S0      
327GND              C4437 -2          A01X+093630Y+088379X0198Y0197R180 S1      
317GND              VIA   -    MD0100PA00X+093819Y+090085X0200Y         S0      
327GND              C4436 -2   M      A01X+093662Y+089818X0198Y0197R090 S1      
327GND              C194  -2          A01X+094374Y+084773X0198Y0197R090 S1      
327GND              R477  -2          A01X+094757Y+084664X0198Y0197R180 S1      
327GND              JPEX2 -10         A01X+097283Y+090030X0200Y0600R090 S1      
327GND              C4282 -2          A01X+086645Y+099783X0280Y0320R180 S1      
327GND              C4286 -2          A01X+090795Y+099829X0400Y0500R090 S1      
317GND              VIA   -    MD0100PA00X+084852Y+101686X0200Y         S0      
327GND              C4230 -2          A01X+006834Y+098501X0400Y0500R090 S1      
327GND              C4244 -2          A01X+005791Y+098518X0400Y0500R090 S1      
327GND              C4229 -2          A01X+004723Y+098652X0280Y0320R180 S1      
327GND              C4228 -2          A01X+004179Y+098652X0280Y0320R180 S1      
327GND              C4243 -2          A01X+002546Y+098652X0280Y0320R180 S1      
327GND              C4227 -2          A01X+003629Y+098652X0280Y0320R180 S1      
327GND              C4226 -2          A01X+003090Y+098652X0280Y0320R180 S1      
327GND              C4242 -2          A01X+002001Y+098652X0280Y0320R180 S1      
327GND              C4241 -2          A01X+001451Y+098652X0280Y0320R180 S1      
327GND              C4240 -2          A01X+000879Y+098652X0280Y0320R180 S1      
327GND              C4231 -2          A01X+006156Y+097130X0400Y0500R090 S1      
327GND              C4245 -2          A01X+005060Y+097130X0400Y0500R090 S1      
327GND              C4339 -2          A01X+091375Y+099883X0280Y0320R180 S1      
327GND              C4287 -2          A01X+085212Y+098533X0400Y0500R090 S1      
327GND              C4300 -2          A01X+085924Y+098533X0400Y0500R090 S1      
327GND              C4301 -2          A01X+086614Y+098533X0400Y0500R090 S1      
327GND              C4342 -2          A01X+096703Y+099654X0400Y0500R090 S1      
327GND              C4343 -2          A01X+094828Y+099644X0400Y0500R090 S1      
327GND              C4356 -2          A01X+095516Y+099649X0400Y0500R090 S1      
327GND              C4357 -2          A01X+097913Y+099726X0400Y0500R090 S1      
317GND              VIA   -    MD0100PA00X+035885Y+151631X0200Y         S0      
317GND              VIA   -    MD0100PA00X+035885Y+150684X0200Y         S0      
317GND              VIA   -    MD0100PA00X+035885Y+151158X0200Y         S0      
327GND              C4322 -2          A18X+137502Y+124751X0120Y0150R180 S2      
317GND              VIA   -    MD0100PA00X+090930Y+101464X0200Y         S0      
317GND              VIA   -    MD0100PA00X+006937Y+106339X0200Y         S0      
317GND              VIA   -    MD0100PA00X+006926Y+105315X0200Y         S0      
327GND              C4348 -2          A18X+095142Y+109806X0120Y0150R270 S2      
327GND              C4332 -2          A18X+094070Y+110082X0280Y0320     S2      
327GND              C4344 -2          A18X+093543Y+110092X0280Y0320     S2      
327GND              C4330 -2          A18X+094589Y+110082X0280Y0320     S2      
327GND              C4346 -2          A18X+093017Y+110093X0280Y0320     S2      
327GND              C4345 -2          A18X+092511Y+110091X0280Y0320     S2      
327GND              C4349 -2          A18X+092111Y+109002X0120Y0150     S2      
327GND              C4347 -2          A18X+092119Y+107982X0280Y0320R090 S2      
327GND              C4331 -2          A18X+092130Y+108517X0280Y0320R090 S2      
327GND              C4333 -2          A18X+092121Y+107437X0280Y0320R090 S2      
327GND              C4274 -2          A18X+089966Y+107451X0280Y0320R270 S2      
317GND              VIA   -    MD0100PA00X+000611Y+106532X0200Y    R270 S0      
317GND              VIA   -    MD0100PA00X+000611Y+107061X0200Y    R270 S0      
317GND              VIA   -    MD0100PA00X+000616Y+107599X0200Y    R270 S0      
317GND              VIA   -    MD0100PA00X+000605Y+108130X0200Y    R270 S0      
317GND              VIA   -    MD0100PA00X+000606Y+108655X0200Y    R270 S0      
317GND              VIA   -    MD0100PA00X+000606Y+109196X0200Y    R270 S0      
327GND              C4234 -2          A18X+000917Y+108653X0280Y0320R090 S2      
327GND              C4235 -2          A18X+000917Y+109194X0280Y0320R090 S2      
327GND              C4233 -2          A18X+000917Y+108129X0280Y0320R090 S2      
327GND              C4232 -2          A18X+000928Y+107597X0280Y0320R090 S2      
327GND              C4219 -2          A18X+000922Y+107059X0280Y0320R090 S2      
327GND              C4220 -2          A18X+000922Y+106530X0280Y0320R090 S2      
327GND              C4222 -2          A18X+003594Y+109382X0120Y0150R180 S2      
327GND              C4236 -2          A18X+003705Y+108264X0120Y0150R180 S2      
327GND              C4237 -2          A18X+003599Y+109069X0120Y0150R180 S2      
327GND              C4223 -2          A18X+004295Y+107303X0120Y0150R180 S2      
327GND              C4221 -2          A18X+005294Y+106477X0280Y0320R270 S2      
327GND              C4218 -2          A18X+003949Y+108673X0280Y0320R270 S2      
317GND              VIA   -    MD0100PA00X+176474Y+109788X0200Y         S0      
317GND              VIA   -    MD0100PA00X+176474Y+110193X0200Y         S0      
327GND              C4388 -2          A18X+176812Y+110116X0280Y0320R090 S2      
327GND              C4402 -2          A18X+176822Y+109580X0280Y0320R090 S2      
327GND              C4387 -2          A18X+176812Y+108611X0280Y0320R090 S2      
327GND              C4386 -2          A18X+176819Y+108087X0280Y0320R090 S2      
327GND              C4405 -2          A18X+176986Y+109084X0120Y0150     S2      
327GND              C4404 -2          A18X+176986Y+107672X0120Y0150     S2      
327GND              C4391 -2          A18X+176994Y+107361X0120Y0150     S2      
327GND              C4390 -2          A18X+179159Y+109125X0120Y0150R180 S2      
327GND              C4403 -2          A18X+180818Y+107448X0280Y0320R270 S2      
327GND              C4401 -2          A18X+178934Y+110108X0280Y0320R270 S2      
327GND              C4400 -2          A18X+179459Y+109563X0280Y0320R270 S2      
317GND              VIA   -    MD0100PA00X+181230Y+107569X0200Y         S0      
327GND              C4389 -2          A01X+180876Y+107569X0280Y0320R270 S1      
317GND              VIA   -    MD0100PA00X+085000Y+109107X0200Y         S0      
317GND              VIA   -    MD0100PA00X+085002Y+109518X0200Y         S0      
327GND              C4293 -2          A18X+087000Y+110301X0120Y0150R270 S2      
327GND              C4279 -2          A18X+087326Y+110306X0120Y0150R270 S2      
327GND              C4292 -2          A18X+087688Y+110306X0120Y0150R270 S2      
327GND              C4290 -2          A18X+085398Y+110073X0280Y0320R090 S2      
327GND              C4291 -2          A18X+085403Y+109472X0280Y0320R090 S2      
327GND              C4275 -2          A18X+085405Y+108926X0280Y0320R090 S2      
327GND              C4277 -2          A18X+085419Y+107851X0280Y0320R090 S2      
327GND              C4276 -2          A18X+085405Y+108392X0280Y0320R090 S2      
327GND              C4288 -2          A18X+085421Y+107330X0280Y0320R090 S2      
327GND              C4278 -2          A18X+088326Y+110070X0120Y0150R180 S2      
327GND              C4289 -2          A18X+088745Y+109344X0280Y0320R270 S2      
317GND              VIA   -    MD0100PA00X+090137Y+107807X0200Y         S0      
317GND              VIA   -    MD0100PA00X+089782Y+107804X0200Y         S0      
327GND              C4281 -2          A01X+089958Y+107611X0120Y0150R090 S1      
327GND              C4295 -2          A01X+090299Y+107608X0120Y0150R090 S1      
327GND              C4294 -2          A01X+090612Y+107610X0120Y0150R090 S1      
327GND              C4280 -2          A01X+089637Y+107608X0120Y0150R090 S1      
317GND              VIA   -    MD0100PA00X+096981Y+099303X0200Y         S0      
327GND              C4299 -2          A01X+090072Y+099783X0280Y0320R180 S1      
327GND              C4298 -2          A01X+089599Y+099783X0280Y0320R180 S1      
327GND              C4352 -2          A01X+097308Y+099766X0280Y0320R180 S1      
327GND              C4353 -2          A01X+096111Y+099748X0280Y0320R180 S1      
327GND              C4341 -2          A01X+094226Y+099783X0280Y0320R180 S1      
327GND              C4354 -2          A01X+093142Y+099783X0280Y0320R180 S1      
327GND              C4340 -2          A01X+093687Y+099783X0280Y0320R180 S1      
327GND              C4338 -2          A01X+092597Y+099783X0280Y0320R180 S1      
327GND              C4355 -2          A01X+092048Y+099783X0280Y0320R180 S1      
327GND              C4297 -2          A01X+089107Y+099783X0280Y0320R180 S1      
327GND              C4296 -2          A01X+088622Y+099783X0280Y0320R180 S1      
327GND              C4285 -2          A01X+088128Y+099783X0280Y0320R180 S1      
327GND              C4284 -2          A01X+087628Y+099783X0280Y0320R180 S1      
327GND              C4283 -2          A01X+087139Y+099783X0280Y0320R180 S1      
327GND              C4334 -2          A01X+091928Y+108872X0120Y0150R180 S1      
327GND              C4335 -2          A01X+091930Y+108083X0120Y0150R180 S1      
327GND              C4361 -2          A01X+144066Y+121126X0280Y0320R180 S1      
327GND              C4360 -2          A01X+141495Y+121142X0280Y0320R180 S1      
317GND              VIA   -    MD0100PA00X+140402Y+128529X0200Y         S0      
317GND              VIA   -    MD0100PA00X+141590Y+128259X0200Y         S0      
317GND              VIA   -    MD0100PA00X+139049Y+128547X0200Y         S0      
317GND              VIA   -    MD0100PA00X+138599Y+128547X0200Y         S0      
327GND              C4371 -2          A18X+144219Y+127914X0280Y0320     S2      
327GND              C4370 -2          A18X+143625Y+127914X0280Y0320     S2      
327GND              C4382 -2          A18X+141828Y+127914X0280Y0320     S2      
327GND              C4385 -2          A18X+142485Y+127914X0280Y0320     S2      
327GND              C4384 -2          A18X+143034Y+127914X0280Y0320     S2      
327GND              C4369 -2          A18X+140080Y+128365X0280Y0320     S2      
327GND              C4383 -2          A18X+140723Y+128375X0280Y0320     S2      
327GND              C4368 -2          A18X+141239Y+128376X0280Y0320     S2      
327GND              C4366 -2          A18X+138550Y+128223X0280Y0320     S2      
327GND              C4380 -2          A18X+139065Y+128220X0280Y0320     S2      
327GND              C4381 -2          A18X+139567Y+128220X0280Y0320     S2      
327GND              C4367 -2          A18X+138031Y+128218X0280Y0320     S2      
327GND              C4363 -2          A18X+144280Y+121422X0120Y0150R090 S2      
327GND              C4362 -2          A18X+144590Y+121425X0120Y0150R090 S2      
327GND              C4377 -2          A18X+143434Y+121422X0120Y0150R090 S2      
327GND              C4376 -2          A18X+142094Y+121422X0120Y0150R090 S2      
327GND              C4372 -2          A18X+143836Y+121211X0280Y0320R180 S2      
327GND              C4373 -2          A18X+143013Y+121211X0280Y0320R180 S2      
327GND              C4358 -2          A18X+142486Y+121211X0280Y0320R180 S2      
327GND              C4359 -2          A18X+141143Y+121211X0280Y0320R180 S2      
327GND              C4374 -2          A18X+141658Y+121211X0280Y0320R180 S2      
327GND              C4375 -2          A18X+140308Y+121211X0280Y0320R180 S2      
327GND              C4364 -2          A18X+137949Y+125410X0120Y0150     S2      
327GND              C4309 -2          A18X+137502Y+125410X0120Y0150R180 S2      
327GND              C4378 -2          A18X+137949Y+125081X0120Y0150     S2      
327GND              C4323 -2   M      A18X+137502Y+125070X0120Y0150R180 S2      
317GND              VIA   -    MD0100PA00X+137739Y+125416X0200Y         S0      
317GND              VIA   -    MD0100PA00X+137739Y+125076X0200Y         S0      
317GND              VIA   -    MD0100PA00X+137739Y+124406X0200Y         S0      
327GND              C1925 -2          A18X+139710Y+121211X0280Y0320R180 S2      
327GND              C1922 -2          A18X+139066Y+121211X0280Y0320R180 S2      
327GND              C1923 -2          A18X+138554Y+121211X0280Y0320R180 S2      
327GND              C1924 -2          A18X+138037Y+121211X0280Y0320R180 S2      
327GND              C4217 -2          A01X+046110Y+126597X0280Y0320     S1      
317GND              VIA   -    MD0100PA00X+045412Y+126950X0200Y         S0      
327GND              C4216 -2   M      A01X+045559Y+126597X0280Y0320     S1      
327GND              C1157 -2          A01X+046224Y+124752X0280Y0320R270 S1      
327GND              C4253 -2          A18X+046532Y+125410X0120Y0150     S2      
327GND              C4267 -2          A18X+046532Y+125081X0120Y0150     S2      
327GND              C4252 -2          A18X+046532Y+124751X0120Y0150     S2      
327GND              C4266 -2   M      A18X+046532Y+124411X0120Y0150     S2      
317GND              VIA   -    MD0100PA00X+046322Y+124406X0200Y         S0      
327GND              C4264 -2          A18X+050628Y+121418X0120Y0150R090 S2      
327GND              C4265 -2          A18X+051967Y+121418X0120Y0150R090 S2      
327GND              C4251 -2          A18X+052813Y+121418X0120Y0150R090 S2      
327GND              C4250 -2          A18X+053124Y+121421X0120Y0150R090 S2      
327GND              C4260 -2          A18X+052369Y+121198X0280Y0320R180 S2      
327GND              C4263 -2          A01X+052612Y+121225X0280Y0320R180 S1      
327GND              C4247 -2          A01X+049960Y+121155X0280Y0320R180 S1      
327GND              C4248 -2          A18X+051546Y+121198X0280Y0320R180 S2      
327GND              C4249 -2          A18X+051019Y+121198X0280Y0320R180 S2      
327GND              C4262 -2          A18X+050220Y+121198X0280Y0320R180 S2      
327GND              C4261 -2          A18X+049677Y+121198X0280Y0320R180 S2      
327GND              C4246 -2          A18X+048905Y+121198X0280Y0320R180 S2      
327GND              C4200 -2          A18X+040630Y+121400X0120Y0150R090 S2      
327GND              C4197 -2          A18X+041182Y+121198X0280Y0320R180 S2      
327GND              C1414 -2          A18X+046624Y+121198X0280Y0320R180 S2      
327GND              C1413 -2          A18X+047135Y+121198X0280Y0320R180 S2      
327GND              C1412 -2          A18X+047658Y+121198X0280Y0320R180 S2      
327GND              C1415 -2          A18X+048289Y+121198X0280Y0320R180 S2      
327GND              C4196 -2          A01X+040071Y+121179X0280Y0320R180 S1      
317GND              VIA   -    MD0100PA00X+052055Y+128718X0200Y    R090 S0      
317GND              VIA   -    MD0100PA00X+051436Y+128737X0200Y    R090 S0      
317GND              VIA   -    MD0100PA00X+051737Y+128722X0200Y    R090 S0      
327GND              C4258 -2          A18X+052814Y+128364X0280Y0320     S2      
327GND              C4273 -2          A18X+051188Y+128364X0280Y0320     S2      
327GND              C4259 -2          A18X+052276Y+128364X0280Y0320     S2      
327GND              C4272 -2          A18X+051733Y+128364X0280Y0320     S2      
327GND              C4254 -2          A18X+049490Y+128484X0280Y0320     S2      
327GND              C4256 -2          A18X+050030Y+128484X0280Y0320     S2      
327GND              C4255 -2          A18X+050603Y+128484X0280Y0320     S2      
327GND              C4257 -2          A18X+048912Y+128316X0280Y0320     S2      
327GND              C4271 -2          A18X+048350Y+128316X0280Y0320     S2      
327GND              C4270 -2          A18X+047810Y+128316X0280Y0320     S2      
327GND              C4269 -2          A18X+047259Y+128316X0280Y0320     S2      
327GND              C4268 -2          A18X+046697Y+128316X0280Y0320     S2      
327GND              C4195 -2          A18X+039925Y+121327X0120Y0150R090 S2      
327GND              C4190 -2          A18X+039595Y+121335X0120Y0150R090 S2      
327GND              C4201 -2          A18X+040260Y+121324X0120Y0150R090 S2      
327GND              C4198 -2          A18X+044384Y+121198X0280Y0320R180 S2      
327GND              C4194 -2          A18X+043800Y+121198X0280Y0320R180 S2      
327GND              C4192 -2          A18X+042456Y+121198X0280Y0320R180 S2      
327GND              C4191 -2          A18X+041732Y+121198X0280Y0320R180 S2      
327GND              C4193 -2          A18X+043010Y+121198X0280Y0320R180 S2      
327GND              C4211 -2          A18X+046085Y+124416X0120Y0150R180 S2      
327GND              C4210 -2   M      A18X+046085Y+124751X0120Y0150R180 S2      
327GND              C4208 -2   M      A18X+046085Y+125070X0120Y0150R180 S2      
317GND              VIA   -    MD0100PA00X+046322Y+125076X0200Y         S0      
327GND              C4209 -2          A18X+046085Y+125410X0120Y0150R180 S2      
317GND              VIA   -    MD0100PA00X+046161Y+128678X0200Y         S0      
317GND              VIA   -    MD0100PA00X+045621Y+128678X0200Y         S0      
327GND              C4202 -2          A18X+046164Y+128316X0280Y0320     S2      
327GND              C4213 -2          A18X+044621Y+128306X0280Y0320     S2      
327GND              C4212 -2          A18X+045134Y+128312X0280Y0320     S2      
327GND              C4203 -2          A18X+045644Y+128314X0280Y0320     S2      
327GND              C4204 -2          A18X+044104Y+128303X0280Y0320     S2      
327GND              C4205 -2          A18X+043629Y+128303X0280Y0320     S2      
327GND              C4214 -2          A18X+043111Y+128331X0280Y0320     S2      
327GND              C4215 -2          A18X+042587Y+128301X0280Y0320     S2      
327GND              C4199 -2          A01X+042682Y+121194X0280Y0320R180 S1      
327GND              C4207 -2          A01X+046132Y+120628X0280Y0320R180 S1      
327GND              C4206 -2          A01X+045597Y+120628X0280Y0320R180 S1      
317GND              VIA   -    MD0100PA00X+046322Y+125416X0200Y         S0      
327GND              C1158 -2          A18X+045047Y+121198X0280Y0320R180 S2      
327GND              C1160 -2          A18X+045581Y+121198X0280Y0320R180 S2      
327GND              C1159 -2          A18X+046101Y+121198X0280Y0320R180 S2      
327GND              C4313 -2          A18X+137303Y+129004X0280Y0320     S2      
327GND              C4321 -2          A18X+133691Y+121449X0120Y0150R090 S2      
327GND              C4320 -2          A18X+134006Y+121449X0120Y0150R090 S2      
327GND              C4307 -2          A18X+133373Y+121450X0120Y0150R090 S2      
317GND              VIA   -    MD0100PA00X+130717Y+124570X0200Y         S0      
327GND              C4304 -2          A18X+131170Y+124570X0280Y0320R180 S2      
327GND              C4305 -2          A18X+135763Y+121211X0280Y0320R180 S2      
327GND              C1667 -2          A18X+137516Y+121211X0280Y0320R180 S2      
327GND              C1669 -2          A18X+136994Y+121211X0280Y0320R180 S2      
327GND              C1670 -2          A18X+136462Y+121211X0280Y0320R180 S2      
327GND              C4316 -2          A18X+132392Y+121211X0280Y0320R180 S2      
317GND              VIA   -    MD0100PA00X+130828Y+127645X0200Y         S0      
327GND              C4308 -2          A18X+131079Y+127572X0120Y0150R270 S2      
317GND              VIA   -    MD0100PA00X+135707Y+129750X0200Y         S0      
317GND              VIA   -    MD0100PA00X+135167Y+129750X0200Y         S0      
317GND              VIA   -    MD0100PA00X+134627Y+129750X0200Y         S0      
317GND              VIA   -    MD0100PA00X+134087Y+129750X0200Y         S0      
317GND              VIA   -    MD0100PA00X+133547Y+129750X0200Y         S0      
317GND              VIA   -    MD0100PA00X+133007Y+129750X0200Y         S0      
327GND              C4324 -2   M      A18X+136768Y+129009X0280Y0320     S2      
327GND              C4312 -2          A18X+135687Y+129009X0280Y0320     S2      
327GND              C4325 -2   M      A18X+136227Y+129009X0280Y0320     S2      
327GND              C4327 -2          A18X+134114Y+129009X0280Y0320     S2      
327GND              C4314 -2          A18X+134637Y+129009X0280Y0320     S2      
327GND              C4315 -2          A18X+135167Y+129009X0280Y0320     S2      
327GND              C4326 -2          A18X+132544Y+129009X0280Y0320     S2      
327GND              C4329 -2          A18X+133059Y+129009X0280Y0320     S2      
327GND              C4311 -2          A18X+133587Y+129009X0280Y0320     S2      
327GND              C4328 -2          A18X+131462Y+128601X0280Y0320     S2      
327GND              C4310 -2          A18X+132007Y+128595X0280Y0320     S2      
327GND              C4306 -2          A18X+131296Y+121361X0120Y0150R090 S2      
327GND              C4318 -2          A18X+131701Y+121211X0280Y0320R180 S2      
327GND              C4302 -2          A18X+132935Y+121211X0280Y0320R180 S2      
327GND              C4317 -2          A18X+134433Y+121211X0280Y0320R180 S2      
327GND              C4319 -2          A01X+134145Y+121176X0280Y0320R180 S1      
327GND              C4303 -2          A01X+131482Y+121213X0280Y0320R180 S1      
327GND              C3546 -2          A01X+150521Y+118591X0280Y0320R270 S1      
327GND              C3549 -2          A01X+150521Y+116071X0280Y0320R270 S1      
327GND              C3543 -2          A01X+150521Y+117331X0280Y0320R270 S1      
327GND              C3564 -2          A01X+150521Y+114811X0280Y0320R270 S1      
327GND              C3577 -2          A01X+150521Y+113551X0280Y0320R270 S1      
327GND              C3589 -2          A01X+150521Y+111031X0280Y0320R270 S1      
327GND              C3580 -2          A01X+150521Y+112291X0280Y0320R270 S1      
327GND              C3372 -2          A01X+104813Y+118591X0280Y0320R270 S1      
327GND              C3369 -2          A01X+104813Y+117331X0280Y0320R270 S1      
327GND              C3375 -2          A01X+104813Y+116071X0280Y0320R270 S1      
327GND              C3390 -2          A01X+104813Y+114811X0280Y0320R270 S1      
327GND              C3403 -2          A01X+104813Y+113551X0280Y0320R270 S1      
327GND              C3406 -2          A01X+104813Y+112291X0280Y0320R270 S1      
327GND              C3415 -2          A01X+104813Y+111031X0280Y0320R270 S1      
327GND              C3198 -2          A01X+059104Y+118591X0280Y0320R270 S1      
327GND              C3195 -2          A01X+059104Y+117331X0280Y0320R270 S1      
327GND              C3201 -2          A01X+059104Y+116071X0280Y0320R270 S1      
327GND              C3216 -2          A01X+059104Y+114811X0280Y0320R270 S1      
327GND              C3229 -2          A01X+059104Y+113551X0280Y0320R270 S1      
327GND              C3232 -2          A01X+059104Y+112291X0280Y0320R270 S1      
327GND              C3241 -2          A01X+059104Y+111031X0280Y0320R270 S1      
327GND              R6448 -2          A01X+142625Y+140770X0198Y0197R270 S1      
327GND              C4184 -2          A18X+042352Y+137600X0198Y0197R090 S2      
327GND              R6372 -2          A18X+042528Y+137097X0198Y0197R180 S2      
317GND              VIA   -    MD0100PA00X+042528Y+137396X0200Y         S0      
317GND              VIA   -    MD0100PA00X+043600Y+138225X0200Y         S0      
327GND              C4182 -2          A18X+043427Y+137845X0400Y0500R090 S2      
317GND              VIA   -    MD0100PA00X+085178Y+082372X0200Y         S0      
327GND              R5524 -1          A01X+084606Y+082769X0198Y0197     S1      
327GND              U316  -4          A01X+172397Y+116397X0240Y0460     S1      
327GND              U315  -4          A01X+126689Y+116397X0240Y0460     S1      
327GND              U314  -4          A01X+080980Y+116397X0240Y0460     S1      
327GND              U313  -4          A01X+035271Y+116397X0240Y0460     S1      
317GND              VIA   -    MD0100PA00X+052867Y+096485X0200Y         S0      
327GND              PJP1  -3          A01X+053287Y+097285X0500Y1350R090 S1      
317GND              VIA   -    MD0100PA00X+023268Y+146680X0200Y         S0      
327GND              C4033 -1          A01X+023650Y+147556X0198Y0197R090 S1      
317GND              VIA   -    MD0100PA00X+022418Y+149282X0200Y         S0      
327GND              C4037 -1          A01X+022746Y+149436X0198Y0197     S1      
317GND              VIA   -    MD0100PA00X+021817Y+147446X0200Y         S0      
327GND              C4013 -1          A01X+022108Y+147990X0198Y0197R090 S1      
317GND              VIA   -    MD0100PA00X+022926Y+146959X0200Y         S0      
327GND              C4009 -1          A01X+023062Y+147452X0198Y0197R180 S1      
327GND              R6301 -2   M      A01X+024964Y+151014X0198Y0197     S1      
327GND              R6300 -2   M      A01X+024964Y+151417X0198Y0197     S1      
327GND              C4034 -1          A01X+025176Y+151796X0198Y0197R180 S1      
327GND              C4030 -1   M      A01X+024946Y+150606X0198Y0197R180 S1      
327GND              C4040 -1          A01X+022194Y+153746X0198Y0197R270 S1      
317GND              VIA   -    MD0100PA00X+021752Y+153717X0200Y         S0      
327GND              C4017 -1   M      A01X+022994Y+154946X0198Y0197R270 S1      
327GND              C4038 -1   M      A01X+023394Y+154946X0198Y0197R270 S1      
327GND              C4014 -1          A01X+024494Y+154946X0198Y0197R270 S1      
327GND              C4010 -1   M      A01X+023794Y+154946X0198Y0197R270 S1      
327GND              R6411 -2          A18X+099200Y+078658X0198Y0197R270 S2      
317GND              VIA   -    MD0100PA00X+083271Y+099327X0200Y         S0      
327GND              C2745 -2          A01X+133769Y+094857X0198Y0197R270 S1      
327GND              R6410 -1          A01X+142496Y+094339X0198Y0197     S1      
327GND              R6409 -1          A01X+145862Y+092818X0198Y0197     S1      
317GND              VIA   -    MD0100PA00X+147435Y+094939X0200Y         S0      
327GND              R6403 -1          A01X+146969Y+094760X0198Y0197R180 S1      
327GND              C4189 -1          A01X+145969Y+095098X0198Y0197R180 S1      
317GND              VIA   -    MD0100PA00X+144445Y+093881X0200Y         S0      
327GND              U429  -4          A01X+143923Y+093829X0140Y0520R270 S1      
327GND              R6314 -2          A18X+130292Y+094400X0198Y0197     S2      
327GND              C2708 -1          A01X+082040Y+093357X0198Y0197     S1      
327GND              R6341 -2          A18X+082515Y+096957X0198Y0197R090 S2      
327GND              R6339 -2          A18X+078763Y+102249X0198Y0197R270 S2      
317GND              VIA   -    MD0100PA00X+079169Y+102544X0200Y         S0      
327GND              R6340 -2   M      A18X+079169Y+102249X0198Y0197R270 S2      
327GND              R5284 -1          A18X+089192Y+081346X0198Y0197R270 S2      
327GND              R5282 -1          A18X+089992Y+080332X0198Y0197R270 S2      
317GND              VIA   -    MD0100PA00X+163753Y+069993X0200Y         S0      
317GND              VIA   -    MD0100PA00X+162415Y+070826X0200Y         S0      
317GND              VIA   -    MD0100PA00X+163747Y+071783X0200Y         S0      
317GND              VIA   -    MD0100PA00X+162881Y+072704X0200Y         S0      
317GND              VIA   -    MD0100PA00X+163103Y+073243X0200Y         S0      
317GND              VIA   -    MD0100PA00X+162997Y+074083X0200Y         S0      
317GND              VIA   -    MD0100PA00X+163119Y+075063X0200Y         S0      
317GND              VIA   -    MD0100PA00X+162746Y+075949X0200Y         S0      
317GND              VIA   -    MD0100PA00X+162036Y+077483X0200Y         S0      
317GND              VIA   -    MD0100PA00X+161961Y+078315X0200Y         S0      
317GND              VIA   -    MD0100PA00X+162076Y+078753X0200Y         S0      
317GND              VIA   -    MD0100PA00X+161957Y+079604X0200Y         S0      
317GND              VIA   -    MD0100PA00X+162007Y+080163X0200Y         S0      
317GND              VIA   -    MD0100PA00X+162048Y+081573X0200Y         S0      
317GND              VIA   -    MD0100PA00X+161626Y+082440X0200Y         S0      
327GND              Q238  -1          A01X+161626Y+082164X0240Y0240R270 S1      
327GND              Q238  -4          A01X+162334Y+081573X0240Y0240R270 S1      
317GND              VIA   -    MD0100PA00X+161324Y+080847X0200Y         S0      
327GND              Q237  -1   M      A01X+161616Y+080754X0240Y0240R270 S1      
327GND              Q237  -4   M      A01X+162324Y+080163X0240Y0240R270 S1      
327GND              Q235  -1   M      A01X+161646Y+079344X0240Y0240R270 S1      
327GND              Q235  -4   M      A01X+162354Y+078753X0240Y0240R270 S1      
327GND              Q233  -1   M      A01X+161666Y+078074X0240Y0240R270 S1      
327GND              Q233  -4   M      A01X+162374Y+077483X0240Y0240R270 S1      
327GND              Q236  -1   M      A01X+162746Y+075654X0240Y0240R270 S1      
327GND              Q236  -4   M      A01X+163454Y+075063X0240Y0240R270 S1      
327GND              Q232  -1   M      A01X+162746Y+073834X0240Y0240R270 S1      
327GND              Q232  -4   M      A01X+163454Y+073243X0240Y0240R270 S1      
327GND              Q239  -1   M      A01X+162716Y+072374X0240Y0240R270 S1      
327GND              Q239  -4   M      A01X+163424Y+071783X0240Y0240R270 S1      
327GND              Q234  -1   M      A01X+162716Y+070584X0240Y0240R270 S1      
327GND              Q234  -4   M      A01X+163424Y+069993X0240Y0240R270 S1      
317GND              VIA   -    MD0100PA00X+021634Y+151564X0200Y         S0      
327GND              C4042 -1          A01X+021964Y+152254X0198Y0197     S1      
327GND              C4025 -1   M      A01X+021994Y+151564X0198Y0197     S1      
317GND              VIA   -    MD0100PA00X+024804Y+153290X0200Y         S0      
327GND              C4048 -1          A01X+024804Y+153046X0198Y0197R270 S1      
317GND              VIA   -    MD0100PA00X+023770Y+153160X0200Y         S0      
327GND              C4041 -1          A01X+024084Y+153046X0198Y0197R270 S1      
317GND              VIA   -    MD0100PA00X+124590Y+152800X0200Y         S0      
327GND              C4112 -1          A01X+124754Y+153134X0198Y0197     S1      
317GND              VIA   -    MD0100PA00X+126324Y+152346X0200Y         S0      
327GND              C4116 -1          A01X+126026Y+152346X0198Y0197R180 S1      
317GND              VIA   -    MD0100PA00X+126026Y+154650X0200Y         S0      
327GND              C4108 -1          A01X+126026Y+154356X0198Y0197R180 S1      
317GND              VIA   -    MD0100PA00X+142884Y+140774X0200Y         S0      
327GND              C4168 -1          A01X+143626Y+140774X0198Y0197R090 S1      
327GND              C4164 -1   M      A01X+143226Y+140774X0198Y0197R090 S1      
317GND              VIA   -    MD0100PA00X+137230Y+142290X0200Y         S0      
327GND              C4128 -1          A18X+136878Y+142290X0198Y0197     S2      
317GND              VIA   -    MD0100PA00X+160070Y+153430X0200Y         S0      
327GND              C4175 -1          A01X+159814Y+153046X0198Y0197R270 S1      
317GND              VIA   -    MD0100PA00X+161420Y+151950X0200Y         S0      
327GND              C4162 -1          A01X+161086Y+152024X0198Y0197R090 S1      
317GND              VIA   -    MD0100PA00X+161860Y+153200X0200Y         S0      
327GND              C4159 -1          A01X+161546Y+153526X0198Y0197R180 S1      
317GND              VIA   -    MD0100PA00X+161436Y+154286X0200Y         S0      
327GND              C4158 -1          A01X+161936Y+153936X0198Y0197R180 S1      
317GND              VIA   -    MD0100PA00X+161880Y+152856X0200Y         S0      
327GND              C4160 -1          A01X+161576Y+152856X0198Y0197R180 S1      
317GND              VIA   -    MD0100PA00X+059298Y+151481X0200Y         S0      
327GND              C4100 -1   M      A01X+059816Y+150146X0198Y0197R180 S1      
327GND              C4096 -1          A01X+059806Y+149366X0198Y0197R180 S1      
327GND              C4098 -1   M      A01X+059806Y+149756X0198Y0197R180 S1      
327GND              C4080 -1          A01X+056424Y+152826X0198Y0197R270 S1      
317GND              VIA   -    MD0100PA00X+056680Y+154180X0200Y         S0      
327GND              C4078 -1          A01X+057194Y+154736X0198Y0197R270 S1      
317GND              VIA   -    MD0100PA00X+058070Y+154410X0200Y         S0      
327GND              C4064 -1          A01X+058374Y+154786X0198Y0197R270 S1      
317GND              VIA   -    MD0100PA00X+056560Y+153080X0200Y         S0      
327GND              C4106 -1          A01X+056796Y+153224X0198Y0197R090 S1      
317GND              VIA   -    MD0100PA00X+059880Y+154640X0200Y         S0      
327GND              C4052 -1          A01X+060024Y+154166X0198Y0197R270 S1      
317GND              VIA   -    MD0100PA00X+059186Y+152354X0200Y         S0      
327GND              C4097 -1          A01X+059186Y+152684X0198Y0197R090 S1      
317GND              VIA   -    MD0100PA00X+058786Y+151794X0200Y         S0      
327GND              C4099 -1          A01X+058786Y+152074X0198Y0197R090 S1      
317GND              VIA   -    MD0100PA00X+058374Y+152064X0200Y         S0      
327GND              C4104 -1          A01X+057976Y+152064X0198Y0197R090 S1      
317GND              VIA   -    MD0100PA00X+058380Y+151800X0200Y         S0      
327GND              C4082 -1          A01X+058214Y+151404X0198Y0197     S1      
327GND              C4051 -1          A01X+040454Y+144294X0198Y0197     S1      
317GND              VIA   -    MD0100PA00X+087570Y+129970X0200Y         S0      
317GND              VIA   -    MD0100PA00X+048480Y+130200X0200Y    R090 S0      
327GND              R5522 -1          A01X+098371Y+071966X0198Y0197R270 S1      
327GND              C4188 -1          A01X+170889Y+117890X0198Y0197R270 S1      
327GND              C2760 -1          A01X+173742Y+114694X0198Y0197R090 S1      
317GND              VIA   -    MD0100PA00X+125180Y+118607X0200Y         S0      
327GND              C4187 -1          A01X+125180Y+117890X0198Y0197R270 S1      
327GND              U427  -4          A01X+126056Y+115324X0140Y0520     S1      
317GND              VIA   -    MD0100PA00X+126387Y+114800X0200Y         S0      
327GND              R6395 -1   M      A01X+126117Y+114607X0198Y0197R180 S1      
327GND              C2758 -1          A01X+128033Y+114694X0198Y0197R090 S1      
317GND              VIA   -    MD0100PA00X+172096Y+114800X0200Y         S0      
327GND              U426  -4          A01X+080347Y+115324X0140Y0520     S1      
327GND              R6391 -1   M      A01X+080409Y+114607X0198Y0197R180 S1      
317GND              VIA   -    MD0100PA00X+080679Y+114800X0200Y         S0      
317GND              VIA   -    MD0100PA00X+170889Y+118922X0200Y         S0      
327GND              C4186 -1          A01X+079472Y+117890X0198Y0197R270 S1      
317GND              VIA   -    MD0100PA00X+079472Y+118607X0200Y         S0      
327GND              C2756 -1          A01X+082324Y+114694X0198Y0197R090 S1      
317GND              VIA   -    MD0100PA00X+033763Y+118607X0200Y         S0      
327GND              C4185 -1          A01X+033763Y+117890X0198Y0197R270 S1      
317GND              VIA   -    MD0100PA00X+034970Y+114800X0200Y         S0      
327GND              U425  -4          A01X+034638Y+115324X0140Y0520     S1      
327GND              R6389 -1   M      A01X+034700Y+114607X0198Y0197R180 S1      
327GND              U123  -4          A01X+083910Y+093578X0240Y0460R180 S1      
317GND              VIA   -    MD0100PA00X+040667Y+141977X0200Y    R090 S0      
317GND              VIA   -    MD0100PA00X+040171Y+141977X0200Y    R090 S0      
317GND              VIA   -    MD0100PA00X+036782Y+131554X0200Y    R270 S0      
317GND              VIA   -    MD0100PA00X+036782Y+131059X0200Y    R270 S0      
317GND              VIA   -    MD0100PA00X+101183Y+134252X0200Y         S0      
317GND              VIA   -    MD0100PA00X+101183Y+134747X0200Y         S0      
317GND              VIA   -    MD0100PA00X+143948Y+130831X0200Y         S0      
317GND              VIA   -    MD0100PA00X+144444Y+130831X0200Y         S0      
317GND              VIA   -    MD0100PA00X+040398Y+135157X0200Y         S0      
317GND              VIA   -    MD0100PA00X+039466Y+137788X0200Y    R270 S0      
327GND              C4181 -2          A18X+039176Y+137788X0198Y0197R090 S2      
317GND              VIA   -    MD0100PA00X+038919Y+136903X0200Y    R270 S0      
317GND              VIA   -    MD0100PA00X+043588Y+139880X0180Y    R270 S0      
327GND              C4177 -2          A18X+043316Y+139880X0198Y0197R180 S2      
317GND              VIA   -    MD0100PA00X+043588Y+139493X0180Y    R270 S0      
327GND              C4179 -2          A18X+043313Y+139493X0198Y0197R180 S2      
317GND              VIA   -    MD0100PA00X+039811Y+140374X0200Y    R270 S0      
327GND              R6371 -2          A18X+040088Y+140339X0198Y0197R270 S2      
317GND              VIA   -    MD0100PA00X+041015Y+141093X0200Y    R270 S0      
327GND              C4178 -2          A18X+041015Y+140853X0198Y0197R270 S2      
317GND              VIA   -    MD0100PA00X+038998Y+140576X0200Y    R270 S0      
317GND              VIA   -    MD0100PA00X+038860Y+139550X0200Y    R270 S0      
327GND              C4180 -2          A18X+038870Y+139259X0198Y0197     S2      
327GND              C4176 -2          A18X+039418Y+140639X0400Y0500R090 S2      
327GND              C4183 -2          A18X+041278Y+136506X0198Y0197R090 S2      
317GND              VIA   -    MD0100PA00X+041428Y+136256X0200Y    R270 S0      
317GND              VIA   -    MD0100PA00X+039596Y+135215X0200Y    R270 S0      
327GND              R6373 -1          A18X+039596Y+135498X0198Y0197R270 S2      
317GND              VIA   -    MD0100PA00X+040894Y+135157X0200Y         S0      
317GND              VIA   -    MD0100PA00X+038946Y+136547X0200Y    R270 S0      
317GND              VIA   -    MD0100PA00X+041344Y+138490X0200Y    R270 S0      
317GND              VIA   -    MD0100PA00X+040821Y+139008X0200Y    R270 S0      
317GND              VIA   -    MD0100PA00X+040821Y+137970X0200Y    R270 S0      
317GND              VIA   -    MD0100PA00X+041344Y+137974X0200Y    R270 S0      
317GND              VIA   -    MD0100PA00X+040311Y+138492X0200Y    R270 S0      
317GND              VIA   -    MD0100PA00X+040303Y+137972X0200Y    R270 S0      
317GND              VIA   -    MD0100PA00X+040311Y+139010X0200Y    R270 S0      
327GND              U424  -33  M      A18X+040823Y+138490X1240Y1240R270 S2      
317GND              VIA   -    MD0100PA00X+041340Y+139006X0200Y    R270 S0      
327GND              J2    -A1         A01X+091542Y+023150X0150Y0530R090 S1      
327GND              J2    -A2         A01X+091542Y+023386X0150Y0530R090 S1      
327GND              J2    -A3         A01X+091542Y+023622X0150Y0530R090 S1      
327GND              J2    -A7         A01X+091542Y+024567X0150Y0530R090 S1      
327GND              J2    -A11        A01X+091542Y+025512X0150Y0530R090 S1      
327GND              J2    -A13        A01X+091542Y+025984X0150Y0530R090 S1      
327GND              J2    -A19        A01X+091542Y+027402X0150Y0530R090 S1      
317GND              J2    -G1  MD0320PA00X+092334Y+022677X0480Y    R090 S3      
317GND              J2    -G3  MD0320PA00X+089538Y+022874X0480Y    R090 S3      
317GND              J2    -G2  MD0320PA00X+092334Y+027874X0480Y    R090 S3      
317GND              J2    -G4  MD0320PA00X+089538Y+027677X0480Y    R090 S3      
317GND              VIA   -    MD0100PA00X+039973Y+144276X0200Y         S0      
327GND              VIA   -           A18X+043855Y+132994X0260Y         S2      
327GND              C2701 -2          A18X+043272Y+133136X0400Y0500     S2      
317GND              VIA   -    MD0080PA00X+022725Y+144501X0160Y    R270 S0      
317GND              VIA   -    MD0080PA00X+022725Y+145329X0160Y    R090 S0      
317GND              VIA   -    MD0080PA00X+022725Y+145601X0160Y    R270 S0      
317GND              VIA   -    MD0080PA00X+022725Y+146429X0160Y    R090 S0      
317GND              VIA   -    MD0080PA00X+021397Y+146429X0160Y    R090 S0      
317GND              VIA   -    MD0080PA00X+021397Y+145601X0160Y    R270 S0      
317GND              VIA   -    MD0080PA00X+021397Y+144501X0160Y    R270 S0      
317GND              VIA   -    MD0080PA00X+021397Y+145329X0160Y    R090 S0      
317GND              VIA   -    MD0080PA00X+063629Y+138430X0160Y    R180 S0      
317GND              VIA   -    MD0080PA00X+063629Y+137238X0160Y    R180 S0      
317GND              VIA   -    MD0080PA00X+065641Y+136010X0160Y         S0      
317GND              VIA   -    MD0080PA00X+065641Y+134819X0160Y         S0      
317GND              VIA   -    MD0080PA00X+075433Y+136010X0160Y         S0      
317GND              VIA   -    MD0080PA00X+075433Y+134819X0160Y         S0      
317GND              VIA   -    MD0080PA00X+074209Y+136010X0160Y         S0      
317GND              VIA   -    MD0080PA00X+074209Y+134819X0160Y         S0      
317GND              VIA   -    MD0080PA00X+072197Y+136010X0160Y    R180 S0      
317GND              VIA   -    MD0080PA00X+072985Y+136010X0160Y         S0      
317GND              VIA   -    MD0080PA00X+072197Y+134819X0160Y    R180 S0      
317GND              VIA   -    MD0080PA00X+072985Y+134819X0160Y         S0      
317GND              VIA   -    MD0080PA00X+070973Y+136010X0160Y    R180 S0      
317GND              VIA   -    MD0080PA00X+071761Y+136010X0160Y         S0      
317GND              VIA   -    MD0080PA00X+070973Y+134819X0160Y    R180 S0      
317GND              VIA   -    MD0080PA00X+071761Y+134819X0160Y         S0      
317GND              VIA   -    MD0080PA00X+069749Y+136010X0160Y    R180 S0      
317GND              VIA   -    MD0080PA00X+069749Y+134819X0160Y    R180 S0      
317GND              VIA   -    MD0080PA00X+068525Y+136010X0160Y    R180 S0      
317GND              VIA   -    MD0080PA00X+068525Y+134819X0160Y    R180 S0      
317GND              VIA   -    MD0080PA00X+066865Y+136010X0160Y         S0      
317GND              VIA   -    MD0080PA00X+066865Y+134819X0160Y         S0      
317GND              VIA   -    MD0080PA00X+076657Y+138430X0160Y         S0      
317GND              VIA   -    MD0080PA00X+075869Y+138430X0160Y    R180 S0      
317GND              VIA   -    MD0080PA00X+076657Y+137238X0160Y         S0      
317GND              VIA   -    MD0080PA00X+075869Y+137238X0160Y    R180 S0      
317GND              VIA   -    MD0080PA00X+074645Y+138430X0160Y    R180 S0      
317GND              VIA   -    MD0080PA00X+075433Y+138430X0160Y         S0      
317GND              VIA   -    MD0080PA00X+074645Y+137238X0160Y    R180 S0      
317GND              VIA   -    MD0080PA00X+075433Y+137238X0160Y         S0      
317GND              VIA   -    MD0080PA00X+073421Y+138430X0160Y    R180 S0      
317GND              VIA   -    MD0080PA00X+073421Y+137238X0160Y    R180 S0      
317GND              VIA   -    MD0080PA00X+071761Y+138430X0160Y         S0      
317GND              VIA   -    MD0080PA00X+071761Y+137238X0160Y         S0      
317GND              VIA   -    MD0080PA00X+070537Y+138430X0160Y         S0      
317GND              VIA   -    MD0080PA00X+069313Y+138430X0160Y         S0      
317GND              VIA   -    MD0080PA00X+070537Y+137238X0160Y         S0      
317GND              VIA   -    MD0080PA00X+069313Y+137238X0160Y         S0      
317GND              VIA   -    MD0080PA00X+068089Y+138430X0160Y         S0      
317GND              VIA   -    MD0080PA00X+068089Y+137238X0160Y         S0      
317GND              VIA   -    MD0080PA00X+067301Y+138430X0160Y    R180 S0      
317GND              VIA   -    MD0080PA00X+066077Y+138430X0160Y    R180 S0      
317GND              VIA   -    MD0080PA00X+066865Y+138430X0160Y         S0      
317GND              VIA   -    MD0080PA00X+067301Y+137238X0160Y    R180 S0      
317GND              VIA   -    MD0080PA00X+066077Y+137238X0160Y    R180 S0      
317GND              VIA   -    MD0080PA00X+066865Y+137238X0160Y         S0      
317GND              VIA   -    MD0080PA00X+064853Y+138430X0160Y    R180 S0      
317GND              VIA   -    MD0080PA00X+064853Y+137238X0160Y    R180 S0      
317GND              VIA   -    MD0080PA00X+056844Y+137238X0160Y         S0      
317GND              VIA   -    MD0080PA00X+056056Y+137238X0160Y    R180 S0      
317GND              VIA   -    MD0080PA00X+056844Y+138430X0160Y         S0      
317GND              VIA   -    MD0080PA00X+056056Y+138430X0160Y    R180 S0      
317GND              VIA   -    MD0080PA00X+054832Y+137238X0160Y    R180 S0      
317GND              VIA   -    MD0080PA00X+055620Y+137238X0160Y         S0      
317GND              VIA   -    MD0080PA00X+054832Y+138430X0160Y    R180 S0      
317GND              VIA   -    MD0080PA00X+055620Y+138430X0160Y         S0      
317GND              VIA   -    MD0080PA00X+053608Y+137238X0160Y    R180 S0      
317GND              VIA   -    MD0080PA00X+053608Y+138430X0160Y    R180 S0      
317GND              VIA   -    MD0080PA00X+052384Y+137238X0160Y    R180 S0      
317GND              VIA   -    MD0080PA00X+052384Y+138430X0160Y    R180 S0      
317GND              VIA   -    MD0080PA00X+050724Y+137238X0160Y         S0      
317GND              VIA   -    MD0080PA00X+049500Y+137238X0160Y         S0      
317GND              VIA   -    MD0080PA00X+050724Y+138430X0160Y         S0      
317GND              VIA   -    MD0080PA00X+049500Y+138430X0160Y         S0      
317GND              VIA   -    MD0080PA00X+048276Y+137238X0160Y         S0      
317GND              VIA   -    MD0080PA00X+048276Y+138430X0160Y         S0      
317GND              VIA   -    MD0080PA00X+047488Y+137238X0160Y    R180 S0      
317GND              VIA   -    MD0080PA00X+047052Y+137238X0160Y         S0      
317GND              VIA   -    MD0080PA00X+046264Y+137238X0160Y    R180 S0      
317GND              VIA   -    MD0080PA00X+047488Y+138430X0160Y    R180 S0      
317GND              VIA   -    MD0080PA00X+047052Y+138430X0160Y         S0      
317GND              VIA   -    MD0080PA00X+046264Y+138430X0160Y    R180 S0      
317GND              VIA   -    MD0080PA00X+045040Y+137238X0160Y    R180 S0      
317GND              VIA   -    MD0080PA00X+045040Y+138430X0160Y    R180 S0      
317GND              VIA   -    MD0080PA00X+043816Y+137238X0160Y    R180 S0      
317GND              VIA   -    MD0080PA00X+043816Y+138430X0160Y    R180 S0      
317GND              VIA   -    MD0080PA00X+054396Y+136010X0160Y         S0      
317GND              VIA   -    MD0080PA00X+055620Y+136010X0160Y         S0      
317GND              VIA   -    MD0080PA00X+053172Y+136010X0160Y         S0      
317GND              VIA   -    MD0080PA00X+051160Y+136010X0160Y    R180 S0      
317GND              VIA   -    MD0080PA00X+051948Y+136010X0160Y         S0      
317GND              VIA   -    MD0080PA00X+052384Y+136010X0160Y    R180 S0      
317GND              VIA   -    MD0080PA00X+049936Y+136010X0160Y    R180 S0      
317GND              VIA   -    MD0080PA00X+048712Y+136010X0160Y    R180 S0      
317GND              VIA   -    MD0080PA00X+047052Y+136010X0160Y         S0      
317GND              VIA   -    MD0080PA00X+044604Y+136010X0160Y         S0      
317GND              VIA   -    MD0080PA00X+045828Y+136010X0160Y         S0      
317GND              VIA   -    MD0080PA00X+043816Y+136010X0160Y    R180 S0      
317GND              VIA   -    MD0080PA00X+054396Y+134819X0160Y         S0      
317GND              VIA   -    MD0080PA00X+055620Y+134819X0160Y         S0      
317GND              VIA   -    MD0080PA00X+053172Y+134819X0160Y         S0      
317GND              VIA   -    MD0080PA00X+051160Y+134819X0160Y    R180 S0      
317GND              VIA   -    MD0080PA00X+051948Y+134819X0160Y         S0      
317GND              VIA   -    MD0080PA00X+052384Y+134819X0160Y    R180 S0      
317GND              VIA   -    MD0080PA00X+049936Y+134819X0160Y    R180 S0      
317GND              VIA   -    MD0080PA00X+048712Y+134819X0160Y    R180 S0      
317GND              VIA   -    MD0080PA00X+047052Y+134819X0160Y         S0      
317GND              VIA   -    MD0080PA00X+044604Y+134819X0160Y         S0      
317GND              VIA   -    MD0080PA00X+045828Y+134819X0160Y         S0      
317GND              VIA   -    MD0080PA00X+043816Y+134819X0160Y    R180 S0      
317GND              VIA   -    MD0080PA00X+056056Y+136010X0160Y    R180 S0      
317GND              VIA   -    MD0080PA00X+056056Y+134819X0160Y    R180 S0      
317GND              VIA   -    MD0080PA00X+054832Y+136010X0160Y    R180 S0      
317GND              VIA   -    MD0080PA00X+054832Y+134819X0160Y    R180 S0      
317GND              VIA   -    MD0080PA00X+053608Y+136010X0160Y    R180 S0      
317GND              VIA   -    MD0080PA00X+053608Y+134819X0160Y    R180 S0      
317GND              VIA   -    MD0080PA00X+048712Y+138430X0160Y    R180 S0      
317GND              VIA   -    MD0080PA00X+048712Y+137238X0160Y    R180 S0      
317GND              VIA   -    MD0080PA00X+047488Y+136010X0160Y    R180 S0      
317GND              VIA   -    MD0080PA00X+047488Y+134819X0160Y    R180 S0      
317GND              VIA   -    MD0080PA00X+046264Y+136010X0160Y    R180 S0      
317GND              VIA   -    MD0080PA00X+046264Y+134819X0160Y    R180 S0      
317GND              VIA   -    MD0080PA00X+045040Y+136010X0160Y    R180 S0      
317GND              VIA   -    MD0080PA00X+045040Y+134819X0160Y    R180 S0      
317GND              VIA   -    MD0080PA00X+049936Y+138430X0160Y    R180 S0      
317GND              VIA   -    MD0080PA00X+049936Y+137238X0160Y    R180 S0      
317GND              VIA   -    MD0080PA00X+051160Y+138430X0160Y    R180 S0      
317GND              VIA   -    MD0080PA00X+051160Y+137238X0160Y    R180 S0      
317GND              VIA   -    MD0080PA00X+045040Y+140850X0160Y    R180 S0      
317GND              VIA   -    MD0080PA00X+045040Y+139658X0160Y    R180 S0      
317GND              VIA   -    MD0080PA00X+046264Y+140850X0160Y    R180 S0      
317GND              VIA   -    MD0080PA00X+046264Y+139658X0160Y    R180 S0      
317GND              VIA   -    MD0080PA00X+047488Y+140850X0160Y    R180 S0      
317GND              VIA   -    MD0080PA00X+047488Y+139658X0160Y    R180 S0      
317GND              VIA   -    MD0080PA00X+048712Y+140850X0160Y    R180 S0      
317GND              VIA   -    MD0080PA00X+048712Y+139658X0160Y    R180 S0      
317GND              VIA   -    MD0080PA00X+049936Y+140850X0160Y    R180 S0      
317GND              VIA   -    MD0080PA00X+049936Y+139658X0160Y    R180 S0      
317GND              VIA   -    MD0080PA00X+051160Y+140850X0160Y    R180 S0      
317GND              VIA   -    MD0080PA00X+051160Y+139658X0160Y    R180 S0      
317GND              VIA   -    MD0080PA00X+052384Y+140850X0160Y    R180 S0      
317GND              VIA   -    MD0080PA00X+052384Y+139658X0160Y    R180 S0      
317GND              VIA   -    MD0080PA00X+053608Y+140850X0160Y    R180 S0      
317GND              VIA   -    MD0080PA00X+053608Y+139658X0160Y    R180 S0      
317GND              VIA   -    MD0080PA00X+054832Y+140850X0160Y    R180 S0      
317GND              VIA   -    MD0080PA00X+054832Y+139658X0160Y    R180 S0      
317GND              VIA   -    MD0080PA00X+056056Y+139658X0160Y    R180 S0      
317GND              VIA   -    MD0080PA00X+056056Y+140850X0160Y    R180 S0      
317GND              VIA   -    MD0080PA00X+077093Y+136010X0160Y    R180 S0      
317GND              VIA   -    MD0080PA00X+077093Y+134819X0160Y    R180 S0      
317GND              VIA   -    MD0080PA00X+075869Y+136010X0160Y    R180 S0      
317GND              VIA   -    MD0080PA00X+075869Y+134819X0160Y    R180 S0      
317GND              VIA   -    MD0080PA00X+073421Y+140840X0160Y    R180 S0      
317GND              VIA   -    MD0080PA00X+073421Y+139649X0160Y    R180 S0      
317GND              VIA   -    MD0080PA00X+074645Y+136010X0160Y    R180 S0      
317GND              VIA   -    MD0080PA00X+074645Y+134819X0160Y    R180 S0      
317GND              VIA   -    MD0080PA00X+073421Y+136010X0160Y    R180 S0      
317GND              VIA   -    MD0080PA00X+073421Y+134819X0160Y    R180 S0      
317GND              VIA   -    MD0080PA00X+072197Y+140840X0160Y    R180 S0      
317GND              VIA   -    MD0080PA00X+072197Y+139649X0160Y    R180 S0      
317GND              VIA   -    MD0080PA00X+068525Y+138430X0160Y    R180 S0      
317GND              VIA   -    MD0080PA00X+068525Y+137238X0160Y    R180 S0      
317GND              VIA   -    MD0080PA00X+067301Y+136010X0160Y    R180 S0      
317GND              VIA   -    MD0080PA00X+067301Y+134819X0160Y    R180 S0      
317GND              VIA   -    MD0080PA00X+066077Y+136010X0160Y    R180 S0      
317GND              VIA   -    MD0080PA00X+066077Y+134819X0160Y    R180 S0      
317GND              VIA   -    MD0080PA00X+064853Y+136010X0160Y    R180 S0      
317GND              VIA   -    MD0080PA00X+064853Y+134819X0160Y    R180 S0      
317GND              VIA   -    MD0080PA00X+062405Y+140850X0160Y    R180 S0      
317GND              VIA   -    MD0080PA00X+062405Y+139658X0160Y    R180 S0      
317GND              VIA   -    MD0080PA00X+063629Y+140850X0160Y    R180 S0      
317GND              VIA   -    MD0080PA00X+063629Y+139658X0160Y    R180 S0      
317GND              VIA   -    MD0080PA00X+064853Y+140850X0160Y    R180 S0      
317GND              VIA   -    MD0080PA00X+064853Y+139658X0160Y    R180 S0      
317GND              VIA   -    MD0080PA00X+066077Y+140850X0160Y    R180 S0      
317GND              VIA   -    MD0080PA00X+066077Y+139658X0160Y    R180 S0      
317GND              VIA   -    MD0080PA00X+069749Y+137238X0160Y    R180 S0      
317GND              VIA   -    MD0080PA00X+067301Y+139658X0160Y    R180 S0      
317GND              VIA   -    MD0080PA00X+070973Y+137238X0160Y    R180 S0      
317GND              VIA   -    MD0080PA00X+068525Y+139658X0160Y    R180 S0      
317GND              VIA   -    MD0080PA00X+072197Y+137238X0160Y    R180 S0      
317GND              VIA   -    MD0080PA00X+069749Y+139658X0160Y    R180 S0      
317GND              VIA   -    MD0080PA00X+070973Y+139658X0160Y    R180 S0      
317GND              VIA   -    MD0080PA00X+069749Y+138430X0160Y    R180 S0      
317GND              VIA   -    MD0080PA00X+067301Y+140850X0160Y    R180 S0      
317GND              VIA   -    MD0080PA00X+070973Y+138430X0160Y    R180 S0      
317GND              VIA   -    MD0080PA00X+068525Y+140850X0160Y    R180 S0      
317GND              VIA   -    MD0080PA00X+072197Y+138430X0160Y    R180 S0      
317GND              VIA   -    MD0080PA00X+069749Y+140850X0160Y    R180 S0      
317GND              VIA   -    MD0080PA00X+070973Y+140850X0160Y    R180 S0      
327GND              R5281 -1          A01X+087315Y+079423X0198Y0197     S1      
317GND              VIA   -    MD0100PA00X+178040Y+125127X0200Y    R180 S0      
317GND              VIA   -    MD0100PA00X+178040Y+124877X0200Y    R180 S0      
317GND              VIA   -    MD0100PA00X+003041Y+123920X0200Y    R180 S0      
317GND              VIA   -    MD0100PA00X+003041Y+124170X0200Y    R180 S0      
317GND              VIA   -    MD0100PA00X+094997Y+132175X0200Y         S0      
317GND              VIA   -    MD0100PA00X+142565Y+129741X0200Y         S0      
317GND              VIA   -    MD0100PA00X+143641Y+130346X0200Y         S0      
317GND              VIA   -    MD0100PA00X+062227Y+086478X0200Y         S0      
317GND              VIA   -    MD0100PA00X+181632Y+097722X0200Y         S0      
317GND              VIA   -    MD0100PA00X+183151Y+097889X0200Y         S0      
317GND              VIA   -    MD0100PA00X+082900Y+085200X0200Y         S0      
317GND              VIA   -    MD0100PA00X+081750Y+076000X0200Y         S0      
317GND              VIA   -    MD0100PA00X+082050Y+077750X0200Y         S0      
317GND              VIA   -    MD0100PA00X+082050Y+079200X0200Y         S0      
327GND              R5917 -1          A01X+081990Y+090092X0198Y0197R180 S1      
327GND              C2628 -1          A01X+082692Y+076650X0198Y0197     S1      
317GND              VIA   -    MD0100PA00X+082692Y+076900X0200Y         S0      
327GND              C2626 -1          A01X+082692Y+078450X0198Y0197     S1      
317GND              VIA   -    MD0100PA00X+082692Y+078700X0200Y         S0      
317GND              VIA   -    MD0100PA00X+084950Y+079700X0200Y         S0      
317GND              VIA   -    MD0100PA00X+084950Y+077900X0200Y         S0      
317GND              VIA   -    MD0100PA00X+084950Y+076100X0200Y         S0      
317GND              VIA   -    MD0100PA00X+086458Y+077050X0200Y         S0      
327GND              C2705 -1          A01X+086458Y+076800X0198Y0197R180 S1      
317GND              VIA   -    MD0100PA00X+084150Y+075816X0200Y         S0      
327GND              U122  -4          A01X+083670Y+075816X0140Y0590R270 S1      
317GND              VIA   -    MD0100PA00X+086458Y+078850X0200Y         S0      
327GND              C2627 -1          A01X+086458Y+078600X0198Y0197R180 S1      
317GND              VIA   -    MD0100PA00X+084150Y+077616X0200Y         S0      
327GND              U121  -4          A01X+083670Y+077616X0140Y0590R270 S1      
317GND              VIA   -    MD0100PA00X+086458Y+080650X0200Y         S0      
327GND              C2625 -1          A01X+086458Y+080400X0198Y0197R180 S1      
317GND              VIA   -    MD0100PA00X+084150Y+079416X0200Y         S0      
327GND              U120  -4          A01X+083670Y+079416X0140Y0590R270 S1      
317GND              VIA   -    MD0100PA00X+082692Y+080500X0200Y         S0      
327GND              C2556 -1          A01X+082692Y+080250X0198Y0197     S1      
327GND              U119  -4          A01X+083670Y+081216X0140Y0590R270 S1      
327GND              R6305 -2          A01X+084600Y+089842X0198Y0197R270 S1      
317GND              VIA   -    MD0100PA00X+151028Y+089973X0200Y         S0      
327GND              R6167 -2          A18X+057561Y+088484X0198Y0197R180 S2      
327GND              R6170 -2          A18X+103269Y+088484X0198Y0197R180 S2      
327GND              R6173 -2          A18X+149111Y+088462X0198Y0197R090 S2      
327GND              R6164 -2          A18X+011867Y+088484X0198Y0197R180 S2      
327GND              C2791 -2          A01X+092096Y+054735X0198Y0197     S1      
327GND              C2792 -2          A01X+091058Y+054735X0198Y0197R180 S1      
327GND              Y7    -4          A01X+091998Y+053371X0480Y0590R270 S1      
327GND              Y7    -2          A01X+091163Y+054001X0480Y0590R270 S1      
317GND              VIA   -    MD0100PA00X+094184Y+027897X0200Y    R090 S0      
317GND              VIA   -    MD0100PA00X+103018Y+028871X0200Y    R090 S0      
317GND              VIA   -    MD0100PA00X+079322Y+014030X0200Y         S0      
317GND              VIA   -    MD0100PA00X+125031Y+014030X0200Y         S0      
317GND              VIA   -    MD0100PA00X+134182Y+094741X0200Y         S0      
317GND              VIA   -    MD0100PA00X+132355Y+096762X0200Y         S0      
317GND              VIA   -    MD0100PA00X+088261Y+099424X0200Y         S0      
327GND              C2700 -2          A18X+039493Y+130724X0198Y0197     S2      
317GND              VIA   -    MD0100PA00X+039128Y+130724X0200Y         S0      
317GND              VIA   -    MD0100PA00X+176529Y+157543X0200Y    R180 S0      
317GND              VIA   -    MD0100PA00X+175858Y+158103X0200Y    R180 S0      
317GND              VIA   -    MD0100PA00X+056064Y+154353X0200Y         S0      
317GND              VIA   -    MD0100PA00X+051807Y+069938X0200Y         S0      
317GND              VIA   -    MD0100PA00X+052695Y+069944X0200Y         S0      
317GND              VIA   -    MD0100PA00X+052263Y+070388X0200Y         S0      
327GND              U94   -TH  M      A01X+096337Y+109367X0670Y0670R180 S1      
327GND              U94   -10         A01X+095786Y+109465X0090Y0240R090 S1      
327GND              U90   -TH  M      A01X+089940Y+109367X0670Y0670R180 S1      
327GND              U90   -10         A01X+089388Y+109465X0090Y0240R090 S1      
327GND              U385  -3          A01X+021100Y+013674X0240Y0240     S1      
327GND              PU82  -3          A01X+011135Y+011368X0100Y0280     S1      
327GND              PU79  -3          A01X+036466Y+045408X0100Y0280R090 S1      
327GND              J45   -A1         A01X+172033Y+007398X0150Y0500R090 S1      
327GND              J45   -A2         A01X+172033Y+007634X0150Y0500R090 S1      
327GND              J45   -A3         A01X+172033Y+007870X0150Y0500R090 S1      
327GND              J45   -A4         A01X+172033Y+008106X0150Y0500R090 S1      
327GND              J45   -A5         A01X+172033Y+008342X0150Y0500R090 S1      
327GND              J45   -A6         A01X+172033Y+008579X0150Y0500R090 S1      
327GND              J45   -A13 M      A01X+172033Y+010232X0150Y0500R090 S1      
327GND              J45   -A16 M      A01X+172033Y+010941X0150Y0500R090 S1      
327GND              J45   -A19 M      A01X+172033Y+011650X0150Y0500R090 S1      
327GND              J45   -A22 M      A01X+172033Y+012358X0150Y0500R090 S1      
327GND              J45   -A25 M      A01X+172033Y+013067X0150Y0500R090 S1      
327GND              J45   -A28 M      A01X+172033Y+013776X0150Y0500R090 S1      
327GND              J45   -B13 M      A01X+173844Y+010232X0150Y0500R090 S1      
327GND              J45   -B16 M      A01X+173844Y+010941X0150Y0500R090 S1      
327GND              J45   -B19 M      A01X+173844Y+011650X0150Y0500R090 S1      
327GND              J45   -B22 M      A01X+173844Y+012358X0150Y0500R090 S1      
327GND              J45   -B25 M      A01X+173844Y+013067X0150Y0500R090 S1      
327GND              J45   -B28 M      A01X+173844Y+013776X0150Y0500R090 S1      
317GND              J45   -G1  MD0440PA00X+172939Y+006071X0640Y1370R090 S3      
317GND              J45   -G2  MD0440PA00X+172939Y+015020X0640Y1370R090 S3      
327GND              J44   -A1         A01X+161797Y+007398X0150Y0500R090 S1      
327GND              J44   -A2         A01X+161797Y+007634X0150Y0500R090 S1      
327GND              J44   -A3         A01X+161797Y+007870X0150Y0500R090 S1      
327GND              J44   -A4         A01X+161797Y+008106X0150Y0500R090 S1      
327GND              J44   -A5         A01X+161797Y+008342X0150Y0500R090 S1      
327GND              J44   -A6         A01X+161797Y+008579X0150Y0500R090 S1      
327GND              J44   -A13 M      A01X+161797Y+010232X0150Y0500R090 S1      
327GND              J44   -A16 M      A01X+161797Y+010941X0150Y0500R090 S1      
327GND              J44   -A19 M      A01X+161797Y+011650X0150Y0500R090 S1      
327GND              J44   -A22 M      A01X+161797Y+012358X0150Y0500R090 S1      
327GND              J44   -A25 M      A01X+161797Y+013067X0150Y0500R090 S1      
327GND              J44   -A28 M      A01X+161797Y+013776X0150Y0500R090 S1      
327GND              J44   -B13 M      A01X+163608Y+010232X0150Y0500R090 S1      
327GND              J44   -B16 M      A01X+163608Y+010941X0150Y0500R090 S1      
327GND              J44   -B19 M      A01X+163608Y+011650X0150Y0500R090 S1      
327GND              J44   -B22 M      A01X+163608Y+012358X0150Y0500R090 S1      
327GND              J44   -B25 M      A01X+163608Y+013067X0150Y0500R090 S1      
327GND              J44   -B28 M      A01X+163608Y+013776X0150Y0500R090 S1      
317GND              J44   -G1  MD0440PA00X+162703Y+006071X0640Y1370R090 S3      
317GND              J44   -G2  MD0440PA00X+162703Y+015020X0640Y1370R090 S3      
327GND              J43   -A1         A01X+151561Y+007398X0150Y0500R090 S1      
327GND              J43   -A2         A01X+151561Y+007634X0150Y0500R090 S1      
327GND              J43   -A3         A01X+151561Y+007870X0150Y0500R090 S1      
327GND              J43   -A4         A01X+151561Y+008106X0150Y0500R090 S1      
327GND              J43   -A5         A01X+151561Y+008342X0150Y0500R090 S1      
327GND              J43   -A6         A01X+151561Y+008579X0150Y0500R090 S1      
327GND              J43   -A13 M      A01X+151561Y+010232X0150Y0500R090 S1      
327GND              J43   -A16 M      A01X+151561Y+010941X0150Y0500R090 S1      
327GND              J43   -A19 M      A01X+151561Y+011650X0150Y0500R090 S1      
327GND              J43   -A22 M      A01X+151561Y+012358X0150Y0500R090 S1      
327GND              J43   -A25 M      A01X+151561Y+013067X0150Y0500R090 S1      
327GND              J43   -A28 M      A01X+151561Y+013776X0150Y0500R090 S1      
327GND              J43   -B13 M      A01X+153372Y+010232X0150Y0500R090 S1      
327GND              J43   -B16 M      A01X+153372Y+010941X0150Y0500R090 S1      
327GND              J43   -B19 M      A01X+153372Y+011650X0150Y0500R090 S1      
327GND              J43   -B22 M      A01X+153372Y+012358X0150Y0500R090 S1      
327GND              J43   -B25 M      A01X+153372Y+013067X0150Y0500R090 S1      
327GND              J43   -B28 M      A01X+153372Y+013776X0150Y0500R090 S1      
317GND              J43   -G1  MD0440PA00X+152466Y+006071X0640Y1370R090 S3      
317GND              J43   -G2  MD0440PA00X+152466Y+015020X0640Y1370R090 S3      
327GND              J42   -A1         A01X+141325Y+007398X0150Y0500R090 S1      
327GND              J42   -A2         A01X+141325Y+007634X0150Y0500R090 S1      
327GND              J42   -A3         A01X+141325Y+007870X0150Y0500R090 S1      
327GND              J42   -A4         A01X+141325Y+008106X0150Y0500R090 S1      
327GND              J42   -A5         A01X+141325Y+008342X0150Y0500R090 S1      
327GND              J42   -A6         A01X+141325Y+008579X0150Y0500R090 S1      
327GND              J42   -A13 M      A01X+141325Y+010232X0150Y0500R090 S1      
327GND              J42   -A16 M      A01X+141325Y+010941X0150Y0500R090 S1      
327GND              J42   -A19 M      A01X+141325Y+011650X0150Y0500R090 S1      
327GND              J42   -A22 M      A01X+141325Y+012358X0150Y0500R090 S1      
327GND              J42   -A25 M      A01X+141325Y+013067X0150Y0500R090 S1      
327GND              J42   -A28 M      A01X+141325Y+013776X0150Y0500R090 S1      
327GND              J42   -B13 M      A01X+143136Y+010232X0150Y0500R090 S1      
327GND              J42   -B16 M      A01X+143136Y+010941X0150Y0500R090 S1      
327GND              J42   -B19 M      A01X+143136Y+011650X0150Y0500R090 S1      
327GND              J42   -B22 M      A01X+143136Y+012358X0150Y0500R090 S1      
327GND              J42   -B25 M      A01X+143136Y+013067X0150Y0500R090 S1      
327GND              J42   -B28 M      A01X+143136Y+013776X0150Y0500R090 S1      
317GND              J42   -G1  MD0440PA00X+142230Y+006071X0640Y1370R090 S3      
317GND              J42   -G2  MD0440PA00X+142230Y+015020X0640Y1370R090 S3      
327GND              J41   -A1         A01X+126325Y+007398X0150Y0500R090 S1      
327GND              J41   -A2         A01X+126325Y+007634X0150Y0500R090 S1      
327GND              J41   -A3         A01X+126325Y+007870X0150Y0500R090 S1      
327GND              J41   -A4         A01X+126325Y+008106X0150Y0500R090 S1      
327GND              J41   -A5         A01X+126325Y+008342X0150Y0500R090 S1      
327GND              J41   -A6         A01X+126325Y+008579X0150Y0500R090 S1      
327GND              J41   -A13 M      A01X+126325Y+010232X0150Y0500R090 S1      
327GND              J41   -A16 M      A01X+126325Y+010941X0150Y0500R090 S1      
327GND              J41   -A19 M      A01X+126325Y+011650X0150Y0500R090 S1      
327GND              J41   -A22 M      A01X+126325Y+012358X0150Y0500R090 S1      
327GND              J41   -A25 M      A01X+126325Y+013067X0150Y0500R090 S1      
327GND              J41   -A28 M      A01X+126325Y+013776X0150Y0500R090 S1      
327GND              J41   -B13 M      A01X+128136Y+010232X0150Y0500R090 S1      
327GND              J41   -B16 M      A01X+128136Y+010941X0150Y0500R090 S1      
327GND              J41   -B19 M      A01X+128136Y+011650X0150Y0500R090 S1      
327GND              J41   -B22 M      A01X+128136Y+012358X0150Y0500R090 S1      
327GND              J41   -B25 M      A01X+128136Y+013067X0150Y0500R090 S1      
327GND              J41   -B28 M      A01X+128136Y+013776X0150Y0500R090 S1      
317GND              J41   -G1  MD0440PA00X+127230Y+006071X0640Y1370R090 S3      
317GND              J41   -G2  MD0440PA00X+127230Y+015020X0640Y1370R090 S3      
327GND              J40   -A1         A01X+116088Y+007398X0150Y0500R090 S1      
327GND              J40   -A2         A01X+116088Y+007634X0150Y0500R090 S1      
327GND              J40   -A3         A01X+116088Y+007870X0150Y0500R090 S1      
327GND              J40   -A4         A01X+116088Y+008106X0150Y0500R090 S1      
327GND              J40   -A5         A01X+116088Y+008342X0150Y0500R090 S1      
327GND              J40   -A6         A01X+116088Y+008579X0150Y0500R090 S1      
327GND              J40   -A13 M      A01X+116088Y+010232X0150Y0500R090 S1      
327GND              J40   -A16 M      A01X+116088Y+010941X0150Y0500R090 S1      
327GND              J40   -A19 M      A01X+116088Y+011650X0150Y0500R090 S1      
327GND              J40   -A22 M      A01X+116088Y+012358X0150Y0500R090 S1      
327GND              J40   -A25 M      A01X+116088Y+013067X0150Y0500R090 S1      
327GND              J40   -A28 M      A01X+116088Y+013776X0150Y0500R090 S1      
327GND              J40   -B13 M      A01X+117900Y+010232X0150Y0500R090 S1      
327GND              J40   -B16 M      A01X+117900Y+010941X0150Y0500R090 S1      
327GND              J40   -B19 M      A01X+117900Y+011650X0150Y0500R090 S1      
327GND              J40   -B22 M      A01X+117900Y+012358X0150Y0500R090 S1      
327GND              J40   -B25 M      A01X+117900Y+013067X0150Y0500R090 S1      
327GND              J40   -B28 M      A01X+117900Y+013776X0150Y0500R090 S1      
317GND              J40   -G1  MD0440PA00X+116994Y+006071X0640Y1370R090 S3      
317GND              J40   -G2  MD0440PA00X+116994Y+015020X0640Y1370R090 S3      
327GND              J39   -A1         A01X+105852Y+007398X0150Y0500R090 S1      
327GND              J39   -A2         A01X+105852Y+007634X0150Y0500R090 S1      
327GND              J39   -A3         A01X+105852Y+007870X0150Y0500R090 S1      
327GND              J39   -A4         A01X+105852Y+008106X0150Y0500R090 S1      
327GND              J39   -A5         A01X+105852Y+008342X0150Y0500R090 S1      
327GND              J39   -A6         A01X+105852Y+008579X0150Y0500R090 S1      
327GND              J39   -A13 M      A01X+105852Y+010232X0150Y0500R090 S1      
327GND              J39   -A16 M      A01X+105852Y+010941X0150Y0500R090 S1      
327GND              J39   -A19 M      A01X+105852Y+011650X0150Y0500R090 S1      
327GND              J39   -A22 M      A01X+105852Y+012358X0150Y0500R090 S1      
327GND              J39   -A25 M      A01X+105852Y+013067X0150Y0500R090 S1      
327GND              J39   -A28 M      A01X+105852Y+013776X0150Y0500R090 S1      
327GND              J39   -B13 M      A01X+107663Y+010232X0150Y0500R090 S1      
327GND              J39   -B16 M      A01X+107663Y+010941X0150Y0500R090 S1      
327GND              J39   -B19 M      A01X+107663Y+011650X0150Y0500R090 S1      
327GND              J39   -B22 M      A01X+107663Y+012358X0150Y0500R090 S1      
327GND              J39   -B25 M      A01X+107663Y+013067X0150Y0500R090 S1      
327GND              J39   -B28 M      A01X+107663Y+013776X0150Y0500R090 S1      
317GND              J39   -G1  MD0440PA00X+106758Y+006071X0640Y1370R090 S3      
317GND              J39   -G2  MD0440PA00X+106758Y+015020X0640Y1370R090 S3      
327GND              J38   -A1         A01X+095616Y+007398X0150Y0500R090 S1      
327GND              J38   -A2         A01X+095616Y+007634X0150Y0500R090 S1      
327GND              J38   -A3         A01X+095616Y+007870X0150Y0500R090 S1      
327GND              J38   -A4         A01X+095616Y+008106X0150Y0500R090 S1      
327GND              J38   -A5         A01X+095616Y+008342X0150Y0500R090 S1      
327GND              J38   -A6         A01X+095616Y+008579X0150Y0500R090 S1      
327GND              J38   -A13 M      A01X+095616Y+010232X0150Y0500R090 S1      
327GND              J38   -A16 M      A01X+095616Y+010941X0150Y0500R090 S1      
327GND              J38   -A19 M      A01X+095616Y+011650X0150Y0500R090 S1      
327GND              J38   -A22 M      A01X+095616Y+012358X0150Y0500R090 S1      
327GND              J38   -A25 M      A01X+095616Y+013067X0150Y0500R090 S1      
327GND              J38   -A28 M      A01X+095616Y+013776X0150Y0500R090 S1      
327GND              J38   -B13 M      A01X+097427Y+010232X0150Y0500R090 S1      
327GND              J38   -B16 M      A01X+097427Y+010941X0150Y0500R090 S1      
327GND              J38   -B19 M      A01X+097427Y+011650X0150Y0500R090 S1      
327GND              J38   -B22 M      A01X+097427Y+012358X0150Y0500R090 S1      
327GND              J38   -B25 M      A01X+097427Y+013067X0150Y0500R090 S1      
327GND              J38   -B28 M      A01X+097427Y+013776X0150Y0500R090 S1      
317GND              J38   -G1  MD0440PA00X+096522Y+006071X0640Y1370R090 S3      
317GND              J38   -G2  MD0440PA00X+096522Y+015020X0640Y1370R090 S3      
327GND              J37   -A1         A01X+080616Y+007398X0150Y0500R090 S1      
327GND              J37   -A2         A01X+080616Y+007634X0150Y0500R090 S1      
327GND              J37   -A3         A01X+080616Y+007870X0150Y0500R090 S1      
327GND              J37   -A4         A01X+080616Y+008106X0150Y0500R090 S1      
327GND              J37   -A5         A01X+080616Y+008342X0150Y0500R090 S1      
327GND              J37   -A6         A01X+080616Y+008579X0150Y0500R090 S1      
327GND              J37   -A13 M      A01X+080616Y+010232X0150Y0500R090 S1      
327GND              J37   -A16 M      A01X+080616Y+010941X0150Y0500R090 S1      
327GND              J37   -A19 M      A01X+080616Y+011650X0150Y0500R090 S1      
327GND              J37   -A22 M      A01X+080616Y+012358X0150Y0500R090 S1      
327GND              J37   -A25 M      A01X+080616Y+013067X0150Y0500R090 S1      
327GND              J37   -A28 M      A01X+080616Y+013776X0150Y0500R090 S1      
327GND              J37   -B13 M      A01X+082427Y+010232X0150Y0500R090 S1      
327GND              J37   -B16 M      A01X+082427Y+010941X0150Y0500R090 S1      
327GND              J37   -B19 M      A01X+082427Y+011650X0150Y0500R090 S1      
327GND              J37   -B22 M      A01X+082427Y+012358X0150Y0500R090 S1      
327GND              J37   -B25 M      A01X+082427Y+013067X0150Y0500R090 S1      
327GND              J37   -B28 M      A01X+082427Y+013776X0150Y0500R090 S1      
317GND              J37   -G1  MD0440PA00X+081522Y+006071X0640Y1370R090 S3      
317GND              J37   -G2  MD0440PA00X+081522Y+015020X0640Y1370R090 S3      
327GND              J36   -A1         A01X+070380Y+007398X0150Y0500R090 S1      
327GND              J36   -A2         A01X+070380Y+007634X0150Y0500R090 S1      
327GND              J36   -A3         A01X+070380Y+007870X0150Y0500R090 S1      
327GND              J36   -A4         A01X+070380Y+008106X0150Y0500R090 S1      
327GND              J36   -A5         A01X+070380Y+008342X0150Y0500R090 S1      
327GND              J36   -A6         A01X+070380Y+008579X0150Y0500R090 S1      
327GND              J36   -A13 M      A01X+070380Y+010232X0150Y0500R090 S1      
327GND              J36   -A16 M      A01X+070380Y+010941X0150Y0500R090 S1      
327GND              J36   -A19 M      A01X+070380Y+011650X0150Y0500R090 S1      
327GND              J36   -A22 M      A01X+070380Y+012358X0150Y0500R090 S1      
327GND              J36   -A25 M      A01X+070380Y+013067X0150Y0500R090 S1      
327GND              J36   -A28 M      A01X+070380Y+013776X0150Y0500R090 S1      
327GND              J36   -B13 M      A01X+072191Y+010232X0150Y0500R090 S1      
327GND              J36   -B16 M      A01X+072191Y+010941X0150Y0500R090 S1      
327GND              J36   -B19 M      A01X+072191Y+011650X0150Y0500R090 S1      
327GND              J36   -B22 M      A01X+072191Y+012358X0150Y0500R090 S1      
327GND              J36   -B25 M      A01X+072191Y+013067X0150Y0500R090 S1      
327GND              J36   -B28 M      A01X+072191Y+013776X0150Y0500R090 S1      
317GND              J36   -G1  MD0440PA00X+071285Y+006071X0640Y1370R090 S3      
317GND              J36   -G2  MD0440PA00X+071285Y+015020X0640Y1370R090 S3      
327GND              J35   -A1         A01X+060144Y+007398X0150Y0500R090 S1      
327GND              J35   -A2         A01X+060144Y+007634X0150Y0500R090 S1      
327GND              J35   -A3         A01X+060144Y+007870X0150Y0500R090 S1      
327GND              J35   -A4         A01X+060144Y+008106X0150Y0500R090 S1      
327GND              J35   -A5         A01X+060144Y+008342X0150Y0500R090 S1      
327GND              J35   -A6         A01X+060144Y+008579X0150Y0500R090 S1      
327GND              J35   -A13 M      A01X+060144Y+010232X0150Y0500R090 S1      
327GND              J35   -A16 M      A01X+060144Y+010941X0150Y0500R090 S1      
327GND              J35   -A19 M      A01X+060144Y+011650X0150Y0500R090 S1      
327GND              J35   -A22 M      A01X+060144Y+012358X0150Y0500R090 S1      
327GND              J35   -A25 M      A01X+060144Y+013067X0150Y0500R090 S1      
327GND              J35   -A28 M      A01X+060144Y+013776X0150Y0500R090 S1      
327GND              J35   -B13 M      A01X+061955Y+010232X0150Y0500R090 S1      
327GND              J35   -B16 M      A01X+061955Y+010941X0150Y0500R090 S1      
327GND              J35   -B19 M      A01X+061955Y+011650X0150Y0500R090 S1      
327GND              J35   -B22 M      A01X+061955Y+012358X0150Y0500R090 S1      
327GND              J35   -B25 M      A01X+061955Y+013067X0150Y0500R090 S1      
327GND              J35   -B28 M      A01X+061955Y+013776X0150Y0500R090 S1      
317GND              J35   -G1  MD0440PA00X+061049Y+006071X0640Y1370R090 S3      
317GND              J35   -G2  MD0440PA00X+061049Y+015020X0640Y1370R090 S3      
327GND              J34   -A1         A01X+049908Y+007398X0150Y0500R090 S1      
327GND              J34   -A2         A01X+049908Y+007634X0150Y0500R090 S1      
327GND              J34   -A3         A01X+049908Y+007870X0150Y0500R090 S1      
327GND              J34   -A4         A01X+049908Y+008106X0150Y0500R090 S1      
327GND              J34   -A5         A01X+049908Y+008342X0150Y0500R090 S1      
327GND              J34   -A6         A01X+049908Y+008579X0150Y0500R090 S1      
327GND              J34   -A13 M      A01X+049908Y+010232X0150Y0500R090 S1      
327GND              J34   -A16 M      A01X+049908Y+010941X0150Y0500R090 S1      
327GND              J34   -A19 M      A01X+049908Y+011650X0150Y0500R090 S1      
327GND              J34   -A22 M      A01X+049908Y+012358X0150Y0500R090 S1      
327GND              J34   -A25 M      A01X+049908Y+013067X0150Y0500R090 S1      
327GND              J34   -A28 M      A01X+049908Y+013776X0150Y0500R090 S1      
327GND              J34   -B13 M      A01X+051718Y+010232X0150Y0500R090 S1      
327GND              J34   -B16 M      A01X+051718Y+010941X0150Y0500R090 S1      
327GND              J34   -B19 M      A01X+051718Y+011650X0150Y0500R090 S1      
327GND              J34   -B22 M      A01X+051718Y+012358X0150Y0500R090 S1      
327GND              J34   -B25 M      A01X+051718Y+013067X0150Y0500R090 S1      
327GND              J34   -B28 M      A01X+051718Y+013776X0150Y0500R090 S1      
317GND              J34   -G1  MD0440PA00X+050813Y+006071X0640Y1370R090 S3      
317GND              J34   -G2  MD0440PA00X+050813Y+015020X0640Y1370R090 S3      
327GND              J33   -A1         A01X+034907Y+007398X0150Y0500R090 S1      
327GND              J33   -A2         A01X+034907Y+007634X0150Y0500R090 S1      
327GND              J33   -A3         A01X+034907Y+007870X0150Y0500R090 S1      
327GND              J33   -A4         A01X+034907Y+008106X0150Y0500R090 S1      
327GND              J33   -A5         A01X+034907Y+008342X0150Y0500R090 S1      
327GND              J33   -A6         A01X+034907Y+008579X0150Y0500R090 S1      
327GND              J33   -A13 M      A01X+034907Y+010232X0150Y0500R090 S1      
327GND              J33   -A16 M      A01X+034907Y+010941X0150Y0500R090 S1      
327GND              J33   -A19 M      A01X+034907Y+011650X0150Y0500R090 S1      
327GND              J33   -A22 M      A01X+034907Y+012358X0150Y0500R090 S1      
327GND              J33   -A25 M      A01X+034907Y+013067X0150Y0500R090 S1      
327GND              J33   -A28 M      A01X+034907Y+013776X0150Y0500R090 S1      
327GND              J33   -B13 M      A01X+036718Y+010232X0150Y0500R090 S1      
327GND              J33   -B16 M      A01X+036718Y+010941X0150Y0500R090 S1      
327GND              J33   -B19 M      A01X+036718Y+011650X0150Y0500R090 S1      
327GND              J33   -B22 M      A01X+036718Y+012358X0150Y0500R090 S1      
327GND              J33   -B25 M      A01X+036718Y+013067X0150Y0500R090 S1      
327GND              J33   -B28 M      A01X+036718Y+013776X0150Y0500R090 S1      
317GND              J33   -G1  MD0440PA00X+035813Y+006071X0640Y1370R090 S3      
317GND              J33   -G2  MD0440PA00X+035813Y+015020X0640Y1370R090 S3      
327GND              J32   -A1         A01X+024671Y+007398X0150Y0500R090 S1      
327GND              J32   -A2         A01X+024671Y+007634X0150Y0500R090 S1      
327GND              J32   -A3         A01X+024671Y+007870X0150Y0500R090 S1      
327GND              J32   -A4         A01X+024671Y+008106X0150Y0500R090 S1      
327GND              J32   -A5         A01X+024671Y+008342X0150Y0500R090 S1      
327GND              J32   -A6         A01X+024671Y+008579X0150Y0500R090 S1      
327GND              J32   -A13 M      A01X+024671Y+010232X0150Y0500R090 S1      
327GND              J32   -A16 M      A01X+024671Y+010941X0150Y0500R090 S1      
327GND              J32   -A19 M      A01X+024671Y+011650X0150Y0500R090 S1      
327GND              J32   -A22 M      A01X+024671Y+012358X0150Y0500R090 S1      
327GND              J32   -A25 M      A01X+024671Y+013067X0150Y0500R090 S1      
327GND              J32   -A28 M      A01X+024671Y+013776X0150Y0500R090 S1      
327GND              J32   -B13 M      A01X+026482Y+010232X0150Y0500R090 S1      
327GND              J32   -B16 M      A01X+026482Y+010941X0150Y0500R090 S1      
327GND              J32   -B19 M      A01X+026482Y+011650X0150Y0500R090 S1      
327GND              J32   -B22 M      A01X+026482Y+012358X0150Y0500R090 S1      
327GND              J32   -B25 M      A01X+026482Y+013067X0150Y0500R090 S1      
327GND              J32   -B28 M      A01X+026482Y+013776X0150Y0500R090 S1      
317GND              J32   -G1  MD0440PA00X+025577Y+006071X0640Y1370R090 S3      
317GND              J32   -G2  MD0440PA00X+025577Y+015020X0640Y1370R090 S3      
327GND              J31   -A1         A01X+014435Y+007398X0150Y0500R090 S1      
327GND              J31   -A2         A01X+014435Y+007634X0150Y0500R090 S1      
327GND              J31   -A3         A01X+014435Y+007870X0150Y0500R090 S1      
327GND              J31   -A4         A01X+014435Y+008106X0150Y0500R090 S1      
327GND              J31   -A5         A01X+014435Y+008342X0150Y0500R090 S1      
327GND              J31   -A6         A01X+014435Y+008579X0150Y0500R090 S1      
327GND              J31   -A13 M      A01X+014435Y+010232X0150Y0500R090 S1      
327GND              J31   -A16 M      A01X+014435Y+010941X0150Y0500R090 S1      
327GND              J31   -A19 M      A01X+014435Y+011650X0150Y0500R090 S1      
327GND              J31   -A22 M      A01X+014435Y+012358X0150Y0500R090 S1      
327GND              J31   -A25 M      A01X+014435Y+013067X0150Y0500R090 S1      
327GND              J31   -A28 M      A01X+014435Y+013776X0150Y0500R090 S1      
327GND              J31   -B13 M      A01X+016246Y+010232X0150Y0500R090 S1      
327GND              J31   -B16 M      A01X+016246Y+010941X0150Y0500R090 S1      
327GND              J31   -B19 M      A01X+016246Y+011650X0150Y0500R090 S1      
327GND              J31   -B22 M      A01X+016246Y+012358X0150Y0500R090 S1      
327GND              J31   -B25 M      A01X+016246Y+013067X0150Y0500R090 S1      
327GND              J31   -B28 M      A01X+016246Y+013776X0150Y0500R090 S1      
317GND              J31   -G1  MD0440PA00X+015340Y+006071X0640Y1370R090 S3      
317GND              J31   -G2  MD0440PA00X+015340Y+015020X0640Y1370R090 S3      
327GND              J30   -A1         A01X+004199Y+007398X0150Y0500R090 S1      
327GND              J30   -A2         A01X+004199Y+007634X0150Y0500R090 S1      
327GND              J30   -A3         A01X+004199Y+007870X0150Y0500R090 S1      
327GND              J30   -A4         A01X+004199Y+008106X0150Y0500R090 S1      
327GND              J30   -A5         A01X+004199Y+008342X0150Y0500R090 S1      
327GND              J30   -A6         A01X+004199Y+008579X0150Y0500R090 S1      
327GND              J30   -A13 M      A01X+004199Y+010232X0150Y0500R090 S1      
327GND              J30   -A16 M      A01X+004199Y+010941X0150Y0500R090 S1      
327GND              J30   -A19 M      A01X+004199Y+011650X0150Y0500R090 S1      
327GND              J30   -A22 M      A01X+004199Y+012358X0150Y0500R090 S1      
327GND              J30   -A25 M      A01X+004199Y+013067X0150Y0500R090 S1      
327GND              J30   -A28 M      A01X+004199Y+013776X0150Y0500R090 S1      
327GND              J30   -B13 M      A01X+006010Y+010232X0150Y0500R090 S1      
327GND              J30   -B16 M      A01X+006010Y+010941X0150Y0500R090 S1      
327GND              J30   -B19 M      A01X+006010Y+011650X0150Y0500R090 S1      
327GND              J30   -B22 M      A01X+006010Y+012358X0150Y0500R090 S1      
327GND              J30   -B25 M      A01X+006010Y+013067X0150Y0500R090 S1      
327GND              J30   -B28 M      A01X+006010Y+013776X0150Y0500R090 S1      
317GND              J30   -G1  MD0440PA00X+005104Y+006071X0640Y1370R090 S3      
317GND              J30   -G2  MD0440PA00X+005104Y+015020X0640Y1370R090 S3      
317GND              VIA   -    MD0100PA00X+093158Y+059067X0200Y    R270 S0      
317GND              VIA   -    MD0100PA00X+093162Y+058442X0200Y    R270 S0      
317GND              VIA   -    MD0100PA00X+093165Y+059327X0200Y    R270 S0      
317GND              VIA   -    MD0100PA00X+093159Y+059942X0200Y    R270 S0      
317GND              VIA   -    MD0100PA00X+094469Y+035219X0200Y         S0      
327GND              R1019 -1          A01X+094175Y+035128X0198Y0197R180 S1      
317GND              VIA   -    MD0100PA00X+142747Y+096562X0200Y         S0      
317GND              VIA   -    MD0100PA00X+071869Y+050963X0200Y         S0      
317GND              VIA   -    M      A01X+002882Y+068214X0200Y    R090 S2      
017GND              VIA   -    M      A18X+002882Y+068214X0260Y    R090 S2      
017GND                    -    MD0100PA00X+002882Y+068214                       
317GND              VIA   -    MD0100PA00X+081989Y+073692X0200Y    R090 S0      
317GND              VIA   -    MD0100PA00X+081549Y+073292X0200Y    R090 S0      
317GND              VIA   -    MD0100PA00X+141104Y+098538X0200Y         S0      
317GND              VIA   -    MD0100PA00X+182583Y+109759X0200Y    R270 S0      
317GND              VIA   -    MD0100PA00X+040785Y+149212X0200Y    R180 S0      
317GND              VIA   -    MD0100PA00X+040747Y+149504X0200Y    R180 S0      
317GND              VIA   -    MD0100PA00X+040638Y+149914X0200Y    R180 S0      
317GND              H81   -5   MD0220PA00X+101083Y+039862X0300Y         S3      
317GND              H81   -4   MD0220PA00X+102087Y+040278X0300Y         S3      
317GND              H81   -3   MD0220PA00X+103090Y+039862X0300Y         S3      
317GND              H81   -6   MD0220PA00X+100667Y+038858X0300Y         S3      
317GND              H81   -2   MD0220PA00X+103506Y+038858X0300Y         S3      
317GND              H81   -7   MD0220PA00X+101083Y+037854X0300Y         S3      
317GND              H81   -8   MD0220PA00X+102087Y+037438X0300Y         S3      
317GND              H81   -9   MD0220PA00X+103090Y+037854X0300Y         S3      
317GND              H79   -5   MD0220PA00X+081004Y+039862X0300Y         S3      
317GND              H79   -4   MD0220PA00X+082008Y+040278X0300Y         S3      
317GND              H79   -3   MD0220PA00X+083012Y+039862X0300Y         S3      
317GND              H79   -6   MD0220PA00X+080588Y+038858X0300Y         S3      
317GND              H79   -2   MD0220PA00X+083428Y+038858X0300Y         S3      
317GND              H79   -7   MD0220PA00X+081004Y+037854X0300Y         S3      
317GND              H79   -8   MD0220PA00X+082008Y+037438X0300Y         S3      
317GND              H79   -9   MD0220PA00X+083012Y+037854X0300Y         S3      
317GND              VIA   -    MD0100PA00X+133828Y+034160X0200Y         S0      
317GND              VIA   -    MD0100PA00X+090246Y+053076X0200Y         S0      
327GND              PC500 -2          A01X+002152Y+020686X0198Y0197R180 S1      
327GND              PC501 -2          A01X+001874Y+020064X0400Y0500     S1      
327GND              PC535 -1          A01X+001242Y+020701X0400Y0500R270 S1      
327GND              PC510 -2          A01X+001782Y+020983X0198Y0197R270 S1      
327GND              PD60  -A          A01X+001478Y+018984X0670Y0990R090 S1      
327GND              PC671 -2          A01X+002720Y+015515X0400Y0500R090 S1      
327GND              PC668 -2          A01X+000826Y+015596X0198Y0197R270 S1      
327GND              C3875 -2          A01X+002282Y+005530X0198Y0197R180 S1      
327GND              C3874 -2          A01X+002673Y+006753X0198Y0197R180 S1      
327GND              C3873 -2          A01X+002673Y+006353X0198Y0197R180 S1      
327GND              C3872 -2          A01X+002673Y+005953X0198Y0197R180 S1      
327GND              C3877 -2          A01X+002282Y+005130X0198Y0197R180 S1      
327GND              C3876 -2          A01X+007338Y+009160X0198Y0197R090 S1      
327GND              C3878 -2          A01X+006938Y+009160X0198Y0197R090 S1      
327GND              PC661 -2          A01X+007264Y+044892X0400Y0500R090 S1      
327GND              PD86  -A          A01X+005962Y+028679X0670Y0990     S1      
327GND              PC643 -2          A01X+007024Y+028116X0400Y0500R270 S1      
327GND              PD21  -A          A01X+007169Y+024257X0850Y0890     S1      
327GND              PC356 -2          A01X+007688Y+021976X0198Y0197R090 S1      
327GND              PC367 -1          A01X+007700Y+022962X0400Y0500R180 S1      
327GND              PC390 -2          A01X+007982Y+022432X0198Y0197R180 S1      
327GND              PC357 -2          A01X+007066Y+022254X0400Y0500R270 S1      
327GND              PD22  -A          A01X+005985Y+022750X0670Y0990     S1      
327GND              PD84  -A          A01X+010083Y+029098X0850Y0890R270 S1      
327GND              PC639 -2          A01X+008984Y+027838X0198Y0197R090 S1      
327GND              PU76  -3          A01X+008297Y+027748X0100Y0280R180 S1      
327GND              PC673 -2          A01X+012360Y+011267X0400Y0500R090 S1      
327GND              C2763 -2          A01X+012721Y+010650X0198Y0197R180 S1      
327GND              PC669 -2          A01X+010466Y+011348X0198Y0197R270 S1      
327GND              PC513 -2          A01X+012111Y+020064X0400Y0500     S1      
327GND              PC512 -2          A01X+012388Y+020686X0198Y0197R180 S1      
327GND              PC520 -2          A01X+012018Y+020983X0198Y0197R270 S1      
327GND              PC509 -1          A01X+011478Y+020701X0400Y0500R270 S1      
327GND              PD62  -A          A01X+011714Y+018984X0670Y0990R090 S1      
327GND              PD87  -A          A01X+016198Y+028679X0670Y0990     S1      
327GND              PC369 -2          A01X+017260Y+028116X0400Y0500R270 S1      
327GND              PD25  -A          A01X+017405Y+024257X0850Y0890     S1      
327GND              PC645 -2          A01X+017302Y+022254X0400Y0500R270 S1      
327GND              PC368 -2          A01X+017924Y+021976X0198Y0197R090 S1      
327GND              PC377 -1          A01X+017936Y+022962X0400Y0500R180 S1      
327GND              PC402 -2          A01X+018218Y+022432X0198Y0197R180 S1      
327GND              PD26  -A          A01X+016221Y+022750X0670Y0990     S1      
327GND              C3879 -2          A01X+018375Y+009160X0198Y0197R090 S1      
327GND              C3885 -2          A01X+017574Y+009160X0198Y0197R090 S1      
327GND              C3884 -2          A01X+017174Y+009160X0198Y0197R090 S1      
327GND              C3880 -2          A01X+017974Y+009160X0198Y0197R090 S1      
327GND              C3883 -2          A01X+018641Y+008014X0198Y0197     S1      
327GND              C3882 -2          A01X+018641Y+007614X0198Y0197     S1      
327GND              C3881 -2          A01X+018641Y+008414X0198Y0197     S1      
327GND              PD88  -A          A01X+020320Y+029098X0850Y0890R270 S1      
327GND              PU75  -3          A01X+018534Y+027748X0100Y0280R180 S1      
327GND              PC649 -2          A01X+019221Y+027838X0198Y0197R090 S1      
327GND              PC681 -2          A01X+022596Y+011267X0400Y0500R090 S1      
327GND              PC678 -2          A01X+020702Y+011348X0198Y0197R270 S1      
327GND              PC523 -1          A01X+021715Y+020701X0400Y0500R270 S1      
327GND              PC525 -2          A01X+022347Y+020064X0400Y0500     S1      
327GND              PC524 -2          A01X+022625Y+020686X0198Y0197R180 S1      
327GND              PC534 -2          A01X+022255Y+020983X0198Y0197R270 S1      
327GND              PD65  -A          A01X+021950Y+018984X0670Y0990R090 S1      
327GND              C3888 -2          A01X+028210Y+009160X0198Y0197R090 S1      
327GND              C3886 -2          A01X+028611Y+009160X0198Y0197R090 S1      
327GND              C3892 -2          A01X+027810Y+009160X0198Y0197R090 S1      
327GND              C3890 -2          A01X+027410Y+009160X0198Y0197R090 S1      
327GND              C3889 -2          A01X+028877Y+008414X0198Y0197     S1      
327GND              C3887 -2          A01X+028877Y+007614X0198Y0197     S1      
327GND              C3891 -2          A01X+028877Y+008014X0198Y0197     S1      
327GND              PD90  -A          A01X+026434Y+028679X0670Y0990     S1      
327GND              PC381 -2          A01X+027496Y+028116X0400Y0500R270 S1      
327GND              PD29  -A          A01X+027642Y+024257X0850Y0890     S1      
327GND              PC376 -2          A01X+028455Y+022432X0198Y0197R180 S1      
327GND              PC380 -2          A01X+028160Y+021976X0198Y0197R090 S1      
327GND              PC355 -1          A01X+028172Y+022962X0400Y0500R180 S1      
327GND              PC650 -2          A01X+027538Y+022254X0400Y0500R270 S1      
327GND              PD30  -A          A01X+026457Y+022750X0670Y0990     S1      
327GND              C863  -2          A18X+028793Y+044332X0120Y0150     S2      
327GND              C874  -2          A18X+028690Y+045515X0198Y0197     S2      
327GND              C870  -2          A18X+028690Y+045115X0198Y0197     S2      
327GND              C866  -2          A18X+028793Y+043692X0120Y0150     S2      
327GND              C865  -2          A18X+028793Y+043352X0120Y0150     S2      
327GND              C864  -2          A18X+028793Y+043012X0120Y0150     S2      
327GND              C862  -2          A18X+028793Y+044012X0120Y0150     S2      
327GND              PD85  -A          A01X+030556Y+029098X0850Y0890R270 S1      
327GND              PC648 -2          A01X+029457Y+027838X0198Y0197R090 S1      
327GND              PU78  -3          A01X+028770Y+027748X0100Y0280R180 S1      
327GND              PC683 -2          A01X+032832Y+011267X0400Y0500R090 S1      
327GND              PC679 -2          A01X+030939Y+011348X0198Y0197R270 S1      
327GND              PC539 -2          A01X+032583Y+020064X0400Y0500     S1      
327GND              PC499 -1          A01X+031951Y+020701X0400Y0500R270 S1      
327GND              PC498 -2          A01X+032491Y+020983X0198Y0197R270 S1      
327GND              PC538 -2          A01X+032861Y+020686X0198Y0197R180 S1      
327GND              PD66  -A          A01X+032187Y+018984X0670Y0990R090 S1      
327GND              C861  -2          A01X+031755Y+044643X0400Y0500R270 S1      
327GND              C860  -2          A01X+031755Y+041994X0400Y0500R090 S1      
327GND              PD10  -A          A01X+039052Y+045321X0670Y0990     S1      
327GND              PC604 -2          A01X+036204Y+044140X0400Y0500R270 S1      
327GND              PD91  -A          A01X+036670Y+028679X0670Y0990     S1      
327GND              PC655 -2          A01X+037732Y+028116X0400Y0500R270 S1      
327GND              PD33  -A          A01X+037878Y+024257X0850Y0890     S1      
327GND              PC392 -2          A01X+038396Y+021976X0198Y0197R090 S1      
327GND              PC391 -1          A01X+038408Y+022962X0400Y0500R180 S1      
327GND              PC354 -2          A01X+038691Y+022432X0198Y0197R180 S1      
327GND              PC393 -2          A01X+037774Y+022254X0400Y0500R270 S1      
327GND              PD34  -A          A01X+036693Y+022750X0670Y0990     S1      
327GND              C3897 -2          A01X+038047Y+009160X0198Y0197R090 S1      
327GND              C3893 -2          A01X+038848Y+009160X0198Y0197R090 S1      
327GND              C3898 -2          A01X+038447Y+009160X0198Y0197R090 S1      
327GND              C3894 -2          A01X+037647Y+009160X0198Y0197R090 S1      
327GND              C3896 -2          A01X+039113Y+008414X0198Y0197     S1      
327GND              C3895 -2          A01X+039113Y+008014X0198Y0197     S1      
327GND              C3899 -2          A01X+039113Y+007614X0198Y0197     S1      
327GND              PC663 -2          A01X+036568Y+046633X0400Y0500R180 S1      
327GND              PC605 -2          A01X+037992Y+044800X0400Y0500R270 S1      
327GND              PC606 -2          A01X+037192Y+044800X0400Y0500R270 S1      
327GND              PC659 -2          A01X+036490Y+044736X0198Y0197     S1      
327GND              PC618 -2          A01X+041556Y+042541X0198Y0197R180 S1      
327GND              PD77  -A          A01X+041173Y+041438X0850Y0890     S1      
327GND              PD79  -A          A01X+039773Y+041895X0670Y0990R270 S1      
327GND              PD12  -A          A01X+041280Y+040011X0850Y0890R270 S1      
327GND              PC307 -1          A01X+039985Y+039880X0400Y0500R090 S1      
327GND              PC306 -2          A01X+039455Y+039598X0198Y0197R090 S1      
327GND              PC321 -2          A01X+039277Y+040814X0400Y0500R180 S1      
327GND              PC320 -2          A01X+038999Y+040192X0198Y0197     S1      
327GND              PD89  -A          A01X+040792Y+029098X0850Y0890R270 S1      
327GND              PC638 -2          A01X+039693Y+027838X0198Y0197R090 S1      
327GND              PU77  -3          A01X+039006Y+027748X0100Y0280R180 S1      
327GND              C2662 -2          A18X+041096Y+031848X0400Y0500R270 S2      
327GND              PC611 -1          A01X+041167Y+045500X0280Y0320R180 S1      
327GND              PR6874-2          A01X+041810Y+045530X0198Y0197R180 S1      
327GND              C2668 -2          A18X+043498Y+034968X0198Y0197     S2      
327GND              C2665 -2          A18X+043127Y+034970X0198Y0197R180 S2      
327GND              C2672 -2          A18X+042390Y+034741X0198Y0197R090 S2      
327GND              C2667 -2          A18X+043096Y+033116X0198Y0197R270 S2      
327GND              C2669 -2          A18X+043576Y+033391X0198Y0197     S2      
327GND              C2664 -2          A18X+043609Y+034287X0198Y0197     S2      
327GND              C2663 -2          A18X+042402Y+033122X0198Y0197R270 S2      
327GND              C2671 -2          A18X+042072Y+034300X0198Y0197R180 S2      
327GND              C2666 -2          A18X+042114Y+033452X0198Y0197R180 S2      
327GND              PC921 -2          A01X+047832Y+011267X0400Y0500R090 S1      
327GND              PC918 -2          A01X+045939Y+011348X0198Y0197R270 S1      
327GND              PC502 -2          A01X+047861Y+020686X0198Y0197R180 S1      
327GND              PC503 -2          A01X+047583Y+020064X0400Y0500     S1      
327GND              PC533 -1          A01X+046951Y+020701X0400Y0500R270 S1      
327GND              PC508 -2          A01X+047491Y+020983X0198Y0197R270 S1      
327GND              PD61  -A          A01X+047187Y+018984X0670Y0990R090 S1      
327GND              PC617 -2          A01X+044375Y+044310X0198Y0197     S1      
327GND              PU72  -7          A01X+042918Y+044404X0100Y0320R090 S1      
327GND              C840  -1          A01X+044375Y+042810X0198Y0197R180 S1      
327GND              PC616 -2          A01X+044375Y+043510X0198Y0197     S1      
327GND              PR6876-2          A01X+044375Y+043910X0198Y0197     S1      
327GND              R944  -1          A01X+044375Y+043160X0198Y0197R180 S1      
327GND              C3900 -2          A01X+053848Y+009160X0198Y0197R090 S1      
327GND              C3903 -2          A01X+053047Y+009160X0198Y0197R090 S1      
327GND              C3902 -2          A01X+053447Y+009160X0198Y0197R090 S1      
327GND              C3904 -2          A01X+052647Y+009160X0198Y0197R090 S1      
327GND              C3906 -2          A01X+054113Y+008014X0198Y0197     S1      
327GND              C3905 -2          A01X+054113Y+007614X0198Y0197     S1      
327GND              C3901 -2          A01X+054113Y+008414X0198Y0197     S1      
327GND              PC791 -2          A01X+052773Y+044592X0400Y0500R090 S1      
327GND              PD102 -A          A01X+051670Y+028679X0670Y0990     S1      
327GND              PC841 -2          A01X+052732Y+028116X0400Y0500R270 S1      
327GND              PD16  -A          A01X+052878Y+024257X0850Y0890     S1      
327GND              PC359 -2          A01X+052774Y+022254X0400Y0500R270 S1      
327GND              PC358 -2          A01X+053396Y+021976X0198Y0197R090 S1      
327GND              PC317 -1          A01X+053408Y+022962X0400Y0500R180 S1      
327GND              PC316 -2          A01X+053691Y+022432X0198Y0197R180 S1      
327GND              PD23  -A          A01X+051694Y+022750X0670Y0990     S1      
327GND              PD105 -A          A01X+055792Y+029098X0850Y0890R270 S1      
327GND              PC839 -2          A01X+054693Y+027838X0198Y0197R090 S1      
327GND              PU107 -3          A01X+054006Y+027748X0100Y0280R180 S1      
327GND              PC515 -2          A01X+057819Y+020064X0400Y0500     S1      
327GND              PC514 -2          A01X+058097Y+020686X0198Y0197R180 S1      
327GND              PC532 -2          A01X+057727Y+020983X0198Y0197R270 S1      
327GND              PC521 -1          A01X+057187Y+020701X0400Y0500R270 S1      
327GND              PD63  -A          A01X+057423Y+018984X0670Y0990R090 S1      
327GND              PC923 -2          A01X+058069Y+011267X0400Y0500R090 S1      
327GND              PC919 -2          A01X+056175Y+011348X0198Y0197R270 S1      
327GND              PD103 -A          A01X+061907Y+028679X0670Y0990     S1      
327GND              PC844 -2          A01X+062968Y+028116X0400Y0500R270 S1      
327GND              PD28  -A          A01X+063114Y+024257X0850Y0890     S1      
327GND              PC366 -2          A01X+063927Y+022432X0198Y0197R180 S1      
327GND              PC371 -2          A01X+063011Y+022254X0400Y0500R270 S1      
327GND              PC370 -2          A01X+063633Y+021976X0198Y0197R090 S1      
327GND              PC379 -1          A01X+063645Y+022962X0400Y0500R180 S1      
327GND              PD27  -A          A01X+061930Y+022750X0670Y0990     S1      
327GND              C3907 -2          A01X+064084Y+009160X0198Y0197R090 S1      
327GND              C3910 -2          A01X+063283Y+009160X0198Y0197R090 S1      
327GND              C3913 -2          A01X+063683Y+009160X0198Y0197R090 S1      
327GND              C3911 -2          A01X+062883Y+009160X0198Y0197R090 S1      
327GND              C3912 -2          A01X+064349Y+007614X0198Y0197     S1      
327GND              C3909 -2          A01X+064349Y+008414X0198Y0197     S1      
327GND              C3908 -2          A01X+064349Y+008014X0198Y0197     S1      
327GND              PD101 -A          A01X+066028Y+029098X0850Y0890R270 S1      
327GND              PU108 -3          A01X+064242Y+027748X0100Y0280R180 S1      
327GND              PC848 -2          A01X+064929Y+027838X0198Y0197R090 S1      
327GND              PC931 -2          A01X+068305Y+011267X0400Y0500R090 S1      
327GND              PC928 -2          A01X+066411Y+011348X0198Y0197R270 S1      
327GND              PC527 -2          A01X+068056Y+020064X0400Y0500     S1      
327GND              PC511 -1          A01X+067423Y+020701X0400Y0500R270 S1      
327GND              PC522 -2          A01X+067963Y+020983X0198Y0197R270 S1      
327GND              PC526 -2          A01X+068333Y+020686X0198Y0197R180 S1      
327GND              PD64  -A          A01X+067659Y+018984X0670Y0990R090 S1      
327GND              C3914 -2          A01X+074320Y+009160X0198Y0197R090 S1      
327GND              C3920 -2          A01X+073919Y+009160X0198Y0197R090 S1      
327GND              C3915 -2          A01X+073519Y+009160X0198Y0197R090 S1      
327GND              C3917 -2          A01X+073119Y+009160X0198Y0197R090 S1      
327GND              C3918 -2          A01X+074586Y+008414X0198Y0197     S1      
327GND              C3916 -2          A01X+074586Y+007614X0198Y0197     S1      
327GND              C3919 -2          A01X+074586Y+008014X0198Y0197     S1      
327GND              PD106 -A          A01X+072143Y+028679X0670Y0990     S1      
327GND              PC854 -2          A01X+073205Y+028116X0400Y0500R270 S1      
327GND              PD32  -A          A01X+073350Y+024257X0850Y0890     S1      
327GND              PC382 -2          A01X+073869Y+021976X0198Y0197R090 S1      
327GND              PC389 -1          A01X+073881Y+022962X0400Y0500R180 S1      
327GND              PC378 -2          A01X+074163Y+022432X0198Y0197R180 S1      
327GND              PD31  -A          A01X+072166Y+022750X0670Y0990     S1      
327GND              PC383 -2          A01X+073247Y+022254X0400Y0500R270 S1      
327GND              C895  -2          A18X+074501Y+044332X0120Y0150     S2      
327GND              C899  -2          A18X+074398Y+045515X0198Y0197     S2      
327GND              C898  -2          A18X+074398Y+045115X0198Y0197     S2      
327GND              C892  -2          A18X+074501Y+044012X0120Y0150     S2      
327GND              C893  -2          A18X+074501Y+043012X0120Y0150     S2      
327GND              C894  -2          A18X+074501Y+043352X0120Y0150     S2      
327GND              C896  -2          A18X+074501Y+043692X0120Y0150     S2      
327GND              PD100 -A          A01X+076264Y+029098X0850Y0890R270 S1      
327GND              PC838 -2          A01X+075166Y+027838X0198Y0197R090 S1      
327GND              PU109 -3          A01X+074478Y+027748X0100Y0280R180 S1      
327GND              C890  -2          A01X+078043Y+041994X0400Y0500R090 S1      
327GND              C891  -2          A01X+077343Y+041994X0400Y0500R090 S1      
327GND              PC536 -2          A01X+078570Y+020686X0198Y0197R180 S1      
327GND              PC537 -2          A01X+078292Y+020064X0400Y0500     S1      
327GND              PC496 -2          A01X+078200Y+020983X0198Y0197R270 S1      
327GND              PC497 -1          A01X+077660Y+020701X0400Y0500R270 S1      
327GND              PD67  -A          A01X+077895Y+018984X0670Y0990R090 S1      
327GND              PD35  -A          A01X+082379Y+028679X0670Y0990     S1      
327GND              PC395 -2          A01X+083441Y+028116X0400Y0500R270 S1      
327GND              PD20  -A          A01X+083586Y+024257X0850Y0890     S1      
327GND              PC394 -2          A01X+084105Y+021976X0198Y0197R090 S1      
327GND              PC365 -1          A01X+084117Y+022962X0400Y0500R180 S1      
327GND              PC388 -2          A01X+084400Y+022432X0198Y0197R180 S1      
327GND              PC856 -2          A01X+083483Y+022254X0400Y0500R270 S1      
327GND              PD107 -A          A01X+082402Y+022750X0670Y0990     S1      
327GND              C3924 -2          A01X+083355Y+009160X0198Y0197R090 S1      
327GND              C3926 -2          A01X+083755Y+009160X0198Y0197R090 S1      
327GND              C3921 -2          A01X+084556Y+009160X0198Y0197R090 S1      
327GND              C3923 -2          A01X+084155Y+009160X0198Y0197R090 S1      
327GND              C3927 -2          A01X+084822Y+007614X0198Y0197     S1      
327GND              C3922 -2          A01X+084822Y+008014X0198Y0197     S1      
327GND              C3925 -2          A01X+084822Y+008414X0198Y0197     S1      
327GND              PD104 -A          A01X+086501Y+029098X0850Y0890R270 S1      
327GND              PC849 -2          A01X+085402Y+027838X0198Y0197R090 S1      
327GND              PU110 -3          A01X+084715Y+027748X0100Y0280R180 S1      
327GND              PD80  -A          A01X+090506Y+043072X0850Y0890     S1      
327GND              PC599 -2          A01X+091088Y+044175X0198Y0197R180 S1      
327GND              PD83  -A          A01X+089306Y+043229X0670Y0990R270 S1      
327GND              PD8   -A          A01X+090813Y+041645X0850Y0890R270 S1      
327GND              PC626 -2          A01X+088809Y+042148X0400Y0500R180 S1      
327GND              PC344 -2          A01X+088532Y+041526X0198Y0197     S1      
327GND              PC341 -1          A01X+089518Y+041514X0400Y0500R090 S1      
327GND              PC340 -2          A01X+088988Y+041232X0198Y0197R090 S1      
327GND              PC631 -1          A01X+090700Y+047134X0280Y0320R180 S1      
327GND              PR6898-2          A01X+091342Y+047164X0198Y0197R180 S1      
327GND              PC549 -2          A01X+093358Y+018582X0400Y0500     S1      
327GND              PC548 -2          A01X+093636Y+019204X0198Y0197R180 S1      
327GND              PC568 -2          A01X+093266Y+019500X0198Y0197R270 S1      
327GND              PC547 -1          A01X+092726Y+019218X0400Y0500R270 S1      
327GND              PD68  -A          A01X+092962Y+017501X0670Y0990R090 S1      
327GND              PC941 -2          A01X+093541Y+011267X0400Y0500R090 S1      
327GND              PC938 -2          A01X+091647Y+011348X0198Y0197R270 S1      
327GND              C2614 -2          A18X+091882Y+036880X0198Y0197R090 S2      
327GND              C2621 -2          A18X+092725Y+036662X0198Y0197     S2      
327GND              C2615 -2          A18X+091546Y+036589X0198Y0197R180 S2      
327GND              C2617 -2          A18X+092762Y+036013X0198Y0197     S2      
327GND              C2620 -2          A18X+092414Y+035797X0198Y0197R270 S2      
327GND              C2619 -2          A18X+091895Y+035790X0198Y0197R270 S2      
327GND              C2616 -2          A18X+091522Y+036058X0198Y0197R180 S2      
327GND              PC637 -2          A01X+093907Y+045944X0198Y0197     S1      
327GND              C842  -1          A01X+093907Y+044444X0198Y0197R180 S1      
327GND              PC636 -2          A01X+093907Y+045144X0198Y0197     S1      
327GND              PR6900-2          A01X+093907Y+045544X0198Y0197     S1      
327GND              R950  -1          A01X+093907Y+044794X0198Y0197R180 S1      
327GND              PD38  -A          A01X+097379Y+028679X0670Y0990     S1      
327GND              PC405 -2          A01X+098441Y+028116X0400Y0500R270 S1      
327GND              PD113 -A          A01X+098586Y+024257X0850Y0890     S1      
327GND              PC861 -2          A01X+098483Y+022254X0400Y0500R270 S1      
327GND              PC404 -2          A01X+099105Y+021976X0198Y0197R090 S1      
327GND              PC401 -1          A01X+099117Y+022962X0400Y0500R180 S1      
327GND              PC400 -2          A01X+099400Y+022432X0198Y0197R180 S1      
327GND              PD111 -A          A01X+097402Y+022750X0670Y0990     S1      
327GND              C3928 -2          A01X+099556Y+009160X0198Y0197R090 S1      
327GND              C3931 -2          A01X+098355Y+009160X0198Y0197R090 S1      
327GND              C3933 -2          A01X+098755Y+009160X0198Y0197R090 S1      
327GND              C3934 -2          A01X+099155Y+009160X0198Y0197R090 S1      
327GND              C3929 -2          A01X+099822Y+008414X0198Y0197     S1      
327GND              C3930 -2          A01X+099822Y+007614X0198Y0197     S1      
327GND              C3932 -2          A01X+099822Y+008014X0198Y0197     S1      
327GND              PC901 -2          A01X+098682Y+044892X0400Y0500R090 S1      
327GND              U113  -B12        A01X+101251Y+031961X0110Y0180     S1      
327GND              U113  -B10        A01X+101005Y+032404X0110Y0180R090 S1      
327GND              C2648 -2          A18X+103371Y+033774X0198Y0197     S2      
327GND              C2647 -2          A18X+103378Y+033352X0198Y0197     S2      
327GND              C2645 -2          A18X+102883Y+034107X0198Y0197R090 S2      
327GND              C2646 -2          A18X+102034Y+034113X0198Y0197R090 S2      
327GND              C2651 -2          A18X+101083Y+033309X0198Y0197R180 S2      
327GND              C2643 -2          A18X+101083Y+033988X0198Y0197R180 S2      
327GND              C2633 -2          A18X+103373Y+032475X0198Y0197     S2      
327GND              C2631 -2          A18X+102967Y+032048X0198Y0197R270 S2      
327GND              C2635 -2          A18X+102145Y+032048X0198Y0197R270 S2      
327GND              C2632 -2          A18X+102592Y+032040X0198Y0197R270 S2      
327GND              C2641 -2          A18X+101083Y+032751X0198Y0197R180 S2      
327GND              C2639 -2          A18X+101083Y+032339X0198Y0197R180 S2      
327GND              PD36  -A          A01X+101501Y+029098X0850Y0890R270 S1      
327GND              PU111 -3          A01X+099715Y+027748X0100Y0280R180 S1      
327GND              PC859 -2          A01X+100402Y+027838X0198Y0197R090 S1      
327GND              PC557 -1          A01X+102896Y+020701X0400Y0500R270 S1      
327GND              PC561 -2          A01X+103528Y+020064X0400Y0500     S1      
327GND              PC560 -2          A01X+103806Y+020686X0198Y0197R180 S1      
327GND              PC580 -2          A01X+103436Y+020983X0198Y0197R270 S1      
327GND              PD70  -A          A01X+103132Y+018984X0670Y0990R090 S1      
327GND              PC943 -2          A01X+103777Y+011267X0400Y0500R090 S1      
327GND              PC958 -2          A01X+101884Y+011348X0198Y0197R270 S1      
327GND              PD44  -A          A01X+108823Y+024257X0850Y0890     S1      
327GND              PC416 -2          A01X+109341Y+021976X0198Y0197R090 S1      
327GND              PC415 -1          A01X+109353Y+022962X0400Y0500R180 S1      
327GND              PC414 -2          A01X+109636Y+022432X0198Y0197R180 S1      
327GND              PC417 -2          A01X+108719Y+022254X0400Y0500R270 S1      
327GND              PD42  -A          A01X+107638Y+022750X0670Y0990     S1      
327GND              C3937 -2          A01X+109392Y+009160X0198Y0197R090 S1      
327GND              C3935 -2          A01X+109792Y+009160X0198Y0197R090 S1      
327GND              C3940 -2          A01X+108592Y+009160X0198Y0197R090 S1      
327GND              C3941 -2          A01X+108992Y+009160X0198Y0197R090 S1      
327GND              C3936 -2          A01X+110058Y+007614X0198Y0197     S1      
327GND              C3939 -2          A01X+110058Y+008014X0198Y0197     S1      
327GND              C3938 -2          A01X+110058Y+008414X0198Y0197     S1      
327GND              PD110 -A          A01X+107615Y+028679X0670Y0990     S1      
327GND              PC864 -2          A01X+108677Y+028116X0400Y0500R270 S1      
327GND              PD112 -A          A01X+111737Y+029098X0850Y0890R270 S1      
327GND              PU112 -3          A01X+109951Y+027748X0100Y0280R180 S1      
327GND              PC869 -2          A01X+110638Y+027838X0198Y0197R090 S1      
327GND              PC951 -2          A01X+114013Y+011267X0400Y0500R090 S1      
327GND              PC939 -2          A01X+112120Y+011348X0198Y0197R270 S1      
327GND              PC573 -2          A01X+113764Y+020064X0400Y0500     S1      
327GND              PC545 -1          A01X+113132Y+020701X0400Y0500R270 S1      
327GND              PC558 -2          A01X+113672Y+020983X0198Y0197R270 S1      
327GND              PC572 -2          A01X+114042Y+020686X0198Y0197R180 S1      
327GND              PD72  -A          A01X+113368Y+018984X0670Y0990R090 S1      
327GND              PD46  -A          A01X+117851Y+028679X0670Y0990     S1      
327GND              PC429 -2          A01X+118913Y+028116X0400Y0500R270 S1      
327GND              C3943 -2          A01X+119628Y+009160X0198Y0197R090 S1      
327GND              C3942 -2          A01X+120029Y+009160X0198Y0197R090 S1      
327GND              C3947 -2          A01X+119228Y+009160X0198Y0197R090 S1      
327GND              C3945 -2          A01X+118828Y+009160X0198Y0197R090 S1      
327GND              C3946 -2          A01X+120294Y+008414X0198Y0197     S1      
327GND              C3944 -2          A01X+120294Y+007614X0198Y0197     S1      
327GND              C3948 -2          A01X+120294Y+008014X0198Y0197     S1      
327GND              PD48  -A          A01X+119059Y+024257X0850Y0890     S1      
327GND              PC428 -2          A01X+119577Y+021976X0198Y0197R090 S1      
327GND              PC427 -1          A01X+119590Y+022962X0400Y0500R180 S1      
327GND              PC364 -2          A01X+119872Y+022432X0198Y0197R180 S1      
327GND              PD114 -A          A01X+117874Y+022750X0670Y0990     S1      
327GND              PC872 -2          A01X+118956Y+022254X0400Y0500R270 S1      
327GND              PD109 -A          A01X+121973Y+029098X0850Y0890R270 S1      
327GND              PC868 -2          A01X+120874Y+027838X0198Y0197R090 S1      
327GND              PU114 -3          A01X+120187Y+027748X0100Y0280R180 S1      
327GND              C922  -2          A18X+120210Y+044332X0120Y0150     S2      
327GND              C934  -2          A18X+120107Y+045515X0198Y0197     S2      
327GND              C929  -2          A18X+120107Y+045115X0198Y0197     S2      
327GND              C925  -2          A18X+120210Y+043352X0120Y0150     S2      
327GND              C924  -2          A18X+120210Y+043012X0120Y0150     S2      
327GND              C923  -2          A18X+120210Y+044012X0120Y0150     S2      
327GND              C926  -2          A18X+120210Y+043692X0120Y0150     S2      
327GND              PC953 -2          A01X+124250Y+011267X0400Y0500R090 S1      
327GND              PC959 -2          A01X+122356Y+011348X0198Y0197R270 S1      
327GND              C921  -2          A01X+123172Y+044643X0400Y0500R270 S1      
327GND              C920  -2          A01X+123172Y+041994X0400Y0500R090 S1      
327GND              PC586 -2          A01X+124000Y+020064X0400Y0500     S1      
327GND              PC546 -2          A01X+123908Y+020983X0198Y0197R270 S1      
327GND              PC585 -2          A01X+124278Y+020686X0198Y0197R180 S1      
327GND              PC583 -1          A01X+123368Y+020701X0400Y0500R270 S1      
327GND              PD75  -A          A01X+123604Y+018984X0670Y0990R090 S1      
327GND              PC903 -2          A01X+127985Y+046633X0400Y0500R180 S1      
327GND              PC804 -2          A01X+129409Y+044800X0400Y0500R270 S1      
327GND              PD95  -A          A01X+130475Y+045321X0670Y0990     S1      
327GND              PC805 -2          A01X+128609Y+044800X0400Y0500R270 S1      
327GND              PC898 -2          A01X+127907Y+044736X0198Y0197     S1      
327GND              PC323 -2          A01X+127622Y+044140X0400Y0500R270 S1      
327GND              PD50  -A          A01X+128088Y+028679X0670Y0990     S1      
327GND              PC876 -2          A01X+129150Y+028116X0400Y0500R270 S1      
327GND              PD49  -A          A01X+129295Y+024257X0850Y0890     S1      
327GND              PC441 -2          A01X+129192Y+022254X0400Y0500R270 S1      
327GND              PC440 -2          A01X+129814Y+021976X0198Y0197R090 S1      
327GND              PC425 -1          A01X+129826Y+022962X0400Y0500R180 S1      
327GND              PC436 -2          A01X+130108Y+022432X0198Y0197R180 S1      
327GND              PD115 -A          A01X+128111Y+022750X0670Y0990     S1      
327GND              C3951 -2          A01X+129864Y+009160X0198Y0197R090 S1      
327GND              C3953 -2          A01X+129464Y+009160X0198Y0197R090 S1      
327GND              C3949 -2          A01X+130265Y+009160X0198Y0197R090 S1      
327GND              C3952 -2          A01X+129064Y+009160X0198Y0197R090 S1      
327GND              C3950 -2          A01X+130530Y+008414X0198Y0197     S1      
327GND              C3954 -2          A01X+130530Y+007614X0198Y0197     S1      
327GND              C3955 -2          A01X+130530Y+008014X0198Y0197     S1      
327GND              PD97  -A          A01X+132590Y+041438X0850Y0890     S1      
327GND              PC818 -2          A01X+132973Y+042541X0198Y0197R180 S1      
327GND              PD11  -A          A01X+131190Y+041895X0670Y0990R270 S1      
327GND              PD96  -A          A01X+132697Y+040011X0850Y0890R270 S1      
327GND              PC806 -2          A01X+130694Y+040814X0400Y0500R180 S1      
327GND              PC322 -2          A01X+130416Y+040192X0198Y0197     S1      
327GND              PC319 -1          A01X+131403Y+039880X0400Y0500R090 S1      
327GND              PC318 -2          A01X+130873Y+039598X0198Y0197R090 S1      
327GND              C2673 -2          A18X+131354Y+032158X0400Y0500R270 S2      
327GND              PD108 -A          A01X+132209Y+029098X0850Y0890R270 S1      
327GND              PC858 -2          A01X+131110Y+027838X0198Y0197R090 S1      
327GND              PU113 -3          A01X+130423Y+027748X0100Y0280R180 S1      
327GND              C2677 -2          A18X+133867Y+034597X0198Y0197     S2      
327GND              C2679 -2          A18X+133756Y+035277X0198Y0197     S2      
327GND              C2682 -2          A18X+132334Y+034603X0198Y0197R180 S2      
327GND              C2680 -2          A18X+133385Y+035279X0198Y0197R180 S2      
327GND              C2683 -2          A18X+132649Y+035050X0198Y0197R090 S2      
327GND              C2678 -2          A18X+133834Y+033700X0198Y0197     S2      
327GND              C2675 -2          A18X+132373Y+033762X0198Y0197R180 S2      
327GND              C2674 -2          A18X+132660Y+033431X0198Y0197R270 S2      
327GND              C2676 -2          A18X+133372Y+033426X0198Y0197R270 S2      
327GND              PC812 -1          A01X+132585Y+045500X0280Y0320R180 S1      
327GND              PR7036-2          A01X+133227Y+045530X0198Y0197R180 S1      
327GND              PC551 -2          A01X+139000Y+020064X0400Y0500     S1      
327GND              PC544 -2          A01X+138908Y+020983X0198Y0197R270 S1      
327GND              PC550 -2          A01X+139278Y+020686X0198Y0197R180 S1      
327GND              PC581 -1          A01X+138368Y+020701X0400Y0500R270 S1      
327GND              PD69  -A          A01X+138604Y+018984X0670Y0990R090 S1      
327GND              PC962 -2          A01X+139250Y+011267X0400Y0500R090 S1      
327GND              PC948 -2          A01X+137356Y+011348X0198Y0197R270 S1      
327GND              PC817 -2          A01X+135792Y+044310X0198Y0197     S1      
327GND              PU104 -7          A01X+134336Y+044404X0100Y0320R090 S1      
327GND              C844  -1          A01X+135792Y+042810X0198Y0197R180 S1      
327GND              PC815 -2          A01X+135792Y+043510X0198Y0197     S1      
327GND              PR7037-2          A01X+135792Y+043910X0198Y0197     S1      
327GND              R956  -1          A01X+135792Y+043160X0198Y0197R180 S1      
327GND              C3956 -2          A01X+145265Y+009160X0198Y0197R090 S1      
327GND              C3957 -2          A01X+144464Y+009160X0198Y0197R090 S1      
327GND              C3959 -2          A01X+144064Y+009160X0198Y0197R090 S1      
327GND              C3962 -2          A01X+144864Y+009160X0198Y0197R090 S1      
327GND              C3961 -2          A01X+145530Y+008414X0198Y0197     S1      
327GND              C3958 -2          A01X+145530Y+007614X0198Y0197     S1      
327GND              C3960 -2          A01X+145530Y+008014X0198Y0197     S1      
327GND              PD118 -A          A01X+143088Y+028679X0670Y0990     S1      
327GND              PC883 -2          A01X+144150Y+028116X0400Y0500R270 S1      
327GND              PD41  -A          A01X+144295Y+024257X0850Y0890     S1      
327GND              PC412 -2          A01X+145108Y+022432X0198Y0197R180 S1      
327GND              PC407 -2          A01X+144192Y+022254X0400Y0500R270 S1      
327GND              PC406 -2          A01X+144814Y+021976X0198Y0197R090 S1      
327GND              PC413 -1          A01X+144826Y+022962X0400Y0500R180 S1      
327GND              PD39  -A          A01X+143111Y+022750X0670Y0990     S1      
327GND              PC911 -2          A01X+144190Y+044592X0400Y0500R090 S1      
327GND              PC966 -2          A01X+149486Y+011267X0400Y0500R090 S1      
327GND              PC949 -2          A01X+147592Y+011348X0198Y0197R270 S1      
327GND              PD116 -A          A01X+147209Y+029098X0850Y0890R270 S1      
327GND              PC888 -2          A01X+146110Y+027838X0198Y0197R090 S1      
327GND              PU115 -3          A01X+145423Y+027748X0100Y0280R180 S1      
327GND              PC563 -2          A01X+149237Y+020064X0400Y0500     S1      
327GND              PC559 -1          A01X+148604Y+020701X0400Y0500R270 S1      
327GND              PC556 -2          A01X+149144Y+020983X0198Y0197R270 S1      
327GND              PC562 -2          A01X+149514Y+020686X0198Y0197R180 S1      
327GND              PD71  -A          A01X+148840Y+018984X0670Y0990R090 S1      
327GND              PD119 -A          A01X+153324Y+028679X0670Y0990     S1      
327GND              PC886 -2          A01X+154386Y+028116X0400Y0500R270 S1      
327GND              PD45  -A          A01X+154531Y+024257X0850Y0890     S1      
327GND              PC418 -2          A01X+155050Y+021976X0198Y0197R090 S1      
327GND              PC437 -1          A01X+155062Y+022962X0400Y0500R180 S1      
327GND              PC424 -2          A01X+155344Y+022432X0198Y0197R180 S1      
327GND              PC419 -2          A01X+154428Y+022254X0400Y0500R270 S1      
327GND              PD43  -A          A01X+153347Y+022750X0670Y0990     S1      
327GND              C3963 -2          A01X+155501Y+009160X0198Y0197R090 S1      
327GND              C3969 -2          A01X+155100Y+009160X0198Y0197R090 S1      
327GND              C3966 -2          A01X+154700Y+009160X0198Y0197R090 S1      
327GND              C3964 -2          A01X+154300Y+009160X0198Y0197R090 S1      
327GND              C3965 -2          A01X+155767Y+008414X0198Y0197     S1      
327GND              C3967 -2          A01X+155767Y+007614X0198Y0197     S1      
327GND              C3968 -2          A01X+155767Y+008014X0198Y0197     S1      
327GND              PD117 -A          A01X+157446Y+029098X0850Y0890R270 S1      
327GND              PC889 -2          A01X+156347Y+027838X0198Y0197R090 S1      
327GND              PU116 -3          A01X+155660Y+027748X0100Y0280R180 S1      
327GND              PC972 -2          A01X+159722Y+011267X0400Y0500R090 S1      
327GND              PC968 -2          A01X+157828Y+011348X0198Y0197R270 S1      
327GND              PC574 -2          A01X+159751Y+020686X0198Y0197R180 S1      
327GND              PC575 -2          A01X+159473Y+020064X0400Y0500     S1      
327GND              PC569 -1          A01X+158841Y+020701X0400Y0500R270 S1      
327GND              PC570 -2          A01X+159381Y+020983X0198Y0197R270 S1      
327GND              PD73  -A          A01X+159076Y+018984X0670Y0990R090 S1      
327GND              PD47  -A          A01X+163560Y+028679X0670Y0990     S1      
327GND              PC431 -2          A01X+164622Y+028116X0400Y0500R270 S1      
327GND              PD121 -A          A01X+164768Y+024257X0850Y0890     S1      
327GND              PC430 -2          A01X+165286Y+021976X0198Y0197R090 S1      
327GND              PC439 -1          A01X+165298Y+022962X0400Y0500R180 S1      
327GND              PC426 -2          A01X+165581Y+022432X0198Y0197R180 S1      
327GND              PC892 -2          A01X+164664Y+022254X0400Y0500R270 S1      
327GND              PD122 -A          A01X+163583Y+022750X0670Y0990     S1      
327GND              C3972 -2          A01X+165336Y+009160X0198Y0197R090 S1      
327GND              C3970 -2          A01X+165737Y+009160X0198Y0197R090 S1      
327GND              C3976 -2          A01X+164536Y+009160X0198Y0197R090 S1      
327GND              C3971 -2          A01X+164936Y+009160X0198Y0197R090 S1      
327GND              C3973 -2          A01X+166003Y+008414X0198Y0197     S1      
327GND              C3974 -2          A01X+166003Y+008014X0198Y0197     S1      
327GND              C3975 -2          A01X+166003Y+007614X0198Y0197     S1      
327GND              C955  -2          A18X+165919Y+044332X0120Y0150     S2      
327GND              C964  -2          A18X+165816Y+045515X0198Y0197     S2      
327GND              C959  -2          A18X+165816Y+045115X0198Y0197     S2      
327GND              C956  -2          A18X+165919Y+043692X0120Y0150     S2      
327GND              C954  -2          A18X+165919Y+043352X0120Y0150     S2      
327GND              C953  -2          A18X+165919Y+043012X0120Y0150     S2      
327GND              C952  -2          A18X+165919Y+044012X0120Y0150     S2      
327GND              PD37  -A          A01X+167682Y+029098X0850Y0890R270 S1      
327GND              PC878 -2          A01X+166583Y+027838X0198Y0197R090 S1      
327GND              PU117 -3          A01X+165896Y+027748X0100Y0280R180 S1      
327GND              PC584 -2          A01X+169709Y+020064X0400Y0500     S1      
327GND              PC582 -2          A01X+169617Y+020983X0198Y0197R270 S1      
327GND              PC587 -2          A01X+169987Y+020686X0198Y0197R180 S1      
327GND              PC571 -1          A01X+169077Y+020701X0400Y0500R270 S1      
327GND              PD74  -A          A01X+169313Y+018984X0670Y0990R090 S1      
327GND              PC976 -2          A01X+169958Y+011267X0400Y0500R090 S1      
327GND              PC969 -2          A01X+168065Y+011348X0198Y0197R270 S1      
327GND              C950  -2          A01X+168881Y+044643X0400Y0500R270 S1      
327GND              C951  -2          A01X+168881Y+041994X0400Y0500R090 S1      
327GND              PD99  -A          A01X+176184Y+045321X0670Y0990     S1      
327GND              PC824 -2          A01X+173330Y+044140X0400Y0500R270 S1      
327GND              PD51  -A          A01X+173796Y+028679X0670Y0990     S1      
327GND              PC443 -2          A01X+174858Y+028116X0400Y0500R270 S1      
327GND              PD40  -A          A01X+175004Y+024257X0850Y0890     S1      
327GND              PC894 -2          A01X+174900Y+022254X0400Y0500R270 S1      
327GND              PC442 -2          A01X+175522Y+021976X0198Y0197R090 S1      
327GND              PC403 -1          A01X+175534Y+022962X0400Y0500R180 S1      
327GND              PC438 -2          A01X+175817Y+022432X0198Y0197R180 S1      
327GND              PD123 -A          A01X+173819Y+022750X0670Y0990     S1      
327GND              C3977 -2          A01X+175974Y+009160X0198Y0197R090 S1      
327GND              C3978 -2          A01X+175173Y+009160X0198Y0197R090 S1      
327GND              C3983 -2          A01X+175573Y+009160X0198Y0197R090 S1      
327GND              C3979 -2          A01X+174773Y+009160X0198Y0197R090 S1      
327GND              C3981 -2          A01X+176239Y+008014X0198Y0197     S1      
327GND              C3982 -2          A01X+176239Y+007614X0198Y0197     S1      
327GND              C3980 -2          A01X+176239Y+008414X0198Y0197     S1      
327GND              PC913 -2          A01X+173694Y+046633X0400Y0500R180 S1      
327GND              PC826 -2          A01X+175118Y+044800X0400Y0500R270 S1      
327GND              PC347 -2          A01X+174318Y+044800X0400Y0500R270 S1      
327GND              PC908 -2          A01X+173616Y+044736X0198Y0197     S1      
327GND              PD17  -A          A01X+178299Y+041438X0850Y0890     S1      
327GND              PC821 -2          A01X+178682Y+042541X0198Y0197R180 S1      
327GND              PD19  -A          A01X+176899Y+041895X0670Y0990R270 S1      
327GND              PD13  -A          A01X+178406Y+040011X0850Y0890R270 S1      
327GND              PC825 -2          A01X+176403Y+040814X0400Y0500R180 S1      
327GND              PC346 -2          A01X+176125Y+040192X0198Y0197     S1      
327GND              PC331 -1          A01X+177111Y+039880X0400Y0500R090 S1      
327GND              PC330 -2          A01X+176581Y+039598X0198Y0197R090 S1      
327GND              PD120 -A          A01X+177918Y+029098X0850Y0890R270 S1      
327GND              PU118 -3          A01X+176132Y+027748X0100Y0280R180 S1      
327GND              PC879 -2          A01X+176819Y+027838X0198Y0197R090 S1      
327GND              PC837 -2          A01X+181501Y+044310X0198Y0197     S1      
327GND              PU106 -7          A01X+180044Y+044404X0100Y0320R090 S1      
327GND              C982  -1          A01X+181501Y+042810X0198Y0197R180 S1      
327GND              PC836 -2          A01X+181501Y+043510X0198Y0197     S1      
327GND              PR7061-2          A01X+181501Y+043910X0198Y0197     S1      
327GND              R962  -1          A01X+181501Y+043160X0198Y0197R180 S1      
327GND              PC832 -1          A01X+178293Y+045500X0280Y0320R180 S1      
327GND              PR7059-2          A01X+178936Y+045530X0198Y0197R180 S1      
327GND              PD18  -A          A01X+088580Y+046955X0670Y0990     S1      
327GND              PC621 -2          A01X+087488Y+046768X0400Y0500R270 S1      
327GND              PC345 -2          A01X+086688Y+046768X0400Y0500R270 S1      
327GND              PC622 -2          A01X+085888Y+046768X0400Y0500R270 S1      
327GND              PC933 -2          A01X+078541Y+011267X0400Y0500R090 S1      
327GND              PC929 -2          A01X+076647Y+011348X0198Y0197R270 S1      
317GND              VIA   -    MD0100PA00X+026640Y+047258X0200Y         S0      
317GND              VIA   -    MD0100PA00X+027435Y+047526X0200Y    R180 S0      
317GND              VIA   -    MD0100PA00X+026640Y+048675X0200Y         S0      
317GND              VIA   -    MD0100PA00X+026640Y+047966X0200Y         S0      
317GND              VIA   -    MD0100PA00X+027435Y+048267X0200Y    R180 S0      
317GND              VIA   -    MD0100PA00X+025430Y+047258X0200Y         S0      
317GND              VIA   -    MD0100PA00X+025910Y+047258X0200Y         S0      
317GND              VIA   -    MD0100PA00X+026160Y+047258X0200Y         S0      
317GND              VIA   -    MD0100PA00X+025910Y+048675X0200Y         S0      
317GND              VIA   -    MD0100PA00X+025430Y+047967X0200Y         S0      
317GND              VIA   -    MD0100PA00X+026160Y+047967X0200Y         S0      
317GND              VIA   -    MD0100PA00X+025910Y+047967X0200Y         S0      
317GND              VIA   -    MD0100PA00X+025430Y+048675X0200Y         S0      
317GND              VIA   -    MD0100PA00X+026160Y+048675X0200Y         S0      
317GND              VIA   -    MD0100PA00X+020328Y+047463X0200Y    R180 S0      
317GND              VIA   -    MD0100PA00X+021538Y+047463X0200Y         S0      
317GND              VIA   -    MD0100PA00X+021058Y+047463X0200Y         S0      
317GND              VIA   -    MD0100PA00X+020808Y+047463X0200Y         S0      
317GND              VIA   -    MD0100PA00X+021538Y+048171X0200Y         S0      
317GND              VIA   -    MD0100PA00X+020808Y+048171X0200Y         S0      
317GND              VIA   -    MD0100PA00X+021058Y+048171X0200Y         S0      
317GND              VIA   -    MD0100PA00X+020328Y+048171X0200Y    R180 S0      
317GND              VIA   -    MD0100PA00X+019422Y+047277X0200Y         S0      
317GND              VIA   -    MD0100PA00X+018517Y+047463X0200Y    R180 S0      
317GND              VIA   -    MD0100PA00X+018543Y+048083X0200Y    R180 S0      
317GND              VIA   -    MD0100PA00X+019507Y+047910X0200Y         S0      
317GND              VIA   -    MD0100PA00X+017737Y+047463X0200Y         S0      
317GND              VIA   -    MD0100PA00X+017737Y+048171X0200Y         S0      
317GND              VIA   -    MD0100PA00X+015119Y+047572X0200Y    R090 S0      
317GND              VIA   -    MD0100PA00X+015119Y+048068X0200Y    R090 S0      
317GND              VIA   -    MD0100PA00X+014079Y+047356X0200Y    R090 S0      
317GND              VIA   -    MD0100PA00X+013579Y+047356X0200Y    R270 S0      
317GND              VIA   -    MD0100PA00X+014079Y+048278X0200Y    R090 S0      
317GND              VIA   -    MD0100PA00X+013579Y+048278X0200Y    R270 S0      
317GND              VIA   -    MD0100PA00X+014620Y+047572X0200Y    R270 S0      
317GND              VIA   -    MD0100PA00X+014620Y+048068X0200Y    R270 S0      
317GND              VIA   -    MD0100PA00X+007803Y+048359X0200Y    R270 S0      
317GND              VIA   -    MD0100PA00X+007803Y+047609X0200Y    R270 S0      
317GND              VIA   -    MD0100PA00X+007803Y+048109X0200Y    R270 S0      
317GND              VIA   -    MD0100PA00X+007803Y+047859X0200Y    R270 S0      
317GND              VIA   -    MD0100PA00X+006982Y+047845X0200Y    R270 S0      
317GND              VIA   -    MD0100PA00X+006982Y+047595X0200Y    R270 S0      
317GND              VIA   -    MD0100PA00X+007433Y+048070X0200Y    R180 S0      
317GND              VIA   -    MD0100PA00X+007183Y+048070X0200Y         S0      
317GND              VIA   -    MD0100PA00X+006637Y+048463X0200Y    R270 S0      
317GND              VIA   -    MD0100PA00X+006637Y+048213X0200Y    R270 S0      
317GND              VIA   -    MD0100PA00X+005364Y+047290X0200Y    R180 S0      
327GND              R5864 -2          A01X+005364Y+047049X0198Y0197R090 S1      
317GND              VIA   -    MD0100PA00X+003565Y+048398X0200Y    R180 S0      
327GND              PC481 -2          A01X+003823Y+048398X0198Y0197R180 S1      
317GND              VIA   -    MD0100PA00X+003565Y+047898X0200Y    R180 S0      
327GND              C2877 -2          A01X+003823Y+047898X0198Y0197R180 S1      
317GND              VIA   -    MD0100PA00X+063446Y+048171X0200Y         S0      
317GND              VIA   -    MD0100PA00X+060827Y+047572X0200Y    R090 S0      
317GND              VIA   -    MD0100PA00X+060827Y+048068X0200Y    R090 S0      
317GND              VIA   -    MD0100PA00X+059787Y+047356X0200Y    R090 S0      
317GND              VIA   -    MD0100PA00X+059288Y+047356X0200Y    R270 S0      
317GND              VIA   -    MD0100PA00X+059787Y+048278X0200Y    R090 S0      
317GND              VIA   -    MD0100PA00X+059288Y+048278X0200Y    R270 S0      
317GND              VIA   -    MD0100PA00X+060328Y+047572X0200Y    R270 S0      
317GND              VIA   -    MD0100PA00X+060328Y+048068X0200Y    R270 S0      
317GND              VIA   -    MD0100PA00X+052861Y+048070X0200Y    R180 S0      
317GND              VIA   -    MD0100PA00X+053512Y+047609X0200Y    R270 S0      
317GND              VIA   -    MD0100PA00X+053141Y+048070X0200Y    R180 S0      
317GND              VIA   -    MD0100PA00X+052690Y+047595X0200Y    R270 S0      
317GND              VIA   -    MD0100PA00X+052690Y+047845X0200Y    R270 S0      
317GND              VIA   -    MD0100PA00X+053512Y+047859X0200Y    R270 S0      
317GND              VIA   -    MD0100PA00X+053512Y+048109X0200Y    R270 S0      
317GND              VIA   -    M      A01X+053512Y+048389X0200Y    R270 S2      
017GND              VIA   -    M      A18X+053512Y+048389X0260Y    R270 S2      
017GND                    -    MD0100PA00X+053512Y+048389                       
317GND              VIA   -    MD0100PA00X+052346Y+048463X0200Y    R270 S0      
317GND              VIA   -    MD0100PA00X+052346Y+048213X0200Y    R270 S0      
317GND              VIA   -    MD0100PA00X+049274Y+048398X0200Y    R180 S0      
327GND              PC457 -2          A01X+049532Y+048398X0198Y0197R180 S1      
317GND              VIA   -    M      A01X+049274Y+047898X0200Y    R180 S2      
017GND              VIA   -    M      A18X+049274Y+047898X0260Y    R180 S2      
017GND                    -    MD0100PA00X+049274Y+047898                       
317GND              VIA   -    MD0100PA00X+041175Y+047451X0200Y    R090 S0      
327GND              Q213  -1          A01X+040876Y+047451X0240Y0240R270 S1      
317GND              VIA   -    MD0100PA00X+039732Y+047956X0200Y    R270 S0      
327GND              R5865 -2          A01X+039973Y+047956X0198Y0197R180 S1      
317GND              VIA   -    MD0100PA00X+039375Y+047838X0200Y         S0      
317GND              VIA   -    MD0100PA00X+039365Y+048238X0200Y         S0      
327GND              PC348 -2          A01X+039124Y+048238X0198Y0197     S1      
317GND              VIA   -    MD0100PA00X+033389Y+047364X0200Y    R090 S0      
317GND              VIA   -    MD0100PA00X+033389Y+047860X0200Y    R090 S0      
317GND              VIA   -    MD0100PA00X+032890Y+047364X0200Y    R270 S0      
317GND              VIA   -    MD0100PA00X+032349Y+048566X0200Y    R090 S0      
317GND              VIA   -    MD0100PA00X+031850Y+048566X0200Y    R270 S0      
317GND              VIA   -    MD0100PA00X+031850Y+048070X0200Y    R270 S0      
317GND              VIA   -    MD0100PA00X+032890Y+047860X0200Y    R270 S0      
317GND              VIA   -    MD0100PA00X+032349Y+048070X0200Y    R090 S0      
317GND              VIA   -    MD0100PA00X+029232Y+047258X0200Y    R180 S0      
317GND              VIA   -    MD0100PA00X+028452Y+047258X0200Y         S0      
317GND              VIA   -    MD0100PA00X+029232Y+048675X0200Y    R180 S0      
317GND              VIA   -    MD0100PA00X+029232Y+047966X0200Y    R180 S0      
317GND              VIA   -    MD0100PA00X+028452Y+048675X0200Y         S0      
317GND              VIA   -    MD0100PA00X+028452Y+047966X0200Y         S0      
317GND              VIA   -    MD0100PA00X+085091Y+048238X0200Y         S0      
327GND              C2883 -2          A01X+084833Y+048238X0198Y0197     S1      
317GND              VIA   -    MD0100PA00X+082242Y+048257X0200Y    R090 S0      
317GND              VIA   -    MD0100PA00X+082242Y+048507X0200Y    R090 S0      
317GND              VIA   -    MD0100PA00X+081386Y+048687X0200Y         S0      
317GND              VIA   -    MD0100PA00X+081076Y+048612X0200Y    R090 S0      
317GND              VIA   -    MD0100PA00X+081636Y+048687X0200Y         S0      
317GND              VIA   -    MD0100PA00X+081076Y+048362X0200Y    R090 S0      
317GND              VIA   -    MD0100PA00X+079098Y+047364X0200Y    R090 S0      
317GND              VIA   -    MD0100PA00X+078598Y+047364X0200Y    R270 S0      
317GND              VIA   -    MD0100PA00X+079098Y+047860X0200Y    R090 S0      
317GND              VIA   -    MD0100PA00X+078598Y+047860X0200Y    R270 S0      
317GND              VIA   -    MD0100PA00X+078058Y+048566X0200Y    R090 S0      
317GND              VIA   -    MD0100PA00X+077558Y+048566X0200Y    R270 S0      
317GND              VIA   -    MD0100PA00X+077558Y+048070X0200Y    R270 S0      
317GND              VIA   -    MD0100PA00X+078058Y+048070X0200Y    R090 S0      
317GND              VIA   -    MD0100PA00X+074940Y+047258X0200Y    R180 S0      
317GND              VIA   -    MD0100PA00X+074160Y+047258X0200Y         S0      
317GND              VIA   -    MD0100PA00X+074940Y+048675X0200Y    R180 S0      
317GND              VIA   -    MD0100PA00X+074940Y+047966X0200Y    R180 S0      
317GND              VIA   -    MD0100PA00X+074160Y+048675X0200Y         S0      
317GND              VIA   -    MD0100PA00X+074107Y+047896X0200Y         S0      
317GND              VIA   -    MD0100PA00X+073143Y+047526X0200Y    R180 S0      
317GND              VIA   -    MD0100PA00X+072349Y+047258X0200Y         S0      
317GND              VIA   -    MD0100PA00X+072349Y+048675X0200Y         S0      
317GND              VIA   -    MD0100PA00X+072349Y+047966X0200Y         S0      
317GND              VIA   -    MD0100PA00X+073143Y+048267X0200Y    R180 S0      
317GND              VIA   -    MD0100PA00X+071139Y+047258X0200Y         S0      
317GND              VIA   -    MD0100PA00X+071619Y+047258X0200Y         S0      
317GND              VIA   -    MD0100PA00X+071869Y+047258X0200Y         S0      
317GND              VIA   -    MD0100PA00X+071869Y+048675X0200Y         S0      
317GND              VIA   -    MD0100PA00X+071619Y+048675X0200Y         S0      
317GND              VIA   -    MD0100PA00X+071139Y+048675X0200Y         S0      
317GND              VIA   -    MD0100PA00X+071139Y+047967X0200Y         S0      
317GND              VIA   -    MD0100PA00X+071869Y+047967X0200Y         S0      
317GND              VIA   -    MD0100PA00X+071619Y+047967X0200Y         S0      
317GND              VIA   -    MD0100PA00X+067247Y+047463X0200Y         S0      
317GND              VIA   -    MD0100PA00X+067247Y+048171X0200Y         S0      
317GND              VIA   -    MD0100PA00X+066037Y+048171X0200Y    R180 S0      
317GND              VIA   -    MD0100PA00X+066517Y+048171X0200Y         S0      
317GND              VIA   -    MD0100PA00X+066767Y+048171X0200Y         S0      
317GND              VIA   -    MD0100PA00X+066037Y+047463X0200Y    R180 S0      
317GND              VIA   -    MD0100PA00X+066767Y+047463X0200Y         S0      
317GND              VIA   -    MD0100PA00X+066517Y+047463X0200Y         S0      
317GND              VIA   -    MD0100PA00X+065131Y+047277X0200Y         S0      
317GND              VIA   -    MD0100PA00X+064226Y+047463X0200Y    R180 S0      
317GND              VIA   -    MD0100PA00X+064252Y+048083X0200Y    R180 S0      
317GND              VIA   -    MD0100PA00X+065216Y+047910X0200Y         S0      
317GND              VIA   -    MD0100PA00X+063446Y+047463X0200Y         S0      
317GND              VIA   -    MD0100PA00X+112955Y+047463X0200Y         S0      
317GND              VIA   -    MD0100PA00X+112955Y+048171X0200Y         S0      
317GND              VIA   -    MD0100PA00X+111745Y+047463X0200Y    R180 S0      
317GND              VIA   -    MD0100PA00X+112475Y+047463X0200Y         S0      
317GND              VIA   -    MD0100PA00X+112225Y+047463X0200Y         S0      
317GND              VIA   -    MD0100PA00X+111745Y+048171X0200Y    R180 S0      
317GND              VIA   -    MD0100PA00X+112225Y+048171X0200Y         S0      
317GND              VIA   -    MD0100PA00X+112475Y+048171X0200Y         S0      
317GND              VIA   -    MD0100PA00X+110924Y+047910X0200Y         S0      
317GND              VIA   -    MD0100PA00X+110840Y+047277X0200Y         S0      
317GND              VIA   -    MD0100PA00X+109934Y+047463X0200Y    R180 S0      
317GND              VIA   -    MD0100PA00X+109960Y+048083X0200Y    R180 S0      
317GND              VIA   -    MD0100PA00X+109154Y+047463X0200Y         S0      
317GND              VIA   -    MD0100PA00X+109154Y+048171X0200Y         S0      
317GND              VIA   -    MD0100PA00X+106536Y+047572X0200Y    R090 S0      
317GND              VIA   -    MD0100PA00X+106536Y+048068X0200Y    R090 S0      
317GND              VIA   -    MD0100PA00X+106037Y+047572X0200Y    R270 S0      
317GND              VIA   -    MD0100PA00X+106037Y+048068X0200Y    R270 S0      
317GND              VIA   -    MD0100PA00X+105496Y+047356X0200Y    R090 S0      
317GND              VIA   -    MD0100PA00X+104997Y+047356X0200Y    R270 S0      
317GND              VIA   -    MD0100PA00X+105496Y+048278X0200Y    R090 S0      
317GND              VIA   -    MD0100PA00X+104997Y+048278X0200Y    R270 S0      
317GND              VIA   -    MD0100PA00X+098040Y+047304X0200Y    R180 S0      
327GND              PC900 -2          A01X+098040Y+047063X0198Y0197R090 S1      
317GND              VIA   -    MD0100PA00X+098399Y+047845X0200Y    R270 S0      
317GND              VIA   -    MD0100PA00X+098399Y+047595X0200Y    R270 S0      
317GND              VIA   -    MD0100PA00X+098850Y+048070X0200Y    R180 S0      
317GND              VIA   -    MD0100PA00X+099221Y+047609X0200Y    R270 S0      
317GND              VIA   -    MD0100PA00X+098054Y+048463X0200Y    R270 S0      
317GND              VIA   -    MD0100PA00X+098054Y+048213X0200Y    R270 S0      
317GND              VIA   -    M      A01X+098570Y+048070X0200Y    R180 S2      
017GND              VIA   -    M      A18X+098570Y+048070X0260Y    R180 S2      
017GND                    -    MD0100PA00X+098570Y+048070                       
317GND              VIA   -    M      A01X+099221Y+048389X0200Y    R270 S2      
017GND              VIA   -    M      A18X+099221Y+048389X0260Y    R270 S2      
017GND                    -    MD0100PA00X+099221Y+048389                       
317GND              VIA   -    MD0100PA00X+099221Y+048109X0200Y    R270 S0      
317GND              VIA   -    MD0100PA00X+099221Y+047859X0200Y    R270 S0      
317GND              VIA   -    MD0100PA00X+097240Y+047295X0200Y    R180 S0      
327GND              PC905 -2          A01X+097240Y+047055X0198Y0197R090 S1      
317GND              VIA   -    MD0100PA00X+096782Y+047290X0200Y    R180 S0      
327GND              R6040 -2          A01X+096782Y+047049X0198Y0197R090 S1      
317GND              VIA   -    MD0100PA00X+094982Y+048398X0200Y    R180 S0      
327GND              PC493 -2          A01X+095240Y+048398X0198Y0197R180 S1      
317GND              VIA   -    MD0100PA00X+094988Y+047849X0200Y    R180 S0      
327GND              C2878 -2          A01X+095240Y+047898X0198Y0197R180 S1      
317GND              VIA   -    MD0100PA00X+088291Y+048035X0200Y    R090 S0      
317GND              VIA   -    MD0100PA00X+087591Y+048626X0200Y    R090 S0      
317GND              VIA   -    MD0100PA00X+085083Y+047338X0200Y         S0      
317GND              VIA   -    MD0100PA00X+085074Y+047738X0200Y         S0      
327GND              PC337 -2          A01X+084833Y+047738X0198Y0197     S1      
317GND              VIA   -    MD0100PA00X+144929Y+048389X0200Y    R270 S0      
317GND              VIA   -    MD0100PA00X+144929Y+048109X0200Y    R270 S0      
317GND              VIA   -    MD0100PA00X+144929Y+047859X0200Y    R270 S0      
317GND              VIA   -    MD0100PA00X+144108Y+047845X0200Y    R270 S0      
317GND              VIA   -    MD0100PA00X+144108Y+047595X0200Y    R270 S0      
317GND              VIA   -    MD0100PA00X+144559Y+048070X0200Y    R180 S0      
317GND              VIA   -    MD0100PA00X+144929Y+047609X0200Y    R270 S0      
317GND              VIA   -    MD0100PA00X+143763Y+048463X0200Y    R270 S0      
317GND              VIA   -    MD0100PA00X+143763Y+048213X0200Y    R270 S0      
317GND              VIA   -    MD0100PA00X+144279Y+048070X0200Y    R180 S0      
317GND              VIA   -    MD0100PA00X+140691Y+048398X0200Y    R180 S0      
327GND              PC480 -2          A01X+140949Y+048398X0198Y0197R180 S1      
317GND              VIA   -    MD0100PA00X+140691Y+047898X0200Y    R180 S0      
327GND              C2882 -2          A01X+140949Y+047898X0198Y0197R180 S1      
317GND              VIA   -    MD0100PA00X+132593Y+047451X0200Y    R090 S0      
327GND              Q217  -1          A01X+132293Y+047451X0240Y0240R270 S1      
317GND              VIA   -    MD0100PA00X+130782Y+048238X0200Y         S0      
327GND              PC468 -2          A01X+130542Y+048238X0198Y0197     S1      
317GND              VIA   -    MD0100PA00X+130792Y+047838X0200Y         S0      
317GND              VIA   -    MD0100PA00X+131149Y+047956X0200Y    R270 S0      
327GND              R6041 -2          A01X+131390Y+047956X0198Y0197R180 S1      
317GND              VIA   -    MD0100PA00X+124806Y+047364X0200Y    R090 S0      
317GND              VIA   -    MD0100PA00X+124307Y+047364X0200Y    R270 S0      
317GND              VIA   -    MD0100PA00X+124806Y+047860X0200Y    R090 S0      
317GND              VIA   -    MD0100PA00X+124307Y+047860X0200Y    R270 S0      
317GND              VIA   -    MD0100PA00X+123766Y+048566X0200Y    R090 S0      
317GND              VIA   -    MD0100PA00X+123267Y+048566X0200Y    R270 S0      
317GND              VIA   -    MD0100PA00X+123267Y+048070X0200Y    R270 S0      
317GND              VIA   -    MD0100PA00X+123766Y+048070X0200Y    R090 S0      
317GND              VIA   -    MD0100PA00X+120649Y+047258X0200Y    R180 S0      
317GND              VIA   -    MD0100PA00X+120649Y+048675X0200Y    R180 S0      
317GND              VIA   -    MD0100PA00X+120649Y+047966X0200Y    R180 S0      
317GND              VIA   -    MD0100PA00X+119869Y+047258X0200Y         S0      
317GND              VIA   -    MD0100PA00X+119869Y+047966X0200Y         S0      
317GND              VIA   -    MD0100PA00X+119869Y+048675X0200Y         S0      
317GND              VIA   -    MD0100PA00X+118058Y+047258X0200Y         S0      
317GND              VIA   -    MD0100PA00X+117578Y+047258X0200Y         S0      
317GND              VIA   -    MD0100PA00X+118852Y+047526X0200Y    R180 S0      
317GND              VIA   -    MD0100PA00X+117578Y+048675X0200Y         S0      
317GND              VIA   -    MD0100PA00X+118058Y+048675X0200Y         S0      
317GND              VIA   -    MD0100PA00X+118058Y+047966X0200Y         S0      
317GND              VIA   -    MD0100PA00X+117578Y+047967X0200Y         S0      
317GND              VIA   -    MD0100PA00X+118852Y+048267X0200Y    R180 S0      
317GND              VIA   -    MD0100PA00X+116848Y+047258X0200Y         S0      
317GND              VIA   -    MD0100PA00X+117328Y+047258X0200Y         S0      
317GND              VIA   -    MD0100PA00X+117328Y+048675X0200Y         S0      
317GND              VIA   -    MD0100PA00X+116848Y+048675X0200Y         S0      
317GND              VIA   -    MD0100PA00X+116848Y+047967X0200Y         S0      
317GND              VIA   -    MD0100PA00X+117328Y+047967X0200Y         S0      
317GND              VIA   -    MD0100PA00X+170515Y+047364X0200Y    R090 S0      
317GND              VIA   -    MD0100PA00X+170016Y+047364X0200Y    R270 S0      
317GND              VIA   -    MD0100PA00X+169475Y+048566X0200Y    R090 S0      
317GND              VIA   -    MD0100PA00X+170016Y+047860X0200Y    R270 S0      
317GND              VIA   -    MD0100PA00X+169475Y+048070X0200Y    R090 S0      
317GND              VIA   -    MD0100PA00X+170515Y+047860X0200Y    R090 S0      
317GND              VIA   -    MD0100PA00X+168976Y+048566X0200Y    R270 S0      
317GND              VIA   -    MD0100PA00X+168976Y+048070X0200Y    R270 S0      
317GND              VIA   -    MD0100PA00X+166358Y+047258X0200Y    R180 S0      
317GND              VIA   -    MD0100PA00X+166358Y+048675X0200Y    R180 S0      
317GND              VIA   -    MD0100PA00X+166358Y+047966X0200Y    R180 S0      
317GND              VIA   -    MD0100PA00X+164561Y+047526X0200Y    R180 S0      
317GND              VIA   -    MD0100PA00X+165578Y+047258X0200Y         S0      
317GND              VIA   -    MD0100PA00X+164561Y+048267X0200Y    R180 S0      
317GND              VIA   -    MD0100PA00X+165578Y+047966X0200Y         S0      
317GND              VIA   -    MD0100PA00X+165578Y+048675X0200Y         S0      
317GND              VIA   -    MD0100PA00X+163036Y+047258X0200Y         S0      
317GND              VIA   -    MD0100PA00X+163286Y+047258X0200Y         S0      
317GND              VIA   -    MD0100PA00X+163766Y+047258X0200Y         S0      
317GND              VIA   -    MD0100PA00X+163286Y+048675X0200Y         S0      
317GND              VIA   -    MD0100PA00X+163036Y+048675X0200Y         S0      
317GND              VIA   -    MD0100PA00X+163766Y+048675X0200Y         S0      
317GND              VIA   -    MD0100PA00X+163766Y+047966X0200Y         S0      
317GND              VIA   -    MD0100PA00X+163286Y+047967X0200Y         S0      
317GND              VIA   -    MD0100PA00X+163036Y+047967X0200Y         S0      
317GND              VIA   -    MD0100PA00X+162556Y+047258X0200Y         S0      
317GND              VIA   -    MD0100PA00X+162556Y+048675X0200Y         S0      
317GND              VIA   -    MD0100PA00X+162556Y+047967X0200Y         S0      
317GND              VIA   -    MD0100PA00X+158664Y+047463X0200Y         S0      
317GND              VIA   -    MD0100PA00X+158184Y+047463X0200Y         S0      
317GND              VIA   -    MD0100PA00X+158664Y+048171X0200Y         S0      
317GND              VIA   -    MD0100PA00X+158184Y+048171X0200Y         S0      
317GND              VIA   -    MD0100PA00X+157934Y+048171X0200Y         S0      
317GND              VIA   -    MD0100PA00X+157454Y+048171X0200Y    R180 S0      
317GND              VIA   -    MD0100PA00X+156633Y+047910X0200Y         S0      
317GND              VIA   -    MD0100PA00X+157934Y+047463X0200Y         S0      
317GND              VIA   -    MD0100PA00X+157454Y+047463X0200Y    R180 S0      
317GND              VIA   -    MD0100PA00X+156548Y+047277X0200Y         S0      
317GND              VIA   -    MD0100PA00X+154863Y+047463X0200Y         S0      
317GND              VIA   -    MD0100PA00X+155643Y+047463X0200Y    R180 S0      
317GND              VIA   -    MD0100PA00X+154863Y+048171X0200Y         S0      
317GND              VIA   -    MD0100PA00X+155669Y+048083X0200Y    R180 S0      
317GND              VIA   -    MD0100PA00X+152245Y+047572X0200Y    R090 S0      
317GND              VIA   -    MD0100PA00X+152245Y+048068X0200Y    R090 S0      
317GND              VIA   -    MD0100PA00X+151746Y+047572X0200Y    R270 S0      
317GND              VIA   -    MD0100PA00X+151746Y+048068X0200Y    R270 S0      
317GND              VIA   -    MD0100PA00X+151205Y+048278X0200Y    R090 S0      
317GND              VIA   -    MD0100PA00X+150705Y+048278X0200Y    R270 S0      
317GND              VIA   -    MD0100PA00X+151205Y+047356X0200Y    R090 S0      
317GND              VIA   -    MD0100PA00X+150705Y+047356X0200Y    R270 S0      
317GND              VIA   -    MD0100PA00X+182298Y+048605X0200Y    R270 S0      
317GND              VIA   -    MD0100PA00X+178301Y+047451X0200Y    R090 S0      
327GND              Q219  -1          A01X+178002Y+047451X0240Y0240R270 S1      
317GND              VIA   -    MD0100PA00X+176501Y+047838X0200Y         S0      
317GND              VIA   -    MD0100PA00X+176858Y+047956X0200Y    R270 S0      
327GND              R6053 -2          A01X+177099Y+047956X0198Y0197R180 S1      
317GND              VIA   -    MD0100PA00X+176491Y+048238X0200Y         S0      
327GND              PC492 -2          A01X+176250Y+048238X0198Y0197     S1      
317GND              VIA   -    MD0100PA00X+000704Y+026837X0200Y         S0      
327GND              R5876 -2          A01X+000974Y+026837X0198Y0197R180 S1      
317GND              VIA   -    MD0100PA00X+001908Y+027843X0200Y         S0      
327GND              U383  -3          A01X+001908Y+028113X0240Y0240     S1      
317GND              VIA   -    MD0100PA00X+000974Y+024578X0200Y         S0      
327GND              PR6907-2          A01X+000974Y+024837X0198Y0197R180 S1      
317GND              VIA   -    MD0100PA00X+001856Y+023859X0200Y    R090 S0      
327GND              C2885 -2          A01X+001883Y+023605X0198Y0197R090 S1      
317GND              VIA   -    MD0100PA00X+001657Y+020684X0200Y    R180 S0      
317GND              VIA   -    MD0100PA00X+001907Y+020684X0200Y    R180 S0      
317GND              VIA   -    MD0100PA00X+001038Y+020339X0200Y    R180 S0      
317GND              VIA   -    MD0100PA00X+001288Y+020339X0200Y    R180 S0      
317GND              VIA   -    M      A01X+001514Y+020168X0200Y    R090 S2      
017GND              VIA   -    M      A18X+001514Y+020168X0260Y    R090 S2      
017GND                    -    MD0100PA00X+001514Y+020168                       
317GND              VIA   -    MD0100PA00X+001052Y+019518X0200Y    R180 S0      
317GND              VIA   -    MD0100PA00X+001302Y+019518X0200Y    R180 S0      
317GND              VIA   -    M      A01X+001832Y+019518X0200Y    R180 S2      
017GND              VIA   -    M      A18X+001832Y+019518X0260Y    R180 S2      
017GND                    -    MD0100PA00X+001832Y+019518                       
317GND              VIA   -    MD0100PA00X+001552Y+019518X0200Y    R180 S0      
317GND              VIA   -    MD0100PA00X+001514Y+019888X0200Y    R090 S0      
317GND              VIA   -    MD0100PA00X+001271Y+017578X0200Y         S0      
327GND              PC675 -2          A01X+001271Y+017338X0198Y0197R090 S1      
317GND              VIA   -    MD0100PA00X+001097Y+015287X0200Y         S0      
317GND              VIA   -    MD0100PA00X+001097Y+015587X0200Y         S0      
317GND              VIA   -    MD0100PA00X+001362Y+015326X0200Y         S0      
327GND              PU81  -3   M      A01X+001495Y+015616X0100Y0280     S1      
317GND              VIA   -    MD0100PA00X+001518Y+014473X0200Y    R180 S0      
327GND              PR6920-2   M      A01X+001518Y+014723X0198Y0197R270 S1      
317GND              VIA   -    MD0100PA00X+001918Y+014473X0200Y    R180 S0      
327GND              PR6919-2   M      A01X+001918Y+014723X0198Y0197R270 S1      
317GND              VIA   -    MD0100PA00X+000906Y+013894X0200Y    R180 S0      
327GND              C2711 -1          A01X+000650Y+013894X0198Y0197R270 S1      
317GND              VIA   -    MD0100PA00X+001265Y+011689X0200Y         S0      
317GND              VIA   -    MD0100PA00X+001673Y+010791X0200Y         S0      
327GND              U126  -4          A01X+001673Y+011171X0240Y0460R180 S1      
317GND              VIA   -    MD0100PA00X+000936Y+010750X0200Y         S0      
327GND              C2712 -1          A01X+000936Y+010500X0198Y0197R180 S1      
317GND              VIA   -    MD0100PA00X+001260Y+009211X0200Y         S0      
317GND              VIA   -    MD0100PA00X+001475Y+006238X0200Y         S0      
327GND              U398  -S          A01X+001475Y+006668X0400Y0560     S1      
317GND              VIA   -    MD0100PA00X+002041Y+005530X0200Y    R180 S0      
317GND              VIA   -    MD0100PA00X+002041Y+005130X0200Y    R180 S0      
317GND              VIA   -    MD0100PA00X+001597Y+000300X0200Y    R270 S0      
317GND              VIA   -    MD0100PA00X+000322Y+032477X0200Y    R270 S0      
317GND              VIA   -    MD0100PA00X+000302Y+030477X0200Y    R270 S0      
317GND              VIA   -    MD0100PA00X+000302Y+028477X0200Y    R270 S0      
317GND              VIA   -    MD0100PA00X+000302Y+026477X0200Y    R270 S0      
317GND              VIA   -    MD0100PA00X+000302Y+024477X0200Y    R270 S0      
317GND              VIA   -    MD0100PA00X+000302Y+022477X0200Y    R270 S0      
317GND              VIA   -    MD0100PA00X+000302Y+020477X0200Y    R270 S0      
317GND              VIA   -    MD0100PA00X+000302Y+018477X0200Y    R270 S0      
317GND              VIA   -    MD0100PA00X+000302Y+016477X0200Y    R270 S0      
317GND              VIA   -    MD0100PA00X+000302Y+014477X0200Y    R270 S0      
317GND              VIA   -    MD0100PA00X+000302Y+012477X0200Y    R270 S0      
317GND              VIA   -    MD0100PA00X+000302Y+010477X0200Y    R270 S0      
317GND              VIA   -    MD0100PA00X+000302Y+008477X0200Y    R270 S0      
317GND              VIA   -    MD0100PA00X+000302Y+006477X0200Y    R270 S0      
317GND              VIA   -    MD0100PA00X+000302Y+004477X0200Y    R270 S0      
317GND              VIA   -    MD0100PA00X+000302Y+002477X0200Y    R270 S0      
317GND              VIA   -    MD0100PA00X+000370Y+000537X0200Y    R270 S0      
317GND              VIA   -    MD0100PA00X+003452Y+021354X0200Y    R090 S0      
317GND              VIA   -    MD0100PA00X+002071Y+017578X0200Y         S0      
327GND              PC670 -2          A01X+002071Y+017338X0198Y0197R090 S1      
317GND              VIA   -    MD0100PA00X+002620Y+015165X0200Y         S0      
317GND              VIA   -    MD0100PA00X+002920Y+015165X0200Y         S0      
317GND              VIA   -    MD0100PA00X+002318Y+014473X0200Y    R180 S0      
327GND              PC674 -2   M      A01X+002318Y+014723X0198Y0197R270 S1      
317GND              VIA   -    MD0100PA00X+002599Y+013776X0200Y         S0      
317GND              VIA   -    MD0100PA00X+003079Y+013776X0200Y         S0      
317GND              VIA   -    MD0100PA00X+002599Y+013067X0200Y         S0      
317GND              VIA   -    MD0100PA00X+003079Y+013067X0200Y         S0      
317GND              VIA   -    MD0100PA00X+003329Y+013067X0200Y         S0      
317GND              VIA   -    MD0100PA00X+002599Y+012358X0200Y         S0      
317GND              VIA   -    MD0100PA00X+003329Y+012358X0200Y         S0      
317GND              VIA   -    MD0100PA00X+003079Y+012358X0200Y         S0      
317GND              VIA   -    MD0100PA00X+002244Y+010650X0200Y         S0      
327GND              C2764 -2          A01X+002484Y+010650X0198Y0197R180 S1      
317GND              VIA   -    MD0100PA00X+002599Y+011650X0200Y         S0      
317GND              VIA   -    MD0100PA00X+003079Y+011650X0200Y         S0      
317GND              VIA   -    MD0100PA00X+003329Y+011650X0200Y         S0      
317GND              VIA   -    MD0100PA00X+003329Y+010941X0200Y         S0      
317GND              VIA   -    MD0100PA00X+003564Y+005360X0200Y    R270 S0      
317GND              VIA   -    MD0100PA00X+002432Y+005953X0200Y    R180 S0      
317GND              VIA   -    MD0100PA00X+002432Y+006353X0200Y    R180 S0      
317GND              VIA   -    MD0100PA00X+002432Y+006753X0200Y    R180 S0      
317GND              VIA   -    MD0100PA00X+002832Y+004477X0200Y    R270 S0      
317GND              VIA   -    MD0100PA00X+002832Y+002477X0200Y    R270 S0      
317GND              VIA   -    MD0100PA00X+002696Y+000447X0200Y    R270 S0      
317GND              VIA   -    MD0100PA00X+001796Y+046930X0200Y    R270 S0      
317GND              VIA   -    MD0100PA00X+001796Y+044930X0200Y    R270 S0      
317GND              VIA   -    MD0100PA00X+001796Y+042930X0200Y    R270 S0      
317GND              VIA   -    MD0100PA00X+001796Y+040930X0200Y    R270 S0      
317GND              VIA   -    MD0100PA00X+001796Y+038930X0200Y    R270 S0      
317GND              VIA   -    MD0100PA00X+001796Y+036930X0200Y    R270 S0      
317GND              VIA   -    MD0100PA00X+001796Y+034930X0200Y    R270 S0      
317GND              VIA   -    MD0100PA00X+001097Y+033334X0200Y    R270 S0      
317GND              VIA   -    MD0100PA00X+006410Y+013067X0200Y    R180 S0      
317GND              VIA   -    MD0100PA00X+006410Y+012358X0200Y    R180 S0      
317GND              VIA   -    MD0100PA00X+005610Y+013067X0200Y         S0      
317GND              VIA   -    MD0100PA00X+005610Y+012358X0200Y         S0      
317GND              VIA   -    MD0100PA00X+006410Y+011650X0200Y    R180 S0      
317GND              VIA   -    MD0100PA00X+006410Y+010941X0200Y    R180 S0      
317GND              VIA   -    MD0100PA00X+006410Y+010232X0200Y    R180 S0      
317GND              VIA   -    MD0100PA00X+005596Y+010304X0200Y         S0      
317GND              VIA   -    MD0100PA00X+005610Y+011650X0200Y         S0      
317GND              VIA   -    MD0100PA00X+005610Y+010941X0200Y         S0      
317GND              VIA   -    MD0100PA00X+005564Y+005360X0200Y    R270 S0      
317GND              VIA   -    MD0100PA00X+003728Y+028527X0200Y         S0      
327GND              R5655 -2          A01X+003484Y+028527X0198Y0197     S1      
317GND              VIA   -    MD0100PA00X+004598Y+016326X0200Y         S0      
327GND              U363  -S          A01X+003942Y+016326X0400Y0560R270 S1      
317GND              VIA   -    MD0100PA00X+003799Y+013776X0200Y         S0      
317GND              VIA   -    MD0100PA00X+005244Y+013776X0200Y         S0      
317GND              VIA   -    MD0100PA00X+004693Y+013776X0200Y    R180 S0      
317GND              VIA   -    MD0100PA00X+003799Y+012358X0200Y         S0      
317GND              VIA   -    MD0100PA00X+003799Y+013067X0200Y         S0      
317GND              VIA   -    MD0100PA00X+004924Y+012166X0200Y    R180 S0      
317GND              VIA   -    MD0100PA00X+004693Y+013067X0200Y    R180 S0      
317GND              VIA   -    MD0100PA00X+003799Y+011650X0200Y         S0      
317GND              VIA   -    MD0100PA00X+003799Y+010232X0200Y         S0      
317GND              VIA   -    MD0100PA00X+004624Y+011650X0200Y    R180 S0      
317GND              VIA   -    MD0100PA00X+004599Y+010232X0200Y    R180 S0      
317GND              VIA   -    MD0100PA00X+004624Y+010941X0200Y    R180 S0      
317GND              VIA   -    MD0100PA00X+003799Y+010941X0200Y         S0      
317GND              VIA   -    MD0100PA00X+004645Y+008558X0200Y         S0      
317GND              VIA   -    MD0100PA00X+004836Y+009247X0200Y         S0      
317GND              VIA   -    MD0100PA00X+004645Y+008038X0200Y         S0      
317GND              VIA   -    MD0100PA00X+004645Y+007518X0200Y         S0      
317GND              VIA   -    MD0100PA00X+004645Y+007778X0200Y         S0      
317GND              VIA   -    MD0100PA00X+004645Y+008298X0200Y         S0      
317GND              VIA   -    MD0100PA00X+002348Y+029562X0200Y         S0      
327GND              C3667 -2          A01X+002348Y+029261X0198Y0197R180 S1      
317GND              VIA   -    MD0100PA00X+002139Y+027320X0200Y         S0      
327GND              Q133  -1          A01X+001846Y+027320X0240Y0240R270 S1      
317GND              VIA   -    MD0100PA00X+002874Y+026729X0200Y         S0      
327GND              Q133  -4          A01X+002555Y+026729X0240Y0240R270 S1      
317GND              VIA   -    MD0100PA00X+002145Y+025320X0200Y         S0      
327GND              Q127  -1          A01X+001846Y+025320X0240Y0240R270 S1      
317GND              VIA   -    MD0100PA00X+002874Y+024729X0200Y         S0      
327GND              Q127  -4          A01X+002555Y+024729X0240Y0240R270 S1      
317GND              VIA   -    MD0100PA00X+002797Y+023869X0200Y    R090 S0      
327GND              PR257 -2          A01X+002797Y+023611X0198Y0197R090 S1      
317GND              VIA   -    MD0100PA00X+002153Y+023612X0200Y    R090 S0      
327GND              PC541 -2          A01X+002409Y+023612X0198Y0197R090 S1      
317GND              VIA   -    MD0100PA00X+003620Y+023871X0200Y    R090 S0      
327GND              PC506 -2          A01X+003620Y+023613X0198Y0197R090 S1      
317GND              VIA   -    MD0100PA00X+007374Y+004477X0200Y    R270 S0      
317GND              VIA   -    MD0100PA00X+007374Y+002477X0200Y    R270 S0      
317GND              VIA   -    MD0100PA00X+007443Y+000537X0200Y    R270 S0      
317GND              VIA   -    MD0100PA00X+006850Y+045020X0200Y         S0      
317GND              VIA   -    MD0100PA00X+006862Y+044727X0200Y         S0      
317GND              VIA   -    MD0100PA00X+006078Y+029380X0200Y         S0      
317GND              VIA   -    MD0100PA00X+006879Y+028819X0200Y         S0      
317GND              VIA   -    MD0100PA00X+006629Y+028819X0200Y         S0      
317GND              VIA   -    MD0100PA00X+006879Y+028569X0200Y         S0      
317GND              VIA   -    MD0100PA00X+006629Y+028569X0200Y         S0      
317GND              VIA   -    MD0100PA00X+005828Y+029380X0200Y         S0      
317GND              VIA   -    MD0100PA00X+006884Y+024889X0200Y    R180 S0      
317GND              VIA   -    MD0100PA00X+006914Y+023661X0200Y    R180 S0      
317GND              VIA   -    MD0100PA00X+005473Y+022623X0200Y    R090 S0      
317GND              VIA   -    MD0100PA00X+005473Y+022373X0200Y    R090 S0      
317GND              VIA   -    MD0100PA00X+005473Y+022873X0200Y    R090 S0      
317GND              VIA   -    MD0100PA00X+005473Y+023123X0200Y    R090 S0      
317GND              VIA   -    MD0100PA00X+006890Y+022614X0200Y         S0      
317GND              VIA   -    MD0100PA00X+006519Y+022646X0200Y    R090 S0      
317GND              VIA   -    M      A01X+006519Y+022366X0200Y    R090 S2      
017GND              VIA   -    M      A18X+006519Y+022366X0260Y    R090 S2      
017GND                    -    MD0100PA00X+006519Y+022366                       
317GND              VIA   -    MD0100PA00X+006519Y+023146X0200Y    R090 S0      
317GND              VIA   -    MD0100PA00X+006519Y+022896X0200Y    R090 S0      
317GND              VIA   -    MD0100PA00X+006410Y+013776X0200Y    R180 S0      
317GND              VIA   -    M      A01X+008382Y+029076X0200Y         S2      
017GND              VIA   -    M      A18X+008382Y+029076X0260Y         S2      
017GND                    -    MD0100PA00X+008382Y+029076                       
317GND              VIA   -    MD0100PA00X+007982Y+029076X0200Y         S0      
327GND              PR6904-2   M      A01X+007982Y+028806X0198Y0197R090 S1      
317GND              VIA   -    MD0100PA00X+007582Y+029076X0200Y         S0      
327GND              PC641 -2   M      A01X+007582Y+028806X0198Y0197R090 S1      
317GND              VIA   -    MD0100PA00X+007159Y+028819X0200Y         S0      
317GND              VIA   -    MD0100PA00X+007159Y+028569X0200Y         S0      
317GND              VIA   -    MD0100PA00X+008477Y+025654X0200Y         S0      
327GND              PC646 -2          A01X+008477Y+025954X0198Y0197R270 S1      
317GND              VIA   -    MD0100PA00X+007677Y+025654X0200Y         S0      
327GND              PC642 -2          A01X+007677Y+025954X0198Y0197R270 S1      
317GND              VIA   -    MD0100PA00X+007384Y+024889X0200Y    R180 S0      
317GND              VIA   -    MD0100PA00X+007134Y+024889X0200Y    R180 S0      
317GND              VIA   -    MD0100PA00X+007316Y+023179X0200Y    R090 S0      
317GND              VIA   -    MD0100PA00X+007164Y+023661X0200Y    R180 S0      
317GND              VIA   -    MD0100PA00X+007414Y+023661X0200Y    R180 S0      
317GND              VIA   -    MD0100PA00X+007685Y+022471X0200Y    R090 S0      
317GND              VIA   -    M      A01X+007170Y+022614X0200Y         S2      
017GND              VIA   -    M      A18X+007170Y+022614X0260Y         S2      
017GND                    -    MD0100PA00X+007170Y+022614                       
317GND              VIA   -    MD0100PA00X+007685Y+022221X0200Y    R090 S0      
317GND              VIA   -    MD0100PA00X+007316Y+022929X0200Y    R090 S0      
317GND              VIA   -    MD0100PA00X+008355Y+020676X0200Y         S0      
317GND              VIA   -    M      A01X+007494Y+018873X0200Y         S2      
017GND              VIA   -    M      A18X+007494Y+018873X0260Y         S2      
017GND                    -    MD0100PA00X+007494Y+018873                       
327GND              C202  -2          A01X+007794Y+018740X0198Y0197R090 S1      
317GND              VIA   -    MD0100PA00X+008157Y+018462X0200Y         S0      
327GND              U51   -10         A01X+008443Y+018383X0090Y0240R090 S1      
317GND              VIA   -    MD0100PA00X+007507Y+019194X0200Y         S0      
327GND              C201  -2          A01X+007785Y+019194X0198Y0197R180 S1      
317GND              VIA   -    MD0100PA00X+007142Y+015154X0200Y         S0      
327GND              R5877 -2          A01X+007420Y+015154X0198Y0197R180 S1      
317GND              VIA   -    MD0100PA00X+008391Y+013669X0200Y    R270 S0      
317GND              VIA   -    MD0100PA00X+008391Y+013173X0200Y    R270 S0      
317GND              VIA   -    MD0100PA00X+008391Y+012251X0200Y    R270 S0      
317GND              VIA   -    MD0100PA00X+007850Y+012462X0200Y    R090 S0      
317GND              VIA   -    MD0100PA00X+007850Y+012957X0200Y    R090 S0      
317GND              VIA   -    MD0100PA00X+007351Y+012462X0200Y    R270 S0      
317GND              VIA   -    MD0100PA00X+007351Y+012957X0200Y    R270 S0      
317GND              VIA   -    MD0100PA00X+008066Y+010378X0200Y    R270 S0      
327GND              R411  -1          A01X+008066Y+010135X0198Y0197R270 S1      
317GND              VIA   -    MD0100PA00X+008391Y+011756X0200Y    R270 S0      
317GND              VIA   -    MD0100PA00X+007850Y+011540X0200Y    R090 S0      
317GND              VIA   -    MD0100PA00X+007351Y+011540X0200Y    R270 S0      
317GND              VIA   -    MD0100PA00X+007850Y+011044X0200Y    R090 S0      
317GND              VIA   -    MD0100PA00X+007351Y+011044X0200Y    R270 S0      
317GND              VIA   -    MD0100PA00X+007311Y+010170X0200Y    R090 S0      
317GND              VIA   -    MD0100PA00X+006938Y+009402X0200Y         S0      
317GND              VIA   -    MD0100PA00X+007338Y+009402X0200Y         S0      
317GND              VIA   -    MD0100PA00X+011761Y+013330X0200Y         S0      
317GND              VIA   -    MD0100PA00X+011015Y+013090X0200Y         S0      
327GND              PC677 -2          A01X+010761Y+013090X0198Y0197R090 S1      
317GND              VIA   -    MD0100PA00X+011558Y+010225X0200Y    R180 S0      
327GND              PR6921-2   M      A01X+011558Y+010475X0198Y0197R270 S1      
317GND              VIA   -    MD0100PA00X+011001Y+011078X0200Y         S0      
317GND              VIA   -    MD0100PA00X+011158Y+010225X0200Y    R180 S0      
327GND              PR6922-2   M      A01X+011158Y+010475X0198Y0197R270 S1      
317GND              VIA   -    MD0100PA00X+010736Y+011039X0200Y         S0      
317GND              VIA   -    MD0100PA00X+010736Y+011339X0200Y         S0      
317GND              VIA   -    M      A01X+011958Y+010225X0200Y    R180 S2      
017GND              VIA   -    M      A18X+011958Y+010225X0260Y    R180 S2      
017GND                    -    MD0100PA00X+011958Y+010225                       
317GND              VIA   -    MD0100PA00X+011333Y+000300X0200Y    R270 S0      
317GND              VIA   -    MD0100PA00X+009026Y+044551X0200Y         S0      
327GND              C3998 -2          A01X+012724Y+044551X0198Y0197R270 S1      
317GND              VIA   -    M      A01X+009594Y+037795X0200Y    R270 S2      
017GND              VIA   -    M      A18X+009594Y+037795X0260Y    R270 S2      
017GND                    -    MD0100PA00X+009594Y+037795                       
317GND              VIA   -    MD0100PA00X+009189Y+028834X0200Y    R090 S0      
317GND              VIA   -    MD0100PA00X+009189Y+029084X0200Y    R090 S0      
317GND              VIA   -    MD0100PA00X+009189Y+029364X0200Y    R090 S0      
317GND              VIA   -    MD0100PA00X+009439Y+028834X0200Y    R090 S0      
317GND              VIA   -    MD0100PA00X+009439Y+029084X0200Y    R090 S0      
317GND              VIA   -    MD0100PA00X+009439Y+029364X0200Y    R090 S0      
317GND              VIA   -    M      A01X+008990Y+028131X0200Y         S2      
017GND              VIA   -    M      A18X+008990Y+028131X0260Y         S2      
017GND                    -    MD0100PA00X+008990Y+028131                       
317GND              VIA   -    MD0100PA00X+008580Y+027921X0200Y         S0      
317GND              VIA   -    MD0100PA00X+008760Y+018516X0200Y         S0      
317GND              VIA   -    MD0100PA00X+009224Y+018512X0200Y         S0      
317GND              VIA   -    MD0100PA00X+009601Y+019242X0200Y         S0      
317GND              VIA   -    MD0100PA00X+009229Y+018053X0200Y         S0      
317GND              VIA   -    MD0100PA00X+008760Y+018057X0200Y         S0      
327GND              U51   -TH  M      A01X+008994Y+018285X0670Y0670R180 S1      
317GND              VIA   -    MD0100PA00X+008590Y+015237X0200Y         S0      
327GND              Q134  -1          A01X+008292Y+015237X0240Y0240R270 S1      
317GND              VIA   -    MD0100PA00X+008890Y+013669X0200Y    R090 S0      
317GND              VIA   -    MD0100PA00X+008700Y+014646X0200Y         S0      
327GND              Q134  -4          A01X+009000Y+014646X0240Y0240R270 S1      
317GND              VIA   -    MD0100PA00X+008890Y+013173X0200Y    R090 S0      
317GND              VIA   -    MD0100PA00X+008890Y+012251X0200Y    R090 S0      
317GND              VIA   -    MD0100PA00X+008890Y+011756X0200Y    R090 S0      
317GND              VIA   -    MD0100PA00X+008808Y+010360X0200Y         S0      
327GND              R6198 -1          A01X+008481Y+010360X0198Y0197R270 S1      
317GND              VIA   -    MD0100PA00X+009333Y+000300X0200Y    R270 S0      
317GND              VIA   -    MD0100PA00X+012143Y+020684X0200Y    R180 S0      
317GND              VIA   -    MD0100PA00X+011893Y+020684X0200Y    R180 S0      
317GND              VIA   -    M      A01X+012068Y+019518X0200Y    R180 S2      
017GND              VIA   -    M      A18X+012068Y+019518X0260Y    R180 S2      
017GND                    -    MD0100PA00X+012068Y+019518                       
317GND              VIA   -    MD0100PA00X+012913Y+015085X0200Y         S0      
327GND              U364  -S          A01X+012519Y+015330X0400Y0560     S1      
317GND              VIA   -    MD0100PA00X+012434Y+014601X0200Y         S0      
327GND              C3661 -2          A01X+012184Y+014601X0198Y0197R090 S1      
317GND              VIA   -    MD0100PA00X+012625Y+014123X0200Y         S0      
327GND              R5651 -2          A01X+012478Y+013884X0198Y0197     S1      
317GND              VIA   -    MD0100PA00X+013315Y+013776X0200Y         S0      
317GND              VIA   -    MD0100PA00X+012835Y+013776X0200Y         S0      
317GND              VIA   -    MD0100PA00X+012835Y+013067X0200Y         S0      
317GND              VIA   -    MD0100PA00X+013315Y+013067X0200Y         S0      
317GND              VIA   -    MD0100PA00X+012835Y+012358X0200Y         S0      
317GND              VIA   -    MD0100PA00X+013315Y+012358X0200Y         S0      
317GND              VIA   -    MD0100PA00X+012260Y+010917X0200Y         S0      
317GND              VIA   -    MD0100PA00X+012560Y+010917X0200Y         S0      
317GND              VIA   -    MD0100PA00X+012461Y+010650X0200Y         S0      
317GND              VIA   -    MD0100PA00X+013315Y+011650X0200Y         S0      
317GND              VIA   -    MD0100PA00X+012835Y+011650X0200Y         S0      
317GND              VIA   -    MD0100PA00X+013068Y+004477X0200Y    R270 S0      
317GND              VIA   -    MD0100PA00X+013068Y+002477X0200Y    R270 S0      
317GND              VIA   -    MD0100PA00X+012932Y+000447X0200Y    R270 S0      
317GND              VIA   -    MD0100PA00X+010933Y+025237X0200Y         S0      
327GND              PR6908-2          A01X+011211Y+025237X0198Y0197R180 S1      
317GND              VIA   -    MD0100PA00X+010757Y+022186X0200Y         S0      
327GND              C2861 -2   M      A01X+010499Y+022186X0198Y0197     S1      
317GND              VIA   -    MD0100PA00X+010757Y+021686X0200Y         S0      
327GND              PC385 -2          A01X+010499Y+021686X0198Y0197     S1      
317GND              VIA   -    MD0100PA00X+010757Y+021286X0200Y         S0      
327GND              PR209 -2          A01X+010499Y+021286X0198Y0197     S1      
317GND              VIA   -    MD0100PA00X+010757Y+020086X0200Y         S0      
317GND              VIA   -    MD0100PA00X+011274Y+020339X0200Y    R180 S0      
317GND              VIA   -    MD0100PA00X+011524Y+020339X0200Y    R180 S0      
317GND              VIA   -    M      A01X+011750Y+020168X0200Y    R090 S2      
017GND              VIA   -    M      A18X+011750Y+020168X0260Y    R090 S2      
017GND                    -    MD0100PA00X+011750Y+020168                       
317GND              VIA   -    MD0100PA00X+011788Y+019518X0200Y    R180 S0      
317GND              VIA   -    MD0100PA00X+011288Y+019518X0200Y    R180 S0      
317GND              VIA   -    MD0100PA00X+011538Y+019518X0200Y    R180 S0      
317GND              VIA   -    MD0100PA00X+011750Y+019888X0200Y    R090 S0      
317GND              VIA   -    MD0100PA00X+010754Y+018066X0200Y         S0      
327GND              R508  -2          A01X+010490Y+018066X0198Y0197     S1      
317GND              VIA   -    MD0100PA00X+010754Y+017266X0200Y         S0      
327GND              R510  -2          A01X+010490Y+017266X0198Y0197     S1      
317GND              VIA   -    MD0100PA00X+011175Y+013458X0200Y         S0      
327GND              U382  -3          A01X+010864Y+013674X0240Y0240     S1      
317GND              VIA   -    MD0100PA00X+013579Y+042568X0200Y    R270 S0      
317GND              VIA   -    MD0100PA00X+014079Y+042568X0200Y    R090 S0      
317GND              VIA   -    MD0100PA00X+013819Y+040229X0200Y    R270 S0      
317GND              VIA   -    MD0100PA00X+014620Y+040935X0200Y    R270 S0      
317GND              VIA   -    MD0100PA00X+014620Y+040440X0200Y    R270 S0      
317GND              VIA   -    MD0100PA00X+014620Y+039518X0200Y    R270 S0      
317GND              VIA   -    MD0100PA00X+014319Y+039734X0200Y    R090 S0      
317GND              VIA   -    MD0100PA00X+013819Y+039734X0200Y    R270 S0      
317GND              VIA   -    MD0100PA00X+014319Y+040229X0200Y    R090 S0      
317GND              VIA   -    MD0100PA00X+014620Y+039022X0200Y    R270 S0      
317GND              VIA   -    MD0100PA00X+013856Y+023871X0200Y    R090 S0      
327GND              PC518 -2          A01X+013856Y+023613X0198Y0197R090 S1      
317GND              VIA   -    MD0100PA00X+013688Y+021354X0200Y    R090 S0      
317GND              VIA   -    MD0100PA00X+014035Y+013776X0200Y         S0      
317GND              VIA   -    MD0100PA00X+014982Y+013776X0200Y    R180 S0      
317GND              VIA   -    MD0100PA00X+014035Y+012358X0200Y         S0      
317GND              VIA   -    MD0100PA00X+014035Y+013067X0200Y         S0      
317GND              VIA   -    MD0100PA00X+013565Y+013067X0200Y         S0      
317GND              VIA   -    MD0100PA00X+013565Y+012358X0200Y         S0      
317GND              VIA   -    MD0100PA00X+014983Y+013067X0200Y    R180 S0      
317GND              VIA   -    MD0100PA00X+014877Y+012458X0200Y    R180 S0      
317GND              VIA   -    MD0100PA00X+013565Y+011650X0200Y         S0      
317GND              VIA   -    MD0100PA00X+014035Y+010232X0200Y         S0      
317GND              VIA   -    MD0100PA00X+014035Y+010941X0200Y         S0      
317GND              VIA   -    MD0100PA00X+014035Y+011650X0200Y         S0      
317GND              VIA   -    MD0100PA00X+014835Y+010232X0200Y    R180 S0      
317GND              VIA   -    MD0100PA00X+014860Y+011650X0200Y    R180 S0      
317GND              VIA   -    MD0100PA00X+014860Y+010941X0200Y    R180 S0      
317GND              VIA   -    MD0100PA00X+013565Y+010941X0200Y         S0      
317GND              VIA   -    MD0100PA00X+014881Y+008558X0200Y         S0      
317GND              VIA   -    MD0100PA00X+014881Y+007778X0200Y         S0      
317GND              VIA   -    MD0100PA00X+014881Y+007518X0200Y         S0      
317GND              VIA   -    MD0100PA00X+014881Y+008298X0200Y         S0      
317GND              VIA   -    MD0100PA00X+014881Y+008038X0200Y         S0      
317GND              VIA   -    MD0100PA00X+013800Y+005360X0200Y    R270 S0      
317GND              VIA   -    MD0100PA00X+012512Y+036240X0200Y         S0      
317GND              VIA   -    MD0100PA00X+012381Y+025320X0200Y         S0      
327GND              Q128  -1          A01X+012082Y+025320X0240Y0240R270 S1      
317GND              VIA   -    MD0100PA00X+012093Y+023859X0200Y    R090 S0      
327GND              C2887 -2          A01X+012093Y+023601X0198Y0197R090 S1      
317GND              VIA   -    MD0100PA00X+012389Y+023612X0200Y    R090 S0      
327GND              PC516 -2          A01X+012645Y+023612X0198Y0197R090 S1      
317GND              VIA   -    MD0100PA00X+013033Y+023869X0200Y    R090 S0      
327GND              PR261 -2          A01X+013033Y+023611X0198Y0197R090 S1      
317GND              VIA   -    MD0100PA00X+013110Y+024729X0200Y         S0      
327GND              Q128  -4          A01X+012791Y+024729X0240Y0240R270 S1      
317GND              VIA   -    MD0100PA00X+015119Y+043770X0200Y    R090 S0      
317GND              VIA   -    MD0100PA00X+015119Y+043274X0200Y    R090 S0      
317GND              VIA   -    MD0100PA00X+015119Y+041857X0200Y    R090 S0      
317GND              VIA   -    MD0100PA00X+015119Y+042352X0200Y    R090 S0      
317GND              VIA   -    MD0100PA00X+015119Y+040935X0200Y    R090 S0      
317GND              VIA   -    MD0100PA00X+015119Y+040440X0200Y    R090 S0      
317GND              VIA   -    MD0100PA00X+015119Y+039518X0200Y    R090 S0      
317GND              VIA   -    MD0100PA00X+015119Y+039022X0200Y    R090 S0      
317GND              VIA   -    MD0100PA00X+016653Y+031239X0200Y         S0      
317GND              VIA   -    MD0100PA00X+016064Y+029380X0200Y         S0      
317GND              VIA   -    MD0100PA00X+016314Y+029380X0200Y         S0      
317GND              VIA   -    MD0100PA00X+015710Y+022373X0200Y    R090 S0      
317GND              VIA   -    MD0100PA00X+015710Y+022623X0200Y    R090 S0      
317GND              VIA   -    M      A01X+016755Y+022366X0200Y    R090 S2      
017GND              VIA   -    M      A18X+016755Y+022366X0260Y    R090 S2      
017GND                    -    MD0100PA00X+016755Y+022366                       
317GND              VIA   -    MD0100PA00X+015710Y+023123X0200Y    R090 S0      
317GND              VIA   -    MD0100PA00X+015710Y+022873X0200Y    R090 S0      
317GND              VIA   -    MD0100PA00X+016646Y+013776X0200Y    R180 S0      
317GND              VIA   -    MD0100PA00X+015505Y+013776X0200Y         S0      
317GND              VIA   -    MD0100PA00X+016646Y+013067X0200Y    R180 S0      
317GND              VIA   -    MD0100PA00X+016646Y+012358X0200Y    R180 S0      
317GND              VIA   -    MD0100PA00X+015846Y+012358X0200Y         S0      
317GND              VIA   -    MD0100PA00X+015846Y+013067X0200Y         S0      
317GND              VIA   -    MD0100PA00X+016646Y+010232X0200Y    R180 S0      
317GND              VIA   -    MD0100PA00X+016646Y+010941X0200Y    R180 S0      
317GND              VIA   -    MD0100PA00X+016646Y+011650X0200Y    R180 S0      
317GND              VIA   -    MD0100PA00X+015846Y+010941X0200Y         S0      
317GND              VIA   -    MD0100PA00X+015833Y+010304X0200Y         S0      
317GND              VIA   -    MD0100PA00X+015846Y+011650X0200Y         S0      
317GND              VIA   -    MD0100PA00X+015137Y+009285X0200Y         S0      
317GND              VIA   -    MD0100PA00X+015800Y+005360X0200Y    R270 S0      
317GND              VIA   -    MD0100PA00X+014079Y+046861X0200Y    R090 S0      
317GND              VIA   -    MD0100PA00X+013579Y+046861X0200Y    R270 S0      
317GND              VIA   -    MD0100PA00X+013660Y+045075X0200Y         S0      
327GND              U9    -S          A01X+014058Y+045075X0400Y0560     S1      
317GND              VIA   -    MD0100PA00X+013579Y+044481X0200Y    R270 S0      
317GND              VIA   -    MD0100PA00X+014079Y+044481X0200Y    R090 S0      
317GND              VIA   -    MD0100PA00X+013579Y+043986X0200Y    R270 S0      
317GND              VIA   -    MD0100PA00X+014079Y+043986X0200Y    R090 S0      
317GND              VIA   -    MD0100PA00X+014620Y+043770X0200Y    R270 S0      
317GND              VIA   -    MD0100PA00X+014620Y+043274X0200Y    R270 S0      
317GND              VIA   -    MD0100PA00X+013579Y+043064X0200Y    R270 S0      
317GND              VIA   -    MD0100PA00X+014079Y+043064X0200Y    R090 S0      
317GND              VIA   -    MD0100PA00X+014620Y+042352X0200Y    R270 S0      
317GND              VIA   -    MD0100PA00X+014620Y+041857X0200Y    R270 S0      
317GND              VIA   -    MD0100PA00X+013579Y+041151X0200Y    R270 S0      
317GND              VIA   -    MD0100PA00X+013579Y+041646X0200Y    R270 S0      
317GND              VIA   -    MD0100PA00X+014079Y+041151X0200Y    R090 S0      
317GND              VIA   -    MD0100PA00X+014079Y+041646X0200Y    R090 S0      
317GND              VIA   -    MD0100PA00X+017913Y+025654X0200Y         S0      
327GND              PC640 -2          A01X+017913Y+025954X0198Y0197R270 S1      
317GND              VIA   -    MD0100PA00X+017120Y+024889X0200Y    R180 S0      
317GND              VIA   -    MD0100PA00X+017370Y+024889X0200Y    R180 S0      
317GND              VIA   -    MD0100PA00X+017620Y+024889X0200Y    R180 S0      
317GND              VIA   -    MD0100PA00X+017150Y+023661X0200Y    R180 S0      
317GND              VIA   -    MD0100PA00X+017552Y+023179X0200Y    R090 S0      
317GND              VIA   -    MD0100PA00X+017650Y+023661X0200Y    R180 S0      
317GND              VIA   -    MD0100PA00X+017400Y+023661X0200Y    R180 S0      
317GND              VIA   -    M      A01X+017406Y+022614X0200Y         S2      
017GND              VIA   -    M      A18X+017406Y+022614X0260Y         S2      
017GND                    -    MD0100PA00X+017406Y+022614                       
317GND              VIA   -    MD0100PA00X+016755Y+022646X0200Y    R090 S0      
317GND              VIA   -    MD0100PA00X+016755Y+022896X0200Y    R090 S0      
317GND              VIA   -    MD0100PA00X+016755Y+023146X0200Y    R090 S0      
317GND              VIA   -    MD0100PA00X+017126Y+022614X0200Y         S0      
317GND              VIA   -    MD0100PA00X+017921Y+022221X0200Y    R090 S0      
317GND              VIA   -    MD0100PA00X+017921Y+022471X0200Y    R090 S0      
317GND              VIA   -    MD0100PA00X+017552Y+022929X0200Y    R090 S0      
317GND              VIA   -    M      A01X+017730Y+018873X0200Y         S2      
017GND              VIA   -    M      A18X+017730Y+018873X0260Y         S2      
017GND                    -    MD0100PA00X+017730Y+018873                       
327GND              C205  -2          A01X+018030Y+018740X0198Y0197R090 S1      
317GND              VIA   -    MD0100PA00X+017743Y+019194X0200Y         S0      
327GND              C210  -2          A01X+018022Y+019194X0198Y0197R180 S1      
317GND              VIA   -    MD0100PA00X+017378Y+015154X0200Y         S0      
327GND              R5888 -2          A01X+017656Y+015154X0198Y0197R180 S1      
317GND              VIA   -    MD0100PA00X+017587Y+012462X0200Y         S0      
317GND              VIA   -    MD0100PA00X+017587Y+012957X0200Y         S0      
317GND              VIA   -    MD0100PA00X+018086Y+012462X0200Y         S0      
317GND              VIA   -    MD0100PA00X+018086Y+012957X0200Y         S0      
317GND              VIA   -    MD0100PA00X+017587Y+011540X0200Y         S0      
317GND              VIA   -    MD0100PA00X+018086Y+011044X0200Y         S0      
317GND              VIA   -    MD0100PA00X+018086Y+011540X0200Y         S0      
317GND              VIA   -    MD0100PA00X+017587Y+011044X0200Y         S0      
317GND              VIA   -    MD0100PA00X+017547Y+010170X0200Y    R090 S0      
317GND              VIA   -    MD0100PA00X+017174Y+009402X0200Y         S0      
317GND              VIA   -    MD0100PA00X+017574Y+009402X0200Y         S0      
317GND              VIA   -    MD0100PA00X+017974Y+009402X0200Y         S0      
317GND              VIA   -    MD0100PA00X+017611Y+004477X0200Y    R270 S0      
317GND              VIA   -    MD0100PA00X+017611Y+002477X0200Y    R270 S0      
317GND              VIA   -    MD0100PA00X+017679Y+000537X0200Y    R270 S0      
317GND              VIA   -    MD0100PA00X+018997Y+018057X0200Y         S0      
317GND              VIA   -    MD0100PA00X+018827Y+015237X0200Y         S0      
327GND              Q135  -1          A01X+018528Y+015237X0240Y0240R270 S1      
317GND              VIA   -    MD0100PA00X+019126Y+013669X0200Y         S0      
317GND              VIA   -    MD0100PA00X+018627Y+013669X0200Y         S0      
317GND              VIA   -    MD0100PA00X+018936Y+014646X0200Y         S0      
327GND              Q135  -4          A01X+019237Y+014646X0240Y0240R270 S1      
317GND              VIA   -    MD0100PA00X+019126Y+013173X0200Y         S0      
317GND              VIA   -    MD0100PA00X+019126Y+012251X0200Y         S0      
317GND              VIA   -    MD0100PA00X+018627Y+012251X0200Y         S0      
317GND              VIA   -    MD0100PA00X+018627Y+013173X0200Y         S0      
317GND              VIA   -    MD0100PA00X+019419Y+010362X0200Y    R090 S0      
327GND              U399  -S          A01X+019419Y+010792X0400Y0560R180 S1      
317GND              VIA   -    MD0100PA00X+018302Y+010378X0200Y    R270 S0      
327GND              R414  -1          A01X+018302Y+010135X0198Y0197R270 S1      
317GND              VIA   -    MD0100PA00X+019126Y+011756X0200Y         S0      
317GND              VIA   -    MD0100PA00X+018627Y+011756X0200Y         S0      
317GND              VIA   -    MD0100PA00X+018375Y+009402X0200Y         S0      
317GND              VIA   -    MD0100PA00X+018882Y+007614X0200Y         S0      
317GND              VIA   -    MD0100PA00X+018882Y+008414X0200Y         S0      
317GND              VIA   -    MD0100PA00X+018882Y+008014X0200Y         S0      
317GND              VIA   -    MD0100PA00X+019570Y+000300X0200Y    R270 S0      
317GND              VIA   -    MD0100PA00X+017737Y+046754X0200Y         S0      
317GND              VIA   -    MD0100PA00X+017737Y+044585X0200Y         S0      
317GND              VIA   -    MD0100PA00X+017737Y+043876X0200Y         S0      
317GND              VIA   -    MD0100PA00X+017737Y+043167X0200Y         S0      
317GND              VIA   -    MD0100PA00X+017737Y+042459X0200Y         S0      
317GND              VIA   -    MD0100PA00X+017737Y+041750X0200Y         S0      
317GND              VIA   -    MD0100PA00X+017737Y+041041X0200Y         S0      
317GND              VIA   -    MD0100PA00X+017737Y+040333X0200Y         S0      
317GND              VIA   -    MD0100PA00X+017737Y+039624X0200Y         S0      
317GND              VIA   -    MD0100PA00X+017737Y+038915X0200Y         S0      
317GND              VIA   -    MD0100PA00X+017818Y+029076X0200Y         S0      
327GND              PC644 -2   M      A01X+017818Y+028806X0198Y0197R090 S1      
317GND              VIA   -    MD0100PA00X+018218Y+029076X0200Y         S0      
327GND              PR6903-2   M      A01X+018218Y+028806X0198Y0197R090 S1      
317GND              VIA   -    MD0100PA00X+016866Y+028569X0200Y         S0      
317GND              VIA   -    MD0100PA00X+017116Y+028819X0200Y         S0      
317GND              VIA   -    MD0100PA00X+016866Y+028819X0200Y         S0      
317GND              VIA   -    MD0100PA00X+017116Y+028569X0200Y         S0      
317GND              VIA   -    MD0100PA00X+017396Y+028819X0200Y         S0      
317GND              VIA   -    MD0100PA00X+017396Y+028569X0200Y         S0      
317GND              VIA   -    MD0100PA00X+019428Y+043645X0200Y         S0      
317GND              VIA   -    MD0100PA00X+019467Y+042983X0200Y         S0      
317GND              VIA   -    MD0100PA00X+019530Y+041482X0200Y         S0      
317GND              VIA   -    MD0100PA00X+018540Y+041257X0200Y    R180 S0      
317GND              VIA   -    MD0100PA00X+018659Y+042630X0200Y    R180 S0      
317GND              VIA   -    MD0100PA00X+019460Y+042286X0200Y         S0      
317GND              VIA   -    MD0100PA00X+019052Y+039624X0200Y         S0      
317GND              VIA   -    MD0100PA00X+018645Y+040491X0200Y    R180 S0      
317GND              VIA   -    MD0100PA00X+018517Y+039624X0200Y    R180 S0      
317GND              VIA   -    MD0100PA00X+018517Y+038915X0200Y    R180 S0      
317GND              VIA   -    MD0100PA00X+019199Y+038915X0200Y         S0      
317GND              VIA   -    M      A01X+018618Y+029076X0200Y         S2      
017GND              VIA   -    M      A18X+018618Y+029076X0260Y         S2      
017GND                    -    MD0100PA00X+018618Y+029076                       
317GND              VIA   -    MD0100PA00X+019425Y+028834X0200Y    R090 S0      
317GND              VIA   -    MD0100PA00X+019425Y+029084X0200Y    R090 S0      
317GND              VIA   -    MD0100PA00X+019425Y+029364X0200Y    R090 S0      
317GND              VIA   -    MD0100PA00X+019675Y+028834X0200Y    R090 S0      
317GND              VIA   -    MD0100PA00X+019675Y+029084X0200Y    R090 S0      
317GND              VIA   -    MD0100PA00X+019675Y+029364X0200Y    R090 S0      
317GND              VIA   -    M      A01X+019226Y+028131X0200Y         S2      
017GND              VIA   -    M      A18X+019226Y+028131X0260Y         S2      
017GND                    -    MD0100PA00X+019226Y+028131                       
317GND              VIA   -    MD0100PA00X+018816Y+027921X0200Y         S0      
317GND              VIA   -    MD0100PA00X+018713Y+025654X0200Y         S0      
327GND              PC647 -2          A01X+018713Y+025954X0198Y0197R270 S1      
317GND              VIA   -    MD0100PA00X+018591Y+020676X0200Y         S0      
317GND              VIA   -    MD0100PA00X+018393Y+018462X0200Y         S0      
327GND              U54   -10         A01X+018680Y+018383X0090Y0240R090 S1      
317GND              VIA   -    MD0100PA00X+019460Y+018512X0200Y         S0      
317GND              VIA   -    MD0100PA00X+018997Y+018516X0200Y         S0      
317GND              VIA   -    MD0100PA00X+019837Y+019242X0200Y         S0      
317GND              VIA   -    MD0100PA00X+019465Y+018053X0200Y         S0      
327GND              U54   -TH  M      A01X+019231Y+018285X0670Y0670R180 S1      
317GND              VIA   -    MD0100PA00X+021058Y+039624X0200Y         S0      
317GND              VIA   -    MD0100PA00X+020808Y+039624X0200Y         S0      
317GND              VIA   -    MD0100PA00X+020328Y+041041X0200Y    R180 S0      
317GND              VIA   -    MD0100PA00X+020328Y+040333X0200Y    R180 S0      
317GND              VIA   -    MD0100PA00X+020328Y+039624X0200Y    R180 S0      
317GND              VIA   -    MD0100PA00X+021538Y+041041X0200Y         S0      
317GND              VIA   -    MD0100PA00X+021058Y+041041X0200Y         S0      
317GND              VIA   -    MD0100PA00X+020808Y+041041X0200Y         S0      
317GND              VIA   -    MD0100PA00X+021058Y+040333X0200Y         S0      
317GND              VIA   -    MD0100PA00X+021538Y+040333X0200Y         S0      
317GND              VIA   -    MD0100PA00X+020808Y+040333X0200Y         S0      
317GND              VIA   -    MD0100PA00X+021538Y+039624X0200Y         S0      
317GND              VIA   -    MD0100PA00X+020328Y+038915X0200Y    R180 S0      
317GND              VIA   -    MD0100PA00X+021058Y+038915X0200Y         S0      
317GND              VIA   -    MD0100PA00X+021538Y+038915X0200Y         S0      
317GND              VIA   -    MD0100PA00X+021169Y+025237X0200Y         S0      
327GND              PR6913-2          A01X+021447Y+025237X0198Y0197R180 S1      
317GND              VIA   -    MD0100PA00X+020993Y+022186X0200Y         S0      
327GND              C2863 -2   M      A01X+020735Y+022186X0198Y0197     S1      
317GND              VIA   -    MD0100PA00X+020993Y+021686X0200Y         S0      
327GND              PC421 -2          A01X+020735Y+021686X0198Y0197     S1      
317GND              VIA   -    MD0100PA00X+020993Y+021286X0200Y         S0      
317GND              VIA   -    MD0100PA00X+021510Y+020339X0200Y    R180 S0      
317GND              VIA   -    MD0100PA00X+020993Y+020086X0200Y         S0      
317GND              VIA   -    MD0100PA00X+021524Y+019518X0200Y    R180 S0      
317GND              VIA   -    MD0100PA00X+020990Y+018066X0200Y         S0      
327GND              R519  -2          A01X+020726Y+018066X0198Y0197     S1      
317GND              VIA   -    MD0100PA00X+020990Y+017266X0200Y         S0      
327GND              R521  -2          A01X+020726Y+017266X0198Y0197     S1      
317GND              VIA   -    MD0100PA00X+021412Y+013458X0200Y         S0      
317GND              VIA   -    MD0100PA00X+021197Y+013330X0200Y         S0      
327GND              PC685 -2          A01X+021197Y+013090X0198Y0197R090 S1      
317GND              VIA   -    MD0100PA00X+021238Y+011078X0200Y         S0      
327GND              PU83  -3   M      A01X+021371Y+011368X0100Y0280     S1      
317GND              VIA   -    MD0100PA00X+021394Y+010225X0200Y    R180 S0      
327GND              PR6924-2   M      A01X+021394Y+010475X0198Y0197R270 S1      
317GND              VIA   -    MD0100PA00X+020973Y+011039X0200Y         S0      
317GND              VIA   -    MD0100PA00X+020973Y+011339X0200Y         S0      
317GND              VIA   -    MD0100PA00X+020220Y+011726X0200Y         S0      
327GND              R6199 -1          A01X+020262Y+011449X0198Y0197R180 S1      
317GND              VIA   -    MD0100PA00X+020359Y+009195X0200Y    R180 S0      
327GND              C2713 -1          A01X+020103Y+009195X0198Y0197R270 S1      
317GND              VIA   -    MD0100PA00X+020846Y+009647X0200Y         S0      
317GND              VIA   -    MD0100PA00X+020640Y+005551X0200Y         S0      
327GND              C2714 -1          A01X+020640Y+005801X0198Y0197R180 S1      
317GND              VIA   -    MD0100PA00X+021126Y+006092X0200Y         S0      
327GND              U127  -4          A01X+021126Y+006472X0240Y0460R180 S1      
317GND              VIA   -    MD0100PA00X+019548Y+046754X0200Y         S0      
317GND              VIA   -    MD0100PA00X+018517Y+046754X0200Y    R180 S0      
317GND              VIA   -    MD0100PA00X+019631Y+044795X0200Y         S0      
317GND              VIA   -    MD0100PA00X+018690Y+044585X0200Y    R180 S0      
317GND              VIA   -    MD0100PA00X+022329Y+023859X0200Y    R090 S0      
327GND              C2889 -2          A01X+022329Y+023601X0198Y0197R090 S1      
317GND              VIA   -    MD0100PA00X+022625Y+023612X0200Y    R090 S0      
327GND              PC517 -2          A01X+022882Y+023612X0198Y0197R090 S1      
317GND              VIA   -    MD0100PA00X+021760Y+020339X0200Y    R180 S0      
317GND              VIA   -    MD0100PA00X+022129Y+020684X0200Y    R180 S0      
317GND              VIA   -    M      A01X+021986Y+020168X0200Y    R090 S2      
017GND              VIA   -    M      A18X+021986Y+020168X0260Y    R090 S2      
017GND                    -    MD0100PA00X+021986Y+020168                       
317GND              VIA   -    MD0100PA00X+022379Y+020684X0200Y    R180 S0      
317GND              VIA   -    M      A01X+022304Y+019518X0200Y    R180 S2      
017GND              VIA   -    M      A18X+022304Y+019518X0260Y    R180 S2      
017GND                    -    MD0100PA00X+022304Y+019518                       
317GND              VIA   -    MD0100PA00X+021774Y+019518X0200Y    R180 S0      
317GND              VIA   -    MD0100PA00X+021986Y+019888X0200Y    R090 S0      
317GND              VIA   -    MD0100PA00X+022024Y+019518X0200Y    R180 S0      
317GND              VIA   -    MD0100PA00X+023150Y+015085X0200Y         S0      
317GND              VIA   -    MD0100PA00X+022670Y+014601X0200Y         S0      
327GND              C204  -2          A01X+022420Y+014601X0198Y0197R090 S1      
317GND              VIA   -    MD0100PA00X+023071Y+013776X0200Y         S0      
317GND              VIA   -    MD0100PA00X+022861Y+014123X0200Y         S0      
327GND              R5663 -2          A01X+022714Y+013884X0198Y0197     S1      
317GND              VIA   -    MD0100PA00X+021997Y+013330X0200Y         S0      
327GND              PC680 -2          A01X+021997Y+013090X0198Y0197R090 S1      
317GND              VIA   -    MD0100PA00X+023071Y+013067X0200Y         S0      
317GND              VIA   -    MD0100PA00X+023071Y+012358X0200Y         S0      
317GND              VIA   -    MD0100PA00X+022796Y+010917X0200Y         S0      
317GND              VIA   -    MD0100PA00X+021794Y+010225X0200Y    R180 S0      
327GND              PR6923-2   M      A01X+021794Y+010475X0198Y0197R270 S1      
317GND              VIA   -    MD0100PA00X+023071Y+011650X0200Y         S0      
317GND              VIA   -    MD0100PA00X+022697Y+010650X0200Y         S0      
327GND              C2765 -2   M      A01X+022956Y+010650X0198Y0197R180 S1      
317GND              VIA   -    MD0100PA00X+022496Y+010917X0200Y         S0      
317GND              VIA   -    M      A01X+022194Y+010225X0200Y    R180 S2      
017GND              VIA   -    M      A18X+022194Y+010225X0260Y    R180 S2      
017GND                    -    MD0100PA00X+022194Y+010225                       
317GND              VIA   -    MD0100PA00X+023168Y+000447X0200Y    R270 S0      
317GND              VIA   -    MD0100PA00X+021570Y+000300X0200Y    R270 S0      
317GND              VIA   -    MD0100PA00X+020328Y+046754X0200Y    R180 S0      
317GND              VIA   -    MD0100PA00X+021058Y+046754X0200Y         S0      
317GND              VIA   -    MD0100PA00X+021538Y+046754X0200Y         S0      
317GND              VIA   -    MD0100PA00X+020808Y+044585X0200Y         S0      
317GND              VIA   -    MD0100PA00X+020328Y+044585X0200Y    R180 S0      
317GND              VIA   -    MD0100PA00X+020328Y+043876X0200Y    R180 S0      
317GND              VIA   -    MD0100PA00X+020328Y+043167X0200Y    R180 S0      
317GND              VIA   -    MD0100PA00X+021058Y+043167X0200Y         S0      
317GND              VIA   -    MD0100PA00X+021538Y+043167X0200Y         S0      
317GND              VIA   -    MD0100PA00X+021538Y+043876X0200Y         S0      
317GND              VIA   -    MD0100PA00X+021058Y+043876X0200Y         S0      
317GND              VIA   -    MD0100PA00X+020808Y+043876X0200Y         S0      
317GND              VIA   -    MD0100PA00X+020808Y+043167X0200Y         S0      
317GND              VIA   -    MD0100PA00X+020328Y+042459X0200Y    R180 S0      
317GND              VIA   -    MD0100PA00X+020328Y+041750X0200Y    R180 S0      
317GND              VIA   -    MD0100PA00X+021538Y+042459X0200Y         S0      
317GND              VIA   -    MD0100PA00X+021058Y+042459X0200Y         S0      
317GND              VIA   -    MD0100PA00X+020808Y+042459X0200Y         S0      
317GND              VIA   -    MD0100PA00X+021058Y+041750X0200Y         S0      
317GND              VIA   -    MD0100PA00X+021538Y+041750X0200Y         S0      
317GND              VIA   -    MD0100PA00X+020808Y+041750X0200Y         S0      
317GND              VIA   -    MD0100PA00X+025373Y+009285X0200Y         S0      
317GND              VIA   -    MD0100PA00X+025117Y+007518X0200Y         S0      
317GND              VIA   -    MD0100PA00X+025117Y+008298X0200Y         S0      
317GND              VIA   -    MD0100PA00X+025117Y+008038X0200Y         S0      
317GND              VIA   -    MD0100PA00X+025117Y+007778X0200Y         S0      
317GND              VIA   -    MD0100PA00X+026036Y+005360X0200Y    R270 S0      
317GND              VIA   -    MD0100PA00X+023635Y+033943X0200Y         S0      
317GND              VIA   -    MD0100PA00X+023346Y+024729X0200Y         S0      
327GND              Q129  -4          A01X+023027Y+024729X0240Y0240R270 S1      
317GND              VIA   -    MD0100PA00X+024092Y+023871X0200Y    R090 S0      
327GND              PC530 -2          A01X+024092Y+023613X0198Y0197R090 S1      
317GND              VIA   -    MD0100PA00X+023269Y+023869X0200Y    R090 S0      
327GND              PR265 -2          A01X+023269Y+023611X0198Y0197R090 S1      
317GND              VIA   -    MD0100PA00X+023924Y+021354X0200Y    R090 S0      
317GND              VIA   -    MD0100PA00X+024271Y+013776X0200Y         S0      
317GND              VIA   -    MD0100PA00X+023551Y+013776X0200Y         S0      
317GND              VIA   -    MD0100PA00X+023551Y+012358X0200Y         S0      
317GND              VIA   -    MD0100PA00X+024271Y+012358X0200Y         S0      
317GND              VIA   -    MD0100PA00X+024271Y+013067X0200Y         S0      
317GND              VIA   -    MD0100PA00X+023551Y+013067X0200Y         S0      
317GND              VIA   -    MD0100PA00X+023801Y+013067X0200Y         S0      
317GND              VIA   -    MD0100PA00X+023801Y+012358X0200Y         S0      
317GND              VIA   -    MD0100PA00X+023801Y+010941X0200Y         S0      
317GND              VIA   -    MD0100PA00X+023551Y+011650X0200Y         S0      
317GND              VIA   -    MD0100PA00X+023801Y+011650X0200Y         S0      
317GND              VIA   -    MD0100PA00X+024271Y+010232X0200Y         S0      
317GND              VIA   -    MD0100PA00X+024271Y+010941X0200Y         S0      
317GND              VIA   -    MD0100PA00X+024271Y+011650X0200Y         S0      
317GND              VIA   -    MD0100PA00X+024036Y+005360X0200Y    R270 S0      
317GND              VIA   -    MD0100PA00X+023304Y+004477X0200Y    R270 S0      
317GND              VIA   -    MD0100PA00X+023304Y+002477X0200Y    R270 S0      
317GND              VIA   -    M      A01X+022827Y+041272X0200Y    R180 S2      
017GND              VIA   -    M      A18X+022827Y+041272X0260Y    R180 S2      
017GND                    -    MD0100PA00X+022827Y+041272                       
327GND              R71   -2          A01X+023069Y+041272X0198Y0197R180 S1      
317GND              VIA   -    M      A01X+022827Y+040472X0200Y    R180 S2      
017GND              VIA   -    M      A18X+022827Y+040472X0260Y    R180 S2      
017GND                    -    MD0100PA00X+022827Y+040472                       
327GND              R70   -2          A01X+023069Y+040472X0198Y0197R180 S1      
317GND              VIA   -    MD0100PA00X+022827Y+040072X0200Y    R180 S0      
327GND              R72   -2          A01X+023069Y+040072X0198Y0197R180 S1      
317GND              VIA   -    MD0100PA00X+022827Y+040872X0200Y    R180 S0      
327GND              R69   -2          A01X+023069Y+040872X0198Y0197R180 S1      
317GND              VIA   -    MD0100PA00X+022827Y+039272X0200Y    R180 S0      
327GND              R79   -2          A01X+023069Y+039272X0198Y0197R180 S1      
317GND              VIA   -    MD0100PA00X+022876Y+031612X0200Y         S0      
317GND              VIA   -    MD0100PA00X+022617Y+025320X0200Y         S0      
327GND              Q129  -1          A01X+022319Y+025320X0240Y0240R270 S1      
317GND              VIA   -    MD0100PA00X+027783Y+010170X0200Y    R090 S0      
317GND              VIA   -    MD0100PA00X+027810Y+009402X0200Y         S0      
317GND              VIA   -    MD0100PA00X+027410Y+009402X0200Y         S0      
317GND              VIA   -    MD0100PA00X+027847Y+004477X0200Y    R270 S0      
317GND              VIA   -    MD0100PA00X+027847Y+002477X0200Y    R270 S0      
317GND              VIA   -    MD0100PA00X+027916Y+000537X0200Y    R270 S0      
317GND              VIA   -    MD0100PA00X+026160Y+046549X0200Y         S0      
317GND              VIA   -    MD0100PA00X+025468Y+044987X0200Y         S0      
327GND              R89   -2          A01X+025228Y+044987X0198Y0197     S1      
317GND              VIA   -    MD0100PA00X+025376Y+043503X0200Y         S0      
327GND              R85   -2          A18X+025108Y+043503X0198Y0197R180 S2      
317GND              VIA   -    MD0100PA00X+025469Y+043103X0200Y         S0      
327GND              R83   -2          A18X+025108Y+043103X0198Y0197R180 S2      
317GND              VIA   -    MD0100PA00X+025500Y+042702X0200Y         S0      
327GND              R81   -2          A18X+025112Y+042702X0198Y0197R180 S2      
317GND              VIA   -    M      A01X+026501Y+040331X0200Y         S2      
017GND              VIA   -    M      A18X+026501Y+040331X0260Y         S2      
017GND                    -    MD0100PA00X+026501Y+040331                       
317GND              VIA   -    MD0100PA00X+025723Y+031208X0200Y         S0      
317GND              VIA   -    MD0100PA00X+026300Y+029380X0200Y         S0      
317GND              VIA   -    MD0100PA00X+025946Y+022373X0200Y    R090 S0      
317GND              VIA   -    MD0100PA00X+025946Y+022623X0200Y    R090 S0      
317GND              VIA   -    MD0100PA00X+025946Y+023123X0200Y    R090 S0      
317GND              VIA   -    MD0100PA00X+025946Y+022873X0200Y    R090 S0      
317GND              VIA   -    MD0100PA00X+025218Y+013776X0200Y    R180 S0      
317GND              VIA   -    MD0100PA00X+025741Y+013776X0200Y         S0      
317GND              VIA   -    MD0100PA00X+025219Y+013067X0200Y    R180 S0      
317GND              VIA   -    MD0100PA00X+026082Y+012358X0200Y         S0      
317GND              VIA   -    MD0100PA00X+026082Y+013067X0200Y         S0      
317GND              VIA   -    MD0100PA00X+025114Y+012458X0200Y    R180 S0      
317GND              VIA   -    MD0100PA00X+026082Y+010941X0200Y         S0      
317GND              VIA   -    MD0100PA00X+026082Y+011650X0200Y         S0      
317GND              VIA   -    MD0100PA00X+025096Y+011650X0200Y    R180 S0      
317GND              VIA   -    MD0100PA00X+025071Y+010232X0200Y    R180 S0      
317GND              VIA   -    MD0100PA00X+025096Y+010941X0200Y    R180 S0      
317GND              VIA   -    MD0100PA00X+026069Y+010304X0200Y         S0      
317GND              VIA   -    MD0100PA00X+025117Y+008558X0200Y         S0      
317GND              VIA   -    MD0100PA00X+026594Y+043010X0200Y    R270 S0      
317GND              VIA   -    MD0100PA00X+026594Y+043260X0200Y    R270 S0      
317GND              VIA   -    MD0100PA00X+026594Y+043510X0200Y    R270 S0      
317GND              VIA   -    MD0100PA00X+026594Y+043760X0200Y    R270 S0      
317GND              VIA   -    MD0100PA00X+026594Y+044010X0200Y    R270 S0      
317GND              VIA   -    MD0100PA00X+026501Y+041039X0200Y         S0      
317GND              VIA   -    MD0100PA00X+027442Y+039050X0200Y         S0      
327GND              R74   -2          A18X+027442Y+038800X0198Y0197     S2      
317GND              VIA   -    MD0100PA00X+027632Y+028569X0200Y         S0      
317GND              VIA   -    MD0100PA00X+026550Y+029380X0200Y         S0      
317GND              VIA   -    MD0100PA00X+027102Y+028569X0200Y         S0      
317GND              VIA   -    MD0100PA00X+027352Y+028819X0200Y         S0      
317GND              VIA   -    MD0100PA00X+027102Y+028819X0200Y         S0      
317GND              VIA   -    MD0100PA00X+027352Y+028569X0200Y         S0      
317GND              VIA   -    MD0100PA00X+027632Y+028819X0200Y         S0      
317GND              VIA   -    MD0100PA00X+027856Y+024889X0200Y    R180 S0      
317GND              VIA   -    MD0100PA00X+027356Y+024889X0200Y    R180 S0      
317GND              VIA   -    MD0100PA00X+027606Y+024889X0200Y    R180 S0      
317GND              VIA   -    MD0100PA00X+027386Y+023661X0200Y    R180 S0      
317GND              VIA   -    MD0100PA00X+027788Y+023179X0200Y    R090 S0      
317GND              VIA   -    MD0100PA00X+027886Y+023661X0200Y    R180 S0      
317GND              VIA   -    MD0100PA00X+027636Y+023661X0200Y    R180 S0      
317GND              VIA   -    MD0100PA00X+026991Y+023146X0200Y    R090 S0      
317GND              VIA   -    MD0100PA00X+027362Y+022614X0200Y         S0      
317GND              VIA   -    MD0100PA00X+027788Y+022929X0200Y    R090 S0      
317GND              VIA   -    M      A01X+026991Y+022366X0200Y    R090 S2      
017GND              VIA   -    M      A18X+026991Y+022366X0260Y    R090 S2      
017GND                    -    MD0100PA00X+026991Y+022366                       
317GND              VIA   -    M      A01X+027642Y+022614X0200Y         S2      
017GND              VIA   -    M      A18X+027642Y+022614X0260Y         S2      
017GND                    -    MD0100PA00X+027642Y+022614                       
317GND              VIA   -    MD0100PA00X+026991Y+022646X0200Y    R090 S0      
317GND              VIA   -    MD0100PA00X+026991Y+022896X0200Y    R090 S0      
317GND              VIA   -    M      A01X+027966Y+018873X0200Y         S2      
017GND              VIA   -    M      A18X+027966Y+018873X0260Y         S2      
017GND                    -    MD0100PA00X+027966Y+018873                       
327GND              C208  -2          A01X+028266Y+018740X0198Y0197R090 S1      
317GND              VIA   -    MD0100PA00X+027980Y+019194X0200Y         S0      
317GND              VIA   -    MD0100PA00X+027615Y+015154X0200Y         S0      
327GND              R5889 -2          A01X+027892Y+015154X0198Y0197R180 S1      
317GND              VIA   -    MD0100PA00X+026882Y+013776X0200Y    R180 S0      
317GND              VIA   -    MD0100PA00X+027823Y+012462X0200Y         S0      
317GND              VIA   -    MD0100PA00X+027823Y+012957X0200Y         S0      
317GND              VIA   -    MD0100PA00X+026882Y+012358X0200Y    R180 S0      
317GND              VIA   -    MD0100PA00X+026882Y+013067X0200Y    R180 S0      
317GND              VIA   -    MD0100PA00X+026882Y+010232X0200Y    R180 S0      
317GND              VIA   -    MD0100PA00X+027823Y+011044X0200Y         S0      
317GND              VIA   -    MD0100PA00X+027823Y+011540X0200Y         S0      
317GND              VIA   -    MD0100PA00X+026882Y+010941X0200Y    R180 S0      
317GND              VIA   -    MD0100PA00X+026882Y+011650X0200Y    R180 S0      
317GND              VIA   -    MD0100PA00X+029233Y+018057X0200Y         S0      
317GND              VIA   -    MD0100PA00X+029063Y+015237X0200Y         S0      
327GND              Q136  -1          A01X+028764Y+015237X0240Y0240R270 S1      
317GND              VIA   -    MD0100PA00X+028864Y+013669X0200Y         S0      
317GND              VIA   -    MD0100PA00X+029363Y+013669X0200Y         S0      
317GND              VIA   -    MD0100PA00X+029173Y+014646X0200Y         S0      
327GND              Q136  -4          A01X+029473Y+014646X0240Y0240R270 S1      
317GND              VIA   -    MD0100PA00X+029363Y+013173X0200Y         S0      
317GND              VIA   -    MD0100PA00X+029363Y+012251X0200Y         S0      
317GND              VIA   -    MD0100PA00X+028322Y+012462X0200Y         S0      
317GND              VIA   -    MD0100PA00X+028322Y+012957X0200Y         S0      
317GND              VIA   -    MD0100PA00X+028864Y+012251X0200Y         S0      
317GND              VIA   -    MD0100PA00X+028864Y+013173X0200Y         S0      
317GND              VIA   -    MD0100PA00X+029363Y+011756X0200Y         S0      
317GND              VIA   -    MD0100PA00X+029655Y+010362X0200Y    R090 S0      
317GND              VIA   -    MD0100PA00X+028538Y+010378X0200Y    R270 S0      
327GND              R416  -1          A01X+028538Y+010135X0198Y0197R270 S1      
317GND              VIA   -    MD0100PA00X+028322Y+011044X0200Y         S0      
317GND              VIA   -    MD0100PA00X+028322Y+011540X0200Y         S0      
317GND              VIA   -    MD0100PA00X+028864Y+011756X0200Y         S0      
317GND              VIA   -    MD0100PA00X+028611Y+009402X0200Y         S0      
317GND              VIA   -    MD0100PA00X+028210Y+009402X0200Y         S0      
317GND              VIA   -    MD0100PA00X+029118Y+007614X0200Y         S0      
317GND              VIA   -    MD0100PA00X+029118Y+008014X0200Y         S0      
317GND              VIA   -    MD0100PA00X+029118Y+008414X0200Y         S0      
317GND              VIA   -    MD0100PA00X+028613Y+003697X0200Y    R090 S0      
317GND              VIA   -    MD0100PA00X+029496Y+001110X0200Y    R270 S0      
327GND              U416  -4          A01X+029496Y+001441X0240Y0520R270 S1      
317GND              VIA   -    MD0100PA00X+026623Y+046226X0200Y         S0      
327GND              C418  -2          A18X+027010Y+046348X0198Y0197     S2      
317GND              VIA   -    MD0100PA00X+026640Y+046549X0200Y         S0      
317GND              VIA   -    MD0100PA00X+027420Y+046603X0200Y    R180 S0      
317GND              VIA   -    MD0100PA00X+026640Y+045841X0200Y         S0      
317GND              VIA   -    MD0100PA00X+026640Y+045132X0200Y         S0      
317GND              VIA   -    MD0100PA00X+028417Y+043996X0200Y    R180 S0      
317GND              VIA   -    MD0100PA00X+028413Y+043707X0200Y    R180 S0      
317GND              VIA   -    MD0100PA00X+028432Y+043357X0200Y    R180 S0      
317GND              VIA   -    MD0100PA00X+028430Y+043076X0200Y    R180 S0      
317GND              VIA   -    MD0100PA00X+029250Y+040331X0200Y    R180 S0      
317GND              VIA   -    MD0100PA00X+029250Y+041039X0200Y    R180 S0      
317GND              VIA   -    MD0100PA00X+028408Y+038150X0200Y         S0      
327GND              R73   -2          A18X+028408Y+038450X0198Y0197R180 S2      
317GND              VIA   -    M      A01X+028854Y+029076X0200Y         S2      
017GND              VIA   -    M      A18X+028854Y+029076X0260Y         S2      
017GND                    -    MD0100PA00X+028854Y+029076                       
317GND              VIA   -    MD0100PA00X+028054Y+029076X0200Y         S0      
327GND              PC651 -2   M      A01X+028054Y+028806X0198Y0197R090 S1      
317GND              VIA   -    MD0100PA00X+028454Y+029076X0200Y         S0      
327GND              PR6909-2   M      A01X+028454Y+028806X0198Y0197R090 S1      
317GND              VIA   -    MD0100PA00X+029661Y+028834X0200Y    R090 S0      
317GND              VIA   -    MD0100PA00X+029661Y+029084X0200Y    R090 S0      
317GND              VIA   -    MD0100PA00X+029661Y+029364X0200Y    R090 S0      
317GND              VIA   -    M      A01X+029462Y+028131X0200Y         S2      
017GND              VIA   -    M      A18X+029462Y+028131X0260Y         S2      
017GND                    -    MD0100PA00X+029462Y+028131                       
317GND              VIA   -    MD0100PA00X+029052Y+027921X0200Y         S0      
317GND              VIA   -    MD0100PA00X+028949Y+025654X0200Y         S0      
327GND              PC656 -2          A01X+028949Y+025954X0198Y0197R270 S1      
317GND              VIA   -    MD0100PA00X+028149Y+025654X0200Y         S0      
327GND              PC652 -2          A01X+028149Y+025954X0198Y0197R270 S1      
317GND              VIA   -    MD0100PA00X+028158Y+022221X0200Y    R090 S0      
317GND              VIA   -    MD0100PA00X+028158Y+022471X0200Y    R090 S0      
317GND              VIA   -    MD0100PA00X+028828Y+020676X0200Y         S0      
317GND              VIA   -    MD0100PA00X+028630Y+018462X0200Y         S0      
327GND              U55   -10         A01X+028916Y+018383X0090Y0240R090 S1      
317GND              VIA   -    MD0100PA00X+029233Y+018516X0200Y         S0      
317GND              VIA   -    MD0100PA00X+031001Y+031673X0200Y    R090 S0      
327GND              Q2    -4          A01X+030731Y+031673X0170Y0240R270 S1      
317GND              VIA   -    MD0100PA00X+029911Y+029364X0200Y    R090 S0      
317GND              VIA   -    MD0100PA00X+029911Y+028834X0200Y    R090 S0      
317GND              VIA   -    MD0100PA00X+029911Y+029084X0200Y    R090 S0      
317GND              VIA   -    MD0100PA00X+031230Y+021686X0200Y         S0      
327GND              PC397 -2          A01X+030972Y+021686X0198Y0197     S1      
317GND              VIA   -    MD0100PA00X+031230Y+022186X0200Y         S0      
327GND              C2865 -2   M      A01X+030972Y+022186X0198Y0197     S1      
317GND              VIA   -    MD0100PA00X+031230Y+020086X0200Y         S0      
317GND              VIA   -    MD0100PA00X+031230Y+021286X0200Y         S0      
317GND              VIA   -    MD0100PA00X+029697Y+018512X0200Y         S0      
317GND              VIA   -    MD0100PA00X+029976Y+019028X0200Y         S0      
317GND              VIA   -    MD0100PA00X+031226Y+018066X0200Y         S0      
327GND              R532  -2          A01X+030962Y+018066X0198Y0197     S1      
317GND              VIA   -    MD0100PA00X+031226Y+017266X0200Y         S0      
327GND              R531  -2          A01X+030962Y+017266X0198Y0197     S1      
317GND              VIA   -    MD0100PA00X+029701Y+018053X0200Y         S0      
327GND              U55   -TH  M      A01X+029467Y+018285X0670Y0670R180 S1      
317GND              VIA   -    MD0100PA00X+030456Y+011726X0200Y         S0      
327GND              R6200 -1          A01X+030498Y+011449X0198Y0197R180 S1      
317GND              VIA   -    MD0100PA00X+031209Y+011339X0200Y         S0      
317GND              VIA   -    MD0100PA00X+030595Y+009195X0200Y         S0      
327GND              C2715 -1          A01X+030340Y+009195X0198Y0197R270 S1      
317GND              VIA   -    MD0100PA00X+031088Y+009661X0200Y         S0      
317GND              VIA   -    MD0100PA00X+030876Y+005551X0200Y         S0      
327GND              C2716 -1          A01X+030876Y+005801X0198Y0197R180 S1      
317GND              VIA   -    MD0100PA00X+030911Y+003754X0200Y    R090 S0      
327GND              C3870 -2          A01X+030911Y+003501X0198Y0197R180 S1      
317GND              VIA   -    MD0100PA00X+029806Y+000300X0200Y    R270 S0      
317GND              VIA   -    MD0100PA00X+029232Y+046549X0200Y    R180 S0      
317GND              VIA   -    MD0100PA00X+028225Y+047014X0200Y         S0      
327GND              R75   -2          A18X+028225Y+046737X0198Y0197R180 S2      
317GND              VIA   -    MD0100PA00X+028452Y+046549X0200Y         S0      
317GND              VIA   -    MD0100PA00X+028448Y+046025X0200Y         S0      
317GND              VIA   -    MD0100PA00X+029232Y+045841X0200Y    R180 S0      
317GND              VIA   -    MD0100PA00X+028438Y+045202X0200Y    R180 S0      
317GND              VIA   -    MD0100PA00X+028444Y+045474X0200Y    R180 S0      
317GND              VIA   -    MD0100PA00X+028442Y+044318X0200Y    R180 S0      
317GND              VIA   -    MD0100PA00X+032048Y+035351X0200Y         S0      
327GND              C873  -2          A01X+032048Y+035085X0198Y0197     S1      
317GND              VIA   -    MD0100PA00X+031590Y+033632X0200Y         S0      
327GND              U16   -3          A01X+032027Y+033632X0220Y0530R090 S1      
317GND              VIA   -    MD0100PA00X+031986Y+032165X0200Y    R180 S0      
327GND              U17   -3          A01X+032343Y+032165X0400Y0500     S1      
317GND              VIA   -    MD0100PA00X+032388Y+030384X0200Y         S0      
327GND              C868  -2          A01X+032388Y+030665X0198Y0197R180 S1      
317GND              VIA   -    MD0100PA00X+031405Y+025237X0200Y         S0      
327GND              PR6914-2          A01X+031683Y+025237X0198Y0197R180 S1      
317GND              VIA   -    MD0100PA00X+032854Y+025320X0200Y         S0      
327GND              Q130  -1          A01X+032555Y+025320X0240Y0240R270 S1      
317GND              VIA   -    MD0100PA00X+032862Y+023612X0200Y    R090 S0      
317GND              VIA   -    MD0100PA00X+032565Y+023859X0200Y    R090 S0      
327GND              C2892 -2          A01X+032565Y+023601X0198Y0197R090 S1      
317GND              VIA   -    MD0100PA00X+032615Y+020684X0200Y    R180 S0      
317GND              VIA   -    MD0100PA00X+031747Y+020339X0200Y    R180 S0      
317GND              VIA   -    M      A01X+032222Y+020168X0200Y    R090 S2      
017GND              VIA   -    M      A18X+032222Y+020168X0260Y    R090 S2      
017GND                    -    MD0100PA00X+032222Y+020168                       
317GND              VIA   -    MD0100PA00X+031997Y+020339X0200Y    R180 S0      
317GND              VIA   -    MD0100PA00X+032365Y+020684X0200Y    R180 S0      
317GND              VIA   -    MD0100PA00X+031761Y+019518X0200Y    R180 S0      
317GND              VIA   -    MD0100PA00X+032011Y+019518X0200Y    R180 S0      
317GND              VIA   -    M      A01X+032541Y+019518X0200Y    R180 S2      
017GND              VIA   -    M      A18X+032541Y+019518X0260Y    R180 S2      
017GND                    -    MD0100PA00X+032541Y+019518                       
317GND              VIA   -    MD0100PA00X+032261Y+019518X0200Y    R180 S0      
317GND              VIA   -    MD0100PA00X+032222Y+019888X0200Y    R090 S0      
317GND              VIA   -    MD0100PA00X+031648Y+013458X0200Y         S0      
327GND              U384  -3          A01X+031337Y+013674X0240Y0240     S1      
317GND              VIA   -    MD0100PA00X+032906Y+014601X0200Y         S0      
327GND              C3664 -2          A01X+032656Y+014601X0198Y0197R090 S1      
317GND              VIA   -    MD0100PA00X+032233Y+013330X0200Y         S0      
327GND              PC682 -2          A01X+032233Y+013090X0198Y0197R090 S1      
317GND              VIA   -    MD0100PA00X+031485Y+013090X0200Y         S0      
327GND              PC687 -2          A01X+031233Y+013090X0198Y0197R090 S1      
317GND              VIA   -    MD0100PA00X+031474Y+011078X0200Y         S0      
327GND              PU84  -3   M      A01X+031607Y+011368X0100Y0280     S1      
317GND              VIA   -    MD0100PA00X+031631Y+010225X0200Y    R180 S0      
327GND              PR6926-2   M      A01X+031631Y+010475X0198Y0197R270 S1      
317GND              VIA   -    MD0100PA00X+032732Y+010917X0200Y         S0      
317GND              VIA   -    MD0100PA00X+032031Y+010225X0200Y    R180 S0      
327GND              PR6925-2   M      A01X+032031Y+010475X0198Y0197R270 S1      
317GND              VIA   -    M      A01X+032431Y+010225X0200Y    R180 S2      
017GND              VIA   -    M      A18X+032431Y+010225X0260Y    R180 S2      
017GND                    -    MD0100PA00X+032431Y+010225                       
317GND              VIA   -    MD0100PA00X+031362Y+006092X0200Y         S0      
327GND              U128  -4          A01X+031362Y+006472X0240Y0460R180 S1      
317GND              VIA   -    MD0100PA00X+031806Y+000300X0200Y    R270 S0      
317GND              VIA   -    MD0100PA00X+030246Y+044579X0200Y         S0      
327GND              C869  -2          A18X+030246Y+044863X0198Y0197R090 S2      
317GND              VIA   -    MD0100PA00X+029851Y+044591X0200Y         S0      
327GND              C867  -2          A18X+029851Y+044863X0198Y0197R090 S2      
317GND              VIA   -    MD0100PA00X+030667Y+041884X0200Y         S0      
317GND              VIA   -    MD0100PA00X+030926Y+040192X0200Y         S0      
327GND              R68   -2          A18X+030686Y+040192X0198Y0197R180 S2      
317GND              VIA   -    MD0100PA00X+030926Y+040592X0200Y         S0      
327GND              R67   -2          A18X+030686Y+040592X0198Y0197R180 S2      
317GND              VIA   -    MD0100PA00X+030926Y+040992X0200Y         S0      
317GND              VIA   -    MD0100PA00X+030139Y+040004X0200Y    R090 S0      
317GND              VIA   -    MD0100PA00X+030131Y+039535X0200Y    R090 S0      
317GND              VIA   -    MD0100PA00X+030926Y+038591X0200Y         S0      
327GND              R64   -2          A18X+030686Y+038591X0198Y0197R180 S2      
317GND              VIA   -    MD0100PA00X+030926Y+039392X0200Y         S0      
317GND              VIA   -    MD0100PA00X+030926Y+038991X0200Y         S0      
327GND              R65   -2          A18X+030686Y+038991X0198Y0197R180 S2      
317GND              VIA   -    MD0100PA00X+030116Y+038031X0200Y    R090 S0      
317GND              VIA   -    MD0100PA00X+030194Y+033202X0200Y    R270 S0      
327GND              C872  -2          A01X+030454Y+033202X0198Y0197R090 S1      
317GND              VIA   -    MD0100PA00X+030681Y+034232X0200Y         S0      
327GND              U15   -3          A01X+030328Y+034232X0160Y0360R270 S1      
317GND              VIA   -    MD0100PA00X+030297Y+032414X0200Y    R090 S0      
327GND              Q2    -1          A01X+029983Y+032185X0170Y0240R270 S1      
317GND              VIA   -    MD0100PA00X+034161Y+021354X0200Y    R090 S0      
317GND              VIA   -    MD0100PA00X+033386Y+015085X0200Y         S0      
327GND              U366  -S          A01X+032991Y+015330X0400Y0560     S1      
317GND              VIA   -    MD0100PA00X+034507Y+013776X0200Y         S0      
317GND              VIA   -    MD0100PA00X+033097Y+014123X0200Y         S0      
327GND              R5659 -2          A01X+032950Y+013884X0198Y0197     S1      
317GND              VIA   -    MD0100PA00X+033787Y+013776X0200Y         S0      
317GND              VIA   -    MD0100PA00X+033307Y+013776X0200Y         S0      
317GND              VIA   -    MD0100PA00X+034037Y+013067X0200Y         S0      
317GND              VIA   -    MD0100PA00X+033307Y+013067X0200Y         S0      
317GND              VIA   -    MD0100PA00X+033307Y+012358X0200Y         S0      
317GND              VIA   -    MD0100PA00X+033787Y+012358X0200Y         S0      
317GND              VIA   -    MD0100PA00X+034037Y+012358X0200Y         S0      
317GND              VIA   -    MD0100PA00X+034507Y+012358X0200Y         S0      
317GND              VIA   -    MD0100PA00X+034507Y+013067X0200Y         S0      
317GND              VIA   -    MD0100PA00X+033787Y+013067X0200Y         S0      
317GND              VIA   -    MD0100PA00X+033032Y+010917X0200Y         S0      
317GND              VIA   -    MD0100PA00X+033307Y+011650X0200Y         S0      
317GND              VIA   -    MD0100PA00X+034037Y+010941X0200Y         S0      
317GND              VIA   -    MD0100PA00X+034507Y+010232X0200Y         S0      
317GND              VIA   -    MD0100PA00X+034507Y+010941X0200Y         S0      
317GND              VIA   -    MD0100PA00X+034037Y+011650X0200Y         S0      
317GND              VIA   -    MD0100PA00X+033787Y+011650X0200Y         S0      
317GND              VIA   -    MD0100PA00X+034507Y+011650X0200Y         S0      
317GND              VIA   -    MD0100PA00X+032933Y+010650X0200Y         S0      
327GND              C2766 -2   M      A01X+033192Y+010650X0198Y0197R180 S1      
317GND              VIA   -    MD0100PA00X+034272Y+005360X0200Y    R270 S0      
317GND              VIA   -    MD0100PA00X+033540Y+004477X0200Y    R270 S0      
317GND              VIA   -    MD0100PA00X+033090Y+003181X0200Y    R090 S0      
327GND              R5811 -2          A01X+032848Y+003181X0198Y0197     S1      
317GND              VIA   -    MD0100PA00X+033090Y+002381X0200Y    R090 S0      
327GND              R5812 -2          A01X+032848Y+002381X0198Y0197     S1      
317GND              VIA   -    MD0100PA00X+033540Y+002477X0200Y    R270 S0      
317GND              VIA   -    MD0100PA00X+033090Y+001181X0200Y    R090 S0      
327GND              R5813 -2          A01X+032848Y+001181X0198Y0197     S1      
317GND              VIA   -    MD0100PA00X+033404Y+000447X0200Y    R270 S0      
317GND              VIA   -    MD0100PA00X+031850Y+047148X0200Y    R270 S0      
317GND              VIA   -    MD0100PA00X+032349Y+046653X0200Y    R090 S0      
317GND              VIA   -    MD0100PA00X+031850Y+046653X0200Y    R270 S0      
317GND              VIA   -    MD0100PA00X+032349Y+047148X0200Y    R090 S0      
317GND              VIA   -    MD0100PA00X+032155Y+044812X0200Y    R090 S0      
317GND              VIA   -    MD0100PA00X+032155Y+044532X0200Y    R090 S0      
317GND              VIA   -    MD0100PA00X+034745Y+044749X0200Y    R090 S0      
327GND              PC667 -2          A01X+034745Y+045033X0198Y0197R180 S1      
317GND              VIA   -    MD0100PA00X+035804Y+043972X0200Y    R270 S0      
317GND              VIA   -    MD0100PA00X+035804Y+044252X0200Y    R270 S0      
317GND              VIA   -    MD0100PA00X+036123Y+040287X0200Y    R270 S0      
327GND              U80   -10         A01X+036048Y+040004X0090Y0240     S1      
317GND              VIA   -    MD0100PA00X+035722Y+039687X0200Y    R270 S0      
317GND              VIA   -    MD0100PA00X+035717Y+039218X0200Y    R270 S0      
317GND              VIA   -    MD0100PA00X+035449Y+037717X0200Y    R270 S0      
327GND              R697  -2          A01X+035449Y+037957X0198Y0197R270 S1      
317GND              VIA   -    MD0100PA00X+034874Y+037539X0200Y    R270 S0      
327GND              R696  -2          A01X+034649Y+037957X0198Y0197R270 S1      
317GND              VIA   -    MD0100PA00X+034897Y+033314X0200Y         S0      
317GND              VIA   -    MD0100PA00X+034838Y+032228X0200Y         S0      
317GND              VIA   -    MD0100PA00X+035642Y+030129X0200Y         S0      
317GND              VIA   -    MD0100PA00X+035455Y+013776X0200Y    R180 S0      
317GND              VIA   -    MD0100PA00X+035952Y+013776X0200Y         S0      
317GND              VIA   -    MD0100PA00X+035455Y+013067X0200Y    R180 S0      
317GND              VIA   -    MD0100PA00X+035350Y+012458X0200Y    R180 S0      
317GND              VIA   -    MD0100PA00X+035333Y+011650X0200Y    R180 S0      
317GND              VIA   -    MD0100PA00X+035333Y+010941X0200Y    R180 S0      
317GND              VIA   -    MD0100PA00X+035307Y+010232X0200Y    R180 S0      
317GND              VIA   -    MD0100PA00X+035354Y+008558X0200Y         S0      
317GND              VIA   -    MD0100PA00X+035609Y+009285X0200Y         S0      
317GND              VIA   -    MD0100PA00X+035354Y+007518X0200Y         S0      
317GND              VIA   -    MD0100PA00X+035354Y+007778X0200Y         S0      
317GND              VIA   -    MD0100PA00X+035354Y+008038X0200Y         S0      
317GND              VIA   -    MD0100PA00X+035354Y+008298X0200Y         S0      
317GND              VIA   -    MD0100PA00X+034505Y+045833X0200Y    R090 S0      
317GND              VIA   -    MD0100PA00X+034329Y+023871X0200Y    R090 S0      
327GND              PC543 -2          A01X+034329Y+023613X0198Y0197R090 S1      
317GND              VIA   -    MD0100PA00X+033583Y+024729X0200Y         S0      
327GND              Q130  -4          A01X+033264Y+024729X0240Y0240R270 S1      
317GND              VIA   -    MD0100PA00X+033505Y+023869X0200Y    R090 S0      
327GND              PR270 -2          A01X+033505Y+023611X0198Y0197R090 S1      
317GND              VIA   -    MD0100PA00X+036181Y+039687X0200Y    R270 S0      
317GND              VIA   -    MD0100PA00X+036455Y+040903X0200Y    R270 S0      
327GND              C413  -2          A01X+036455Y+040653X0198Y0197     S1      
317GND              VIA   -    M      A01X+036859Y+040902X0200Y    R270 S2      
017GND              VIA   -    M      A18X+036859Y+040902X0260Y    R270 S2      
017GND                    -    MD0100PA00X+036859Y+040902                       
327GND              C871  -2          A01X+036859Y+040662X0198Y0197R090 S1      
317GND              VIA   -    MD0100PA00X+037699Y+039525X0200Y    R270 S0      
317GND              VIA   -    MD0100PA00X+036177Y+039223X0200Y    R270 S0      
327GND              U80   -TH  M      A01X+035950Y+039452X0670Y0670R090 S1      
317GND              VIA   -    MD0100PA00X+037326Y+037001X0200Y         S0      
317GND              VIA   -    MD0100PA00X+036493Y+037423X0200Y         S0      
317GND              VIA   -    MD0100PA00X+036806Y+035418X0200Y         S0      
317GND              VIA   -    MD0100PA00X+037588Y+028819X0200Y         S0      
317GND              VIA   -    MD0100PA00X+037338Y+028569X0200Y         S0      
317GND              VIA   -    MD0100PA00X+037588Y+028569X0200Y         S0      
317GND              VIA   -    MD0100PA00X+037338Y+028819X0200Y         S0      
317GND              VIA   -    MD0100PA00X+036786Y+029380X0200Y         S0      
317GND              VIA   -    MD0100PA00X+036536Y+029380X0200Y         S0      
317GND              VIA   -    MD0100PA00X+037593Y+024889X0200Y    R180 S0      
317GND              VIA   -    MD0100PA00X+037622Y+023661X0200Y    R180 S0      
317GND              VIA   -    M      A01X+037878Y+022614X0200Y         S2      
017GND              VIA   -    M      A18X+037878Y+022614X0260Y         S2      
017GND                    -    MD0100PA00X+037878Y+022614                       
317GND              VIA   -    M      A01X+037228Y+022366X0200Y    R090 S2      
017GND              VIA   -    M      A18X+037228Y+022366X0260Y    R090 S2      
017GND                    -    MD0100PA00X+037228Y+022366                       
317GND              VIA   -    MD0100PA00X+037228Y+023146X0200Y    R090 S0      
317GND              VIA   -    MD0100PA00X+037228Y+022896X0200Y    R090 S0      
317GND              VIA   -    MD0100PA00X+036182Y+022623X0200Y    R090 S0      
317GND              VIA   -    MD0100PA00X+036182Y+022373X0200Y    R090 S0      
317GND              VIA   -    MD0100PA00X+036182Y+022873X0200Y    R090 S0      
317GND              VIA   -    MD0100PA00X+036182Y+023123X0200Y    R090 S0      
317GND              VIA   -    MD0100PA00X+037598Y+022614X0200Y         S0      
317GND              VIA   -    MD0100PA00X+037228Y+022646X0200Y    R090 S0      
317GND              VIA   -    MD0100PA00X+037118Y+013776X0200Y    R180 S0      
317GND              VIA   -    MD0100PA00X+037118Y+012358X0200Y    R180 S0      
317GND              VIA   -    MD0100PA00X+037118Y+013067X0200Y    R180 S0      
317GND              VIA   -    MD0100PA00X+036318Y+012358X0200Y         S0      
317GND              VIA   -    MD0100PA00X+036318Y+013067X0200Y         S0      
317GND              VIA   -    MD0100PA00X+037118Y+010232X0200Y    R180 S0      
317GND              VIA   -    MD0100PA00X+037118Y+010941X0200Y    R180 S0      
317GND              VIA   -    MD0100PA00X+037118Y+011650X0200Y    R180 S0      
317GND              VIA   -    MD0100PA00X+036318Y+010941X0200Y         S0      
317GND              VIA   -    MD0100PA00X+036318Y+011650X0200Y         S0      
317GND              VIA   -    MD0100PA00X+036305Y+010304X0200Y         S0      
317GND              VIA   -    MD0100PA00X+037647Y+009402X0200Y         S0      
317GND              VIA   -    MD0100PA00X+036272Y+005360X0200Y    R270 S0      
317GND              VIA   -    MD0100PA00X+039100Y+013669X0200Y         S0      
317GND              VIA   -    MD0100PA00X+038060Y+012462X0200Y         S0      
317GND              VIA   -    MD0100PA00X+038559Y+012462X0200Y         S0      
317GND              VIA   -    MD0100PA00X+038060Y+012957X0200Y         S0      
317GND              VIA   -    MD0100PA00X+038559Y+012957X0200Y         S0      
317GND              VIA   -    MD0100PA00X+039100Y+012251X0200Y         S0      
317GND              VIA   -    MD0100PA00X+039100Y+013173X0200Y         S0      
317GND              VIA   -    MD0100PA00X+038775Y+010378X0200Y    R270 S0      
327GND              R420  -1          A01X+038775Y+010135X0198Y0197R270 S1      
317GND              VIA   -    MD0100PA00X+038060Y+011044X0200Y         S0      
317GND              VIA   -    MD0100PA00X+038559Y+011044X0200Y         S0      
317GND              VIA   -    MD0100PA00X+038060Y+011540X0200Y         S0      
317GND              VIA   -    MD0100PA00X+038559Y+011540X0200Y         S0      
317GND              VIA   -    MD0100PA00X+039100Y+011756X0200Y         S0      
317GND              VIA   -    MD0100PA00X+038020Y+010170X0200Y    R090 S0      
317GND              VIA   -    MD0100PA00X+038047Y+009402X0200Y         S0      
317GND              VIA   -    MD0100PA00X+038848Y+009402X0200Y         S0      
317GND              VIA   -    MD0100PA00X+038447Y+009402X0200Y         S0      
317GND              VIA   -    MD0100PA00X+039354Y+008014X0200Y         S0      
317GND              VIA   -    MD0100PA00X+039354Y+008414X0200Y         S0      
317GND              VIA   -    MD0100PA00X+039354Y+007614X0200Y         S0      
317GND              VIA   -    MD0100PA00X+038083Y+004477X0200Y    R270 S0      
317GND              VIA   -    MD0100PA00X+038361Y+003062X0200Y    R270 S0      
327GND              C2718 -1          A01X+038611Y+003062X0198Y0197R090 S1      
317GND              VIA   -    MD0100PA00X+038083Y+002477X0200Y    R270 S0      
317GND              VIA   -    MD0100PA00X+038849Y+002407X0200Y    R270 S0      
327GND              U129  -4          A01X+039282Y+002575X0240Y0460R090 S1      
317GND              VIA   -    MD0100PA00X+038152Y+000537X0200Y    R270 S0      
317GND              VIA   -    MD0100PA00X+038806Y+000300X0200Y    R270 S0      
317GND              VIA   -    MD0100PA00X+036644Y+047219X0200Y         S0      
317GND              VIA   -    MD0100PA00X+036928Y+046529X0200Y    R270 S0      
317GND              VIA   -    MD0100PA00X+036928Y+046809X0200Y    R270 S0      
317GND              VIA   -    MD0100PA00X+037610Y+046231X0200Y    R270 S0      
327GND              PC666 -2   M      A01X+037360Y+046231X0198Y0197     S1      
317GND              VIA   -    MD0100PA00X+036756Y+045274X0200Y    R090 S0      
317GND              VIA   -    MD0100PA00X+037610Y+045431X0200Y    R270 S0      
327GND              PR6918-2   M      A01X+037360Y+045431X0198Y0197     S1      
317GND              VIA   -    MD0100PA00X+037610Y+045831X0200Y    R270 S0      
327GND              PR6917-2   M      A01X+037360Y+045831X0198Y0197     S1      
317GND              VIA   -    MD0100PA00X+036792Y+044632X0200Y    R270 S0      
317GND              VIA   -    MD0100PA00X+036792Y+044912X0200Y    R270 S0      
317GND              VIA   -    MD0100PA00X+036495Y+045009X0200Y    R090 S0      
317GND              VIA   -    MD0100PA00X+037592Y+044632X0200Y    R270 S0      
317GND              VIA   -    MD0100PA00X+037592Y+044912X0200Y    R270 S0      
317GND              VIA   -    MD0100PA00X+039891Y+010362X0200Y    R090 S0      
327GND              U401  -S          A01X+039891Y+010792X0400Y0560R180 S1      
317GND              VIA   -    MD0100PA00X+039599Y+011756X0200Y         S0      
317GND              VIA   -    MD0100PA00X+040849Y+011758X0200Y         S0      
327GND              R6201 -1          A01X+040734Y+011449X0198Y0197R180 S1      
317GND              VIA   -    MD0100PA00X+040806Y+000300X0200Y    R270 S0      
317GND              VIA   -    MD0100PA00X+039384Y+046641X0200Y    R090 S0      
327GND              PC470 -2          A01X+039124Y+046641X0198Y0197     S1      
317GND              VIA   -    MD0100PA00X+038558Y+045564X0200Y    R270 S0      
317GND              VIA   -    MD0100PA00X+038558Y+045284X0200Y    R270 S0      
317GND              VIA   -    MD0100PA00X+038558Y+045004X0200Y    R270 S0      
317GND              VIA   -    M      A01X+039383Y+042394X0200Y         S2      
017GND              VIA   -    M      A18X+039383Y+042394X0260Y         S2      
017GND                    -    MD0100PA00X+039383Y+042394                       
317GND              VIA   -    M      A01X+039389Y+041361X0200Y         S2      
017GND              VIA   -    M      A18X+039389Y+041361X0260Y         S2      
017GND                    -    MD0100PA00X+039389Y+041361                       
317GND              VIA   -    MD0100PA00X+039244Y+040195X0200Y         S0      
317GND              VIA   -    M      A01X+039637Y+040710X0200Y    R270 S2      
017GND              VIA   -    M      A18X+039637Y+040710X0260Y    R270 S2      
017GND                    -    MD0100PA00X+039637Y+040710                       
317GND              VIA   -    MD0100PA00X+038524Y+037098X0200Y    R270 S0      
317GND              VIA   -    MD0100PA00X+038924Y+037107X0200Y    R270 S0      
327GND              PC456 -2          A01X+038924Y+037348X0198Y0197R270 S1      
317GND              VIA   -    MD0100PA00X+039239Y+034256X0200Y         S0      
317GND              VIA   -    MD0100PA00X+039239Y+033760X0200Y         S0      
317GND              VIA   -    M      A01X+039090Y+029076X0200Y         S2      
017GND              VIA   -    M      A18X+039090Y+029076X0260Y         S2      
017GND                    -    MD0100PA00X+039090Y+029076                       
317GND              VIA   -    MD0100PA00X+038290Y+029076X0200Y         S0      
327GND              PC653 -2   M      A01X+038290Y+028806X0198Y0197R090 S1      
317GND              VIA   -    MD0100PA00X+038690Y+029076X0200Y         S0      
327GND              PR6911-2   M      A01X+038690Y+028806X0198Y0197R090 S1      
317GND              VIA   -    MD0100PA00X+037868Y+028819X0200Y         S0      
317GND              VIA   -    MD0100PA00X+037868Y+028569X0200Y         S0      
317GND              VIA   -    MD0100PA00X+039288Y+027921X0200Y         S0      
317GND              VIA   -    MD0100PA00X+038385Y+025654X0200Y         S0      
327GND              PC654 -2          A01X+038385Y+025954X0198Y0197R270 S1      
317GND              VIA   -    MD0100PA00X+039185Y+025654X0200Y         S0      
327GND              PC657 -2          A01X+039185Y+025954X0198Y0197R270 S1      
317GND              VIA   -    MD0100PA00X+038093Y+024889X0200Y    R180 S0      
317GND              VIA   -    MD0100PA00X+037843Y+024889X0200Y    R180 S0      
317GND              VIA   -    MD0100PA00X+038024Y+023179X0200Y    R090 S0      
317GND              VIA   -    MD0100PA00X+037872Y+023661X0200Y    R180 S0      
317GND              VIA   -    MD0100PA00X+038122Y+023661X0200Y    R180 S0      
317GND              VIA   -    MD0100PA00X+038394Y+022471X0200Y    R090 S0      
317GND              VIA   -    MD0100PA00X+038394Y+022221X0200Y    R090 S0      
317GND              VIA   -    MD0100PA00X+038024Y+022929X0200Y    R090 S0      
317GND              VIA   -    MD0100PA00X+039064Y+020676X0200Y         S0      
317GND              VIA   -    M      A01X+038202Y+018873X0200Y         S2      
017GND              VIA   -    M      A18X+038202Y+018873X0260Y         S2      
017GND                    -    MD0100PA00X+038202Y+018873                       
327GND              C211  -2          A01X+038502Y+018740X0198Y0197R090 S1      
317GND              VIA   -    MD0100PA00X+038866Y+018462X0200Y         S0      
327GND              U56   -10         A01X+039152Y+018383X0090Y0240R090 S1      
317GND              VIA   -    MD0100PA00X+038216Y+019194X0200Y         S0      
327GND              C207  -2          A01X+038494Y+019194X0198Y0197R180 S1      
317GND              VIA   -    MD0100PA00X+039558Y+045284X0200Y    R270 S0      
317GND              VIA   -    MD0100PA00X+039558Y+045004X0200Y    R270 S0      
317GND              VIA   -    MD0100PA00X+039913Y+042394X0200Y         S0      
317GND              VIA   -    MD0100PA00X+040163Y+042394X0200Y         S0      
317GND              VIA   -    MD0100PA00X+040169Y+041361X0200Y         S0      
317GND              VIA   -    MD0100PA00X+039919Y+041361X0200Y         S0      
317GND              VIA   -    MD0100PA00X+039669Y+041361X0200Y         S0      
317GND              VIA   -    MD0100PA00X+040939Y+042039X0200Y    R180 S0      
317GND              VIA   -    MD0100PA00X+039663Y+042394X0200Y         S0      
317GND              VIA   -    MD0100PA00X+040202Y+040264X0200Y         S0      
317GND              VIA   -    MD0100PA00X+039952Y+040264X0200Y         S0      
317GND              VIA   -    MD0100PA00X+039494Y+039895X0200Y         S0      
317GND              VIA   -    MD0100PA00X+040684Y+039666X0200Y    R090 S0      
317GND              VIA   -    MD0100PA00X+040684Y+040166X0200Y    R090 S0      
317GND              VIA   -    MD0100PA00X+040684Y+039916X0200Y    R090 S0      
317GND              VIA   -    MD0100PA00X+040927Y+040824X0200Y    R180 S0      
317GND              VIA   -    MD0100PA00X+039637Y+040990X0200Y    R270 S0      
317GND              VIA   -    MD0100PA00X+039424Y+037090X0200Y         S0      
327GND              C2855 -2          A01X+039424Y+037348X0198Y0197R270 S1      
317GND              VIA   -    MD0100PA00X+040749Y+035414X0200Y         S0      
317GND              VIA   -    MD0100PA00X+039737Y+034444X0200Y         S0      
327GND              C2670 -2          A01X+040073Y+034444X0280Y0320R090 S1      
317GND              VIA   -    MD0100PA00X+039895Y+033371X0200Y         S0      
317GND              VIA   -    MD0100PA00X+040948Y+031492X0200Y         S0      
317GND              VIA   -    MD0100PA00X+039898Y+029084X0200Y    R090 S0      
317GND              VIA   -    MD0100PA00X+039898Y+028834X0200Y    R090 S0      
317GND              VIA   -    MD0100PA00X+040148Y+029084X0200Y    R090 S0      
317GND              VIA   -    MD0100PA00X+040148Y+028834X0200Y    R090 S0      
317GND              VIA   -    MD0100PA00X+040148Y+029364X0200Y    R090 S0      
317GND              VIA   -    MD0100PA00X+039898Y+029364X0200Y    R090 S0      
317GND              VIA   -    M      A01X+039699Y+028131X0200Y         S2      
017GND              VIA   -    M      A18X+039699Y+028131X0260Y         S2      
017GND                    -    MD0100PA00X+039699Y+028131                       
317GND              VIA   -    MD0100PA00X+039933Y+018512X0200Y         S0      
317GND              VIA   -    MD0100PA00X+039469Y+018516X0200Y         S0      
317GND              VIA   -    MD0100PA00X+040310Y+019242X0200Y         S0      
317GND              VIA   -    MD0100PA00X+039469Y+018057X0200Y         S0      
317GND              VIA   -    MD0100PA00X+039937Y+018053X0200Y         S0      
327GND              U56   -TH  M      A01X+039703Y+018285X0670Y0670R180 S1      
317GND              VIA   -    MD0100PA00X+039599Y+013669X0200Y         S0      
317GND              VIA   -    MD0100PA00X+039599Y+012251X0200Y         S0      
317GND              VIA   -    MD0100PA00X+039599Y+013173X0200Y         S0      
317GND              VIA   -    MD0100PA00X+041545Y+045504X0200Y    R270 S0      
317GND              VIA   -    MD0100PA00X+041185Y+042674X0200Y    R180 S0      
327GND              PC607 -2   M      A01X+041185Y+042926X0198Y0197R270 S1      
317GND              VIA   -    MD0100PA00X+041189Y+042039X0200Y    R180 S0      
317GND              VIA   -    MD0100PA00X+041439Y+042039X0200Y    R180 S0      
317GND              VIA   -    MD0100PA00X+041185Y+042424X0200Y    R180 S0      
317GND              VIA   -    MD0100PA00X+041888Y+039916X0200Y    R090 S0      
317GND              VIA   -    MD0100PA00X+041427Y+040824X0200Y    R180 S0      
317GND              VIA   -    MD0100PA00X+041177Y+040824X0200Y    R180 S0      
317GND              VIA   -    MD0100PA00X+041888Y+039666X0200Y    R090 S0      
317GND              VIA   -    MD0100PA00X+041888Y+040166X0200Y    R090 S0      
317GND              VIA   -    MD0100PA00X+042448Y+036786X0200Y         S0      
327GND              R1134 -2          A01X+042448Y+036523X0198Y0197R090 S1      
317GND              VIA   -    MD0100PA00X+041632Y+036790X0200Y         S0      
327GND              R1133 -2          A01X+041632Y+036522X0198Y0197R090 S1      
317GND              VIA   -    MD0100PA00X+041343Y+034680X0200Y         S0      
327GND              U115  -2          A01X+041689Y+034559X0070Y0340R270 S1      
317GND              VIA   -    MD0100PA00X+042123Y+034578X0200Y         S0      
317GND              VIA   -    MD0100PA00X+042123Y+033126X0200Y         S0      
317GND              VIA   -    MD0100PA00X+042123Y+033852X0200Y         S0      
317GND              VIA   -    MD0100PA00X+041198Y+031492X0200Y         S0      
317GND              VIA   -    MD0100PA00X+041500Y+030697X0200Y         S0      
317GND              VIA   -    MD0100PA00X+041996Y+030697X0200Y         S0      
317GND              VIA   -    MD0100PA00X+042287Y+030997X0200Y         S0      
317GND              VIA   -    MD0100PA00X+041466Y+022186X0200Y         S0      
327GND              C2867 -2   M      A01X+041208Y+022186X0198Y0197     S1      
317GND              VIA   -    MD0100PA00X+041466Y+021686X0200Y         S0      
327GND              PC373 -2          A01X+041208Y+021686X0198Y0197     S1      
317GND              VIA   -    MD0100PA00X+041466Y+020086X0200Y         S0      
317GND              VIA   -    MD0100PA00X+041466Y+021286X0200Y         S0      
317GND              VIA   -    MD0100PA00X+041463Y+017266X0200Y         S0      
327GND              R542  -2          A01X+041198Y+017266X0198Y0197     S1      
317GND              VIA   -    MD0100PA00X+041463Y+018066X0200Y         S0      
327GND              R543  -2          A01X+041198Y+018066X0198Y0197     S1      
317GND              VIA   -    MD0100PA00X+042615Y+015154X0200Y         S0      
317GND              VIA   -    MD0100PA00X+042005Y+003342X0200Y    R090 S0      
327GND              C2717 -1          A01X+042005Y+003598X0198Y0197R180 S1      
317GND              VIA   -    MD0100PA00X+039558Y+045564X0200Y    R270 S0      
317GND              VIA   -    MD0100PA00X+045845Y+034471X0200Y         S0      
317GND              VIA   -    MD0100PA00X+045845Y+033976X0200Y         S0      
317GND              VIA   -    MD0100PA00X+045845Y+032401X0200Y         S0      
317GND              VIA   -    MD0100PA00X+045845Y+032896X0200Y         S0      
317GND              VIA   -    MD0100PA00X+044806Y+000300X0200Y    R270 S0      
317GND              VIA   -    MD0100PA00X+042778Y+046403X0200Y         S0      
317GND              VIA   -    MD0100PA00X+043231Y+043616X0200Y    R270 S0      
327GND              PU72  -3          A01X+042918Y+043616X0100Y0320R090 S1      
317GND              VIA   -    MD0100PA00X+043372Y+043398X0200Y    R270 S0      
327GND              PU72  -2          A01X+042918Y+043420X0100Y0320R090 S1      
317GND              VIA   -    MD0100PA00X+043075Y+036781X0200Y         S0      
317GND              VIA   -    MD0100PA00X+043570Y+036781X0200Y         S0      
317GND              VIA   -    MD0100PA00X+043044Y+035812X0200Y         S0      
317GND              VIA   -    MD0100PA00X+043579Y+034574X0200Y         S0      
317GND              VIA   -    MD0100PA00X+042850Y+034578X0200Y         S0      
317GND              VIA   -    MD0100PA00X+043579Y+033126X0200Y         S0      
317GND              VIA   -    MD0100PA00X+042846Y+033126X0200Y         S0      
327GND              U115  -49  M      A01X+042850Y+033850X1660Y1660     S1      
317GND              VIA   -    MD0100PA00X+042783Y+030997X0200Y         S0      
317GND              VIA   -    MD0100PA00X+043075Y+030697X0200Y         S0      
317GND              VIA   -    MD0100PA00X+043570Y+030697X0200Y         S0      
317GND              VIA   -    MD0100PA00X+044063Y+015237X0200Y         S0      
327GND              Q220  -1          A01X+043764Y+015237X0240Y0240R270 S1      
317GND              VIA   -    MD0100PA00X+044173Y+014646X0200Y         S0      
327GND              Q220  -4          A01X+044473Y+014646X0240Y0240R270 S1      
317GND              VIA   -    MD0100PA00X+042806Y+000300X0200Y    R270 S0      
317GND              VIA   -    MD0100PA00X+041875Y+046861X0200Y         S0      
327GND              Q213  -4          A01X+041584Y+046861X0240Y0240R270 S1      
317GND              VIA   -    MD0100PA00X+047039Y+038955X0200Y         S0      
317GND              VIA   -    MD0100PA00X+046638Y+036636X0200Y         S0      
317GND              VIA   -    MD0100PA00X+046145Y+035258X0200Y         S0      
317GND              VIA   -    MD0100PA00X+046145Y+034763X0200Y         S0      
317GND              VIA   -    MD0100PA00X+046145Y+033188X0200Y         S0      
317GND              VIA   -    MD0100PA00X+046145Y+033684X0200Y         S0      
317GND              VIA   -    MD0100PA00X+046405Y+025237X0200Y         S0      
327GND              PR7067-2          A01X+046683Y+025237X0198Y0197R180 S1      
317GND              VIA   -    M      A01X+047223Y+020168X0200Y    R090 S2      
017GND              VIA   -    M      A18X+047223Y+020168X0260Y    R090 S2      
017GND                    -    MD0100PA00X+047223Y+020168                       
317GND              VIA   -    MD0100PA00X+046997Y+020339X0200Y    R180 S0      
317GND              VIA   -    MD0100PA00X+046747Y+020339X0200Y    R180 S0      
317GND              VIA   -    MD0100PA00X+047366Y+020684X0200Y    R180 S0      
317GND              VIA   -    M      A01X+047541Y+019518X0200Y    R180 S2      
017GND              VIA   -    M      A18X+047541Y+019518X0260Y    R180 S2      
017GND                    -    MD0100PA00X+047541Y+019518                       
317GND              VIA   -    MD0100PA00X+047223Y+019888X0200Y    R090 S0      
317GND              VIA   -    MD0100PA00X+047261Y+019518X0200Y    R180 S0      
317GND              VIA   -    MD0100PA00X+046761Y+019518X0200Y    R180 S0      
317GND              VIA   -    MD0100PA00X+047011Y+019518X0200Y    R180 S0      
317GND              VIA   -    MD0100PA00X+046648Y+013458X0200Y         S0      
327GND              U387  -3          A01X+046337Y+013674X0240Y0240     S1      
317GND              VIA   -    MD0100PA00X+046433Y+013330X0200Y         S0      
327GND              PC925 -2          A01X+046433Y+013090X0198Y0197R090 S1      
317GND              VIA   -    MD0100PA00X+047233Y+013330X0200Y         S0      
327GND              PC920 -2          A01X+047233Y+013090X0198Y0197R090 S1      
317GND              VIA   -    MD0100PA00X+046631Y+010225X0200Y    R180 S0      
327GND              PR7108-2   M      A01X+046631Y+010475X0198Y0197R270 S1      
317GND              VIA   -    MD0100PA00X+047031Y+010225X0200Y    R180 S0      
327GND              PR7107-2   M      A01X+047031Y+010475X0198Y0197R270 S1      
317GND              VIA   -    MD0100PA00X+046209Y+011339X0200Y         S0      
317GND              VIA   -    MD0100PA00X+046474Y+011078X0200Y         S0      
327GND              PU123 -3   M      A01X+046607Y+011368X0100Y0280     S1      
317GND              VIA   -    M      A01X+047431Y+010225X0200Y    R180 S2      
017GND              VIA   -    M      A18X+047431Y+010225X0260Y    R180 S2      
017GND                    -    MD0100PA00X+047431Y+010225                       
317GND              VIA   -    MD0100PA00X+046806Y+000300X0200Y    R270 S0      
317GND              VIA   -    MD0100PA00X+044618Y+044710X0200Y    R180 S0      
327GND              PC613 -2   M      A01X+044375Y+044710X0198Y0197     S1      
317GND              VIA   -    MD0100PA00X+044809Y+037577X0200Y         S0      
317GND              VIA   -    MD0100PA00X+045346Y+037069X0200Y         S0      
317GND              VIA   -    MD0100PA00X+048505Y+023869X0200Y    R090 S0      
327GND              PR258 -2          A01X+048505Y+023611X0198Y0197R090 S1      
317GND              VIA   -    MD0100PA00X+047565Y+023859X0200Y    R090 S0      
327GND              C2886 -2          A01X+047565Y+023601X0198Y0197R090 S1      
317GND              VIA   -    MD0100PA00X+047862Y+023612X0200Y    R090 S0      
327GND              PC540 -2          A01X+048118Y+023612X0198Y0197R090 S1      
317GND              VIA   -    MD0100PA00X+048583Y+024729X0200Y         S0      
327GND              Q200  -4          A01X+048264Y+024729X0240Y0240R270 S1      
317GND              VIA   -    MD0100PA00X+049161Y+021354X0200Y    R090 S0      
317GND              VIA   -    MD0100PA00X+047616Y+020684X0200Y    R180 S0      
317GND              VIA   -    MD0100PA00X+048386Y+015085X0200Y         S0      
327GND              U367  -S          A01X+047991Y+015330X0400Y0560     S1      
317GND              VIA   -    MD0100PA00X+048788Y+013776X0200Y         S0      
317GND              VIA   -    MD0100PA00X+048308Y+013776X0200Y         S0      
317GND              VIA   -    MD0100PA00X+048097Y+014123X0200Y         S0      
327GND              R5671 -2          A01X+047950Y+013884X0198Y0197     S1      
317GND              VIA   -    MD0100PA00X+047906Y+014601X0200Y         S0      
327GND              C3663 -2          A01X+047656Y+014601X0198Y0197R090 S1      
317GND              VIA   -    MD0100PA00X+048308Y+012358X0200Y         S0      
317GND              VIA   -    MD0100PA00X+049038Y+013067X0200Y         S0      
317GND              VIA   -    MD0100PA00X+049038Y+012358X0200Y         S0      
317GND              VIA   -    MD0100PA00X+048788Y+013067X0200Y         S0      
317GND              VIA   -    MD0100PA00X+048788Y+012358X0200Y         S0      
317GND              VIA   -    MD0100PA00X+048308Y+013067X0200Y         S0      
317GND              VIA   -    MD0100PA00X+049038Y+011650X0200Y         S0      
317GND              VIA   -    MD0100PA00X+049038Y+010941X0200Y         S0      
317GND              VIA   -    MD0100PA00X+048788Y+011650X0200Y         S0      
317GND              VIA   -    MD0100PA00X+048308Y+011650X0200Y         S0      
317GND              VIA   -    MD0100PA00X+047933Y+010650X0200Y         S0      
327GND              C2767 -2   M      A01X+048193Y+010650X0198Y0197R180 S1      
317GND              VIA   -    MD0100PA00X+047732Y+010917X0200Y         S0      
317GND              VIA   -    MD0100PA00X+048032Y+010917X0200Y         S0      
317GND              VIA   -    MD0100PA00X+048540Y+004477X0200Y    R270 S0      
317GND              VIA   -    MD0100PA00X+048540Y+002477X0200Y    R270 S0      
317GND              VIA   -    MD0100PA00X+048404Y+000447X0200Y    R270 S0      
317GND              VIA   -    MD0100PA00X+051272Y+005360X0200Y    R270 S0      
317GND              VIA   -    MD0100PA00X+049778Y+044847X0200Y         S0      
327GND              Q214  -4          A01X+049778Y+045138X0240Y0240R180 S1      
317GND              VIA   -    MD0100PA00X+050368Y+045547X0200Y         S0      
327GND              Q214  -1          A01X+050368Y+045846X0240Y0240R180 S1      
317GND              VIA   -    MD0100PA00X+049348Y+043990X0200Y    R180 S0      
327GND              R5829 -2          A01X+049348Y+043749X0198Y0197R090 S1      
317GND              VIA   -    MD0100PA00X+049742Y+035456X0200Y         S0      
327GND              U124  -12         A01X+050182Y+035666X0120Y0630R270 S1      
317GND              VIA   -    MD0100PA00X+049329Y+023871X0200Y    R090 S0      
327GND              PC507 -2          A01X+049329Y+023613X0198Y0197R090 S1      
317GND              VIA   -    MD0100PA00X+049508Y+013776X0200Y         S0      
317GND              VIA   -    MD0100PA00X+050455Y+013776X0200Y    R180 S0      
317GND              VIA   -    MD0100PA00X+050455Y+013067X0200Y    R180 S0      
317GND              VIA   -    MD0100PA00X+050665Y+012165X0200Y    R180 S0      
317GND              VIA   -    MD0100PA00X+049508Y+012358X0200Y         S0      
317GND              VIA   -    MD0100PA00X+049508Y+013067X0200Y         S0      
317GND              VIA   -    MD0100PA00X+049508Y+010941X0200Y         S0      
317GND              VIA   -    MD0100PA00X+049508Y+010232X0200Y         S0      
317GND              VIA   -    MD0100PA00X+049508Y+011650X0200Y         S0      
317GND              VIA   -    MD0100PA00X+050333Y+011650X0200Y    R180 S0      
317GND              VIA   -    MD0100PA00X+050333Y+010941X0200Y    R180 S0      
317GND              VIA   -    MD0100PA00X+050308Y+010232X0200Y    R180 S0      
317GND              VIA   -    MD0100PA00X+050354Y+008558X0200Y         S0      
317GND              VIA   -    MD0100PA00X+050609Y+009285X0200Y         S0      
317GND              VIA   -    MD0100PA00X+050354Y+008298X0200Y         S0      
317GND              VIA   -    MD0100PA00X+050354Y+008038X0200Y         S0      
317GND              VIA   -    MD0100PA00X+050354Y+007518X0200Y         S0      
317GND              VIA   -    MD0100PA00X+050354Y+007778X0200Y         S0      
317GND              VIA   -    MD0100PA00X+049272Y+005360X0200Y    R270 S0      
317GND              VIA   -    MD0100PA00X+048248Y+044452X0200Y         S0      
317GND              VIA   -    MD0100PA00X+048253Y+041846X0200Y         S0      
327GND              Q126  -4          A01X+048253Y+042137X0240Y0240R180 S1      
317GND              VIA   -    MD0100PA00X+048844Y+042546X0200Y         S0      
327GND              Q126  -1          A01X+048844Y+042846X0240Y0240R180 S1      
317GND              VIA   -    MD0100PA00X+048172Y+038709X0200Y         S0      
327GND              R1567 -2          A01X+048534Y+038709X0198Y0197R180 S1      
317GND              VIA   -    MD0100PA00X+048172Y+039159X0200Y         S0      
327GND              R1566 -2          A01X+048534Y+039159X0198Y0197R180 S1      
317GND              VIA   -    MD0100PA00X+048354Y+038031X0200Y         S0      
317GND              VIA   -    MD0100PA00X+048374Y+037127X0200Y         S0      
317GND              VIA   -    MD0100PA00X+048358Y+037584X0200Y         S0      
317GND              VIA   -    MD0100PA00X+048324Y+036648X0200Y         S0      
317GND              VIA   -    MD0100PA00X+047854Y+025320X0200Y         S0      
327GND              Q200  -1          A01X+047555Y+025320X0240Y0240R270 S1      
317GND              VIA   -    MD0100PA00X+053047Y+009402X0200Y         S0      
317GND              VIA   -    MD0100PA00X+053848Y+009402X0200Y         S0      
317GND              VIA   -    MD0100PA00X+053447Y+009402X0200Y         S0      
317GND              VIA   -    MD0100PA00X+053083Y+004477X0200Y    R270 S0      
317GND              VIA   -    MD0100PA00X+053083Y+002477X0200Y    R270 S0      
317GND              VIA   -    MD0100PA00X+053152Y+000537X0200Y    R270 S0      
317GND              VIA   -    MD0100PA00X+051331Y+047004X0200Y    R180 S0      
327GND              PC796 -2          A01X+051331Y+046763X0198Y0197R090 S1      
317GND              VIA   -    MD0100PA00X+052131Y+047004X0200Y    R180 S0      
327GND              PC790 -2          A01X+052131Y+046763X0198Y0197R090 S1      
317GND              VIA   -    MD0100PA00X+050873Y+046990X0200Y    R180 S0      
327GND              R5964 -2          A01X+050873Y+046749X0198Y0197R090 S1      
317GND              VIA   -    MD0100PA00X+052358Y+044720X0200Y         S0      
317GND              VIA   -    MD0100PA00X+052370Y+044427X0200Y         S0      
317GND              VIA   -    MD0100PA00X+051002Y+044635X0200Y         S0      
327GND              PC788 -2          A01X+051002Y+044876X0198Y0197R270 S1      
317GND              VIA   -    MD0100PA00X+051461Y+044587X0200Y         S0      
327GND              PU101 -3          A01X+051627Y+044856X0100Y0280     S1      
317GND              VIA   -    MD0100PA00X+051284Y+043451X0200Y         S0      
327GND              PR7013-2          A01X+051284Y+043692X0198Y0197R270 S1      
317GND              VIA   -    MD0100PA00X+051684Y+043451X0200Y         S0      
327GND              PR7011-2          A01X+051684Y+043692X0198Y0197R270 S1      
317GND              VIA   -    MD0100PA00X+052084Y+043451X0200Y         S0      
327GND              PC794 -2          A01X+052084Y+043692X0198Y0197R270 S1      
317GND              VIA   -    MD0100PA00X+051134Y+031112X0200Y         S0      
317GND              VIA   -    MD0100PA00X+052338Y+028819X0200Y         S0      
317GND              VIA   -    MD0100PA00X+052338Y+028569X0200Y         S0      
317GND              VIA   -    MD0100PA00X+051537Y+029380X0200Y         S0      
317GND              VIA   -    MD0100PA00X+051787Y+029380X0200Y         S0      
317GND              VIA   -    MD0100PA00X+051182Y+022623X0200Y    R090 S0      
317GND              VIA   -    MD0100PA00X+051182Y+022373X0200Y    R090 S0      
317GND              VIA   -    MD0100PA00X+051182Y+022873X0200Y    R090 S0      
317GND              VIA   -    MD0100PA00X+051182Y+023123X0200Y    R090 S0      
317GND              VIA   -    MD0100PA00X+052228Y+023146X0200Y    R090 S0      
317GND              VIA   -    MD0100PA00X+052228Y+022896X0200Y    R090 S0      
317GND              VIA   -    MD0100PA00X+052228Y+022646X0200Y    R090 S0      
317GND              VIA   -    M      A01X+052228Y+022366X0200Y    R090 S2      
017GND              VIA   -    M      A18X+052228Y+022366X0260Y    R090 S2      
017GND                    -    MD0100PA00X+052228Y+022366                       
317GND              VIA   -    MD0100PA00X+052118Y+013776X0200Y    R180 S0      
317GND              VIA   -    MD0100PA00X+050925Y+013776X0200Y         S0      
317GND              VIA   -    MD0100PA00X+052118Y+012358X0200Y    R180 S0      
317GND              VIA   -    MD0100PA00X+052118Y+013067X0200Y    R180 S0      
317GND              VIA   -    MD0100PA00X+051318Y+012358X0200Y         S0      
317GND              VIA   -    MD0100PA00X+051318Y+013067X0200Y         S0      
317GND              VIA   -    MD0100PA00X+052118Y+010232X0200Y    R180 S0      
317GND              VIA   -    MD0100PA00X+052118Y+010941X0200Y    R180 S0      
317GND              VIA   -    MD0100PA00X+052118Y+011650X0200Y    R180 S0      
317GND              VIA   -    MD0100PA00X+051318Y+010941X0200Y         S0      
317GND              VIA   -    MD0100PA00X+051318Y+011650X0200Y         S0      
317GND              VIA   -    MD0100PA00X+051305Y+010304X0200Y         S0      
317GND              VIA   -    M      A01X+054091Y+029076X0200Y         S2      
017GND              VIA   -    M      A18X+054091Y+029076X0260Y         S2      
017GND                    -    MD0100PA00X+054091Y+029076                       
317GND              VIA   -    MD0100PA00X+053691Y+029076X0200Y         S0      
327GND              PR7063-2          A01X+053691Y+028806X0198Y0197R090 S1      
317GND              VIA   -    MD0100PA00X+053291Y+029076X0200Y         S0      
327GND              PC845 -2          A01X+053291Y+028806X0198Y0197R090 S1      
317GND              VIA   -    MD0100PA00X+052868Y+028819X0200Y         S0      
317GND              VIA   -    MD0100PA00X+052588Y+028819X0200Y         S0      
317GND              VIA   -    MD0100PA00X+052868Y+028569X0200Y         S0      
317GND              VIA   -    MD0100PA00X+052588Y+028569X0200Y         S0      
317GND              VIA   -    MD0100PA00X+052593Y+024889X0200Y    R180 S0      
317GND              VIA   -    MD0100PA00X+053385Y+025654X0200Y         S0      
327GND              PC840 -2          A01X+053385Y+025954X0198Y0197R270 S1      
317GND              VIA   -    MD0100PA00X+053093Y+024889X0200Y    R180 S0      
317GND              VIA   -    MD0100PA00X+052843Y+024889X0200Y    R180 S0      
317GND              VIA   -    MD0100PA00X+053024Y+023179X0200Y    R090 S0      
317GND              VIA   -    MD0100PA00X+052873Y+023661X0200Y    R180 S0      
317GND              VIA   -    MD0100PA00X+053123Y+023661X0200Y    R180 S0      
317GND              VIA   -    MD0100PA00X+052623Y+023661X0200Y    R180 S0      
317GND              VIA   -    MD0100PA00X+053394Y+022471X0200Y    R090 S0      
317GND              VIA   -    MD0100PA00X+053394Y+022221X0200Y    R090 S0      
317GND              VIA   -    MD0100PA00X+052598Y+022614X0200Y         S0      
317GND              VIA   -    M      A01X+052878Y+022614X0200Y         S2      
017GND              VIA   -    M      A18X+052878Y+022614X0260Y         S2      
017GND                    -    MD0100PA00X+052878Y+022614                       
317GND              VIA   -    MD0100PA00X+053024Y+022929X0200Y    R090 S0      
317GND              VIA   -    M      A01X+053203Y+018873X0200Y         S2      
017GND              VIA   -    M      A18X+053203Y+018873X0260Y         S2      
017GND                    -    MD0100PA00X+053203Y+018873                       
327GND              C310  -2          A01X+053502Y+018740X0198Y0197R090 S1      
317GND              VIA   -    MD0100PA00X+053216Y+019194X0200Y         S0      
327GND              C315  -2          A01X+053494Y+019194X0198Y0197R180 S1      
317GND              VIA   -    MD0100PA00X+053866Y+018462X0200Y         S0      
327GND              U59   -10         A01X+054152Y+018383X0090Y0240R090 S1      
317GND              VIA   -    MD0100PA00X+052851Y+015154X0200Y         S0      
327GND              R6065 -2          A01X+053129Y+015154X0198Y0197R180 S1      
317GND              VIA   -    MD0100PA00X+053559Y+012957X0200Y         S0      
317GND              VIA   -    MD0100PA00X+053559Y+012462X0200Y         S0      
317GND              VIA   -    MD0100PA00X+053060Y+012957X0200Y         S0      
317GND              VIA   -    MD0100PA00X+053060Y+012462X0200Y         S0      
317GND              VIA   -    MD0100PA00X+053775Y+010378X0200Y    R270 S0      
327GND              R423  -1          A01X+053775Y+010135X0198Y0197R270 S1      
317GND              VIA   -    MD0100PA00X+053060Y+011044X0200Y         S0      
317GND              VIA   -    MD0100PA00X+053559Y+011540X0200Y         S0      
317GND              VIA   -    MD0100PA00X+053559Y+011044X0200Y         S0      
317GND              VIA   -    MD0100PA00X+053060Y+011540X0200Y         S0      
317GND              VIA   -    MD0100PA00X+053020Y+010170X0200Y    R090 S0      
317GND              VIA   -    MD0100PA00X+052647Y+009402X0200Y         S0      
317GND              VIA   -    MD0100PA00X+055148Y+029364X0200Y    R090 S0      
317GND              VIA   -    MD0100PA00X+054898Y+029364X0200Y    R090 S0      
317GND              VIA   -    M      A01X+054699Y+028131X0200Y         S2      
017GND              VIA   -    M      A18X+054699Y+028131X0260Y         S2      
017GND                    -    MD0100PA00X+054699Y+028131                       
317GND              VIA   -    MD0100PA00X+054288Y+027921X0200Y         S0      
317GND              VIA   -    MD0100PA00X+054185Y+025654X0200Y         S0      
327GND              PC846 -2          A01X+054185Y+025954X0198Y0197R270 S1      
317GND              VIA   -    MD0100PA00X+054064Y+020676X0200Y         S0      
317GND              VIA   -    MD0100PA00X+054469Y+018516X0200Y         S0      
317GND              VIA   -    MD0100PA00X+054933Y+018512X0200Y         S0      
317GND              VIA   -    MD0100PA00X+055310Y+019242X0200Y         S0      
317GND              VIA   -    MD0100PA00X+054469Y+018057X0200Y         S0      
317GND              VIA   -    MD0100PA00X+054937Y+018053X0200Y         S0      
327GND              U59   -TH  M      A01X+054703Y+018285X0670Y0670R180 S1      
317GND              VIA   -    MD0100PA00X+054299Y+015237X0200Y         S0      
327GND              Q221  -1          A01X+054000Y+015237X0240Y0240R270 S1      
317GND              VIA   -    MD0100PA00X+054100Y+013669X0200Y         S0      
317GND              VIA   -    MD0100PA00X+054599Y+013669X0200Y         S0      
317GND              VIA   -    MD0100PA00X+054409Y+014646X0200Y         S0      
327GND              Q221  -4          A01X+054709Y+014646X0240Y0240R270 S1      
317GND              VIA   -    MD0100PA00X+054100Y+013173X0200Y         S0      
317GND              VIA   -    MD0100PA00X+054100Y+012251X0200Y         S0      
317GND              VIA   -    MD0100PA00X+054599Y+013173X0200Y         S0      
317GND              VIA   -    MD0100PA00X+054599Y+012251X0200Y         S0      
317GND              VIA   -    MD0100PA00X+054891Y+010362X0200Y    R090 S0      
327GND              U402  -S          A01X+054891Y+010792X0400Y0560R180 S1      
317GND              VIA   -    MD0100PA00X+054599Y+011756X0200Y         S0      
317GND              VIA   -    MD0100PA00X+054100Y+011756X0200Y         S0      
317GND              VIA   -    MD0100PA00X+054354Y+007614X0200Y         S0      
317GND              VIA   -    MD0100PA00X+054354Y+008014X0200Y         S0      
317GND              VIA   -    MD0100PA00X+054354Y+008414X0200Y         S0      
317GND              VIA   -    MD0100PA00X+055042Y+000300X0200Y    R270 S0      
317GND              VIA   -    MD0100PA00X+053514Y+039755X0200Y         S0      
327GND              C2709 -2          A01X+053514Y+039431X0198Y0197     S1      
317GND              VIA   -    MD0100PA00X+056642Y+025237X0200Y         S0      
327GND              PR7068-2          A01X+056919Y+025237X0198Y0197R180 S1      
317GND              VIA   -    MD0100PA00X+056466Y+021686X0200Y         S0      
327GND              PC313 -2          A01X+056208Y+021686X0198Y0197     S1      
317GND              VIA   -    MD0100PA00X+056466Y+022186X0200Y         S0      
327GND              C2862 -2   M      A01X+056208Y+022186X0198Y0197     S1      
317GND              VIA   -    MD0100PA00X+056983Y+020339X0200Y         S0      
317GND              VIA   -    MD0100PA00X+056466Y+020086X0200Y         S0      
317GND              VIA   -    MD0100PA00X+056466Y+021286X0200Y         S0      
317GND              VIA   -    M      A01X+057459Y+020168X0200Y    R090 S2      
017GND              VIA   -    M      A18X+057459Y+020168X0260Y    R090 S2      
017GND                    -    MD0100PA00X+057459Y+020168                       
317GND              VIA   -    MD0100PA00X+057233Y+020339X0200Y    R180 S0      
317GND              VIA   -    MD0100PA00X+057247Y+019518X0200Y    R180 S0      
317GND              VIA   -    MD0100PA00X+056997Y+019518X0200Y         S0      
317GND              VIA   -    MD0100PA00X+056463Y+017266X0200Y         S0      
327GND              R553  -2          A01X+056198Y+017266X0198Y0197     S1      
317GND              VIA   -    MD0100PA00X+056463Y+018066X0200Y         S0      
327GND              R554  -2          A01X+056198Y+018066X0198Y0197     S1      
317GND              VIA   -    MD0100PA00X+056884Y+013458X0200Y         S0      
327GND              U386  -3          A01X+056573Y+013674X0240Y0240     S1      
317GND              VIA   -    MD0100PA00X+056729Y+013090X0200Y         S0      
327GND              PC927 -2          A01X+056469Y+013090X0198Y0197R090 S1      
317GND              VIA   -    MD0100PA00X+056867Y+010225X0200Y    R180 S0      
327GND              PR7110-2   M      A01X+056867Y+010475X0198Y0197R270 S1      
317GND              VIA   -    MD0100PA00X+057267Y+010225X0200Y    R180 S0      
317GND              VIA   -    MD0100PA00X+056445Y+011339X0200Y         S0      
317GND              VIA   -    MD0100PA00X+056710Y+011078X0200Y         S0      
327GND              PU124 -3   M      A01X+056844Y+011368X0100Y0280     S1      
317GND              VIA   -    MD0100PA00X+055692Y+011726X0200Y         S0      
327GND              R6202 -1          A01X+055734Y+011449X0198Y0197R180 S1      
317GND              VIA   -    MD0100PA00X+055832Y+009195X0200Y         S0      
327GND              C2719 -1          A01X+055576Y+009195X0198Y0197R270 S1      
317GND              VIA   -    MD0100PA00X+056322Y+009681X0200Y         S0      
317GND              VIA   -    MD0100PA00X+056112Y+005551X0200Y         S0      
327GND              C2720 -1          A01X+056112Y+005801X0198Y0197R180 S1      
317GND              VIA   -    MD0100PA00X+056629Y+006092X0200Y         S0      
327GND              U130  -4          A01X+056599Y+006472X0240Y0460R180 S1      
317GND              VIA   -    MD0100PA00X+057042Y+000300X0200Y    R270 S0      
317GND              VIA   -    MD0100PA00X+055290Y+043083X0200Y         S0      
327GND              C4000 -2          A01X+058432Y+044551X0198Y0197R270 S1      
317GND              VIA   -    MD0100PA00X+054171Y+038172X0200Y         S0      
327GND              R1568 -2          A01X+053876Y+038172X0198Y0197     S1      
317GND              VIA   -    MD0100PA00X+055373Y+038849X0200Y         S0      
317GND              VIA   -    MD0100PA00X+054164Y+038905X0200Y         S0      
317GND              VIA   -    MD0100PA00X+054898Y+029084X0200Y    R090 S0      
317GND              VIA   -    MD0100PA00X+054898Y+028834X0200Y    R090 S0      
317GND              VIA   -    MD0100PA00X+055148Y+029084X0200Y    R090 S0      
317GND              VIA   -    MD0100PA00X+055148Y+028834X0200Y    R090 S0      
317GND              VIA   -    MD0100PA00X+058149Y+033668X0200Y         S0      
317GND              VIA   -    MD0100PA00X+058090Y+025320X0200Y         S0      
327GND              Q201  -1          A01X+057791Y+025320X0240Y0240R270 S1      
317GND              VIA   -    MD0100PA00X+057801Y+023859X0200Y    R090 S0      
327GND              C2888 -2          A01X+057801Y+023601X0198Y0197R090 S1      
317GND              VIA   -    MD0100PA00X+058098Y+023612X0200Y    R090 S0      
327GND              PC505 -2          A01X+058354Y+023612X0198Y0197R090 S1      
317GND              VIA   -    MD0100PA00X+058819Y+024729X0200Y         S0      
327GND              Q201  -4          A01X+058500Y+024729X0240Y0240R270 S1      
317GND              VIA   -    MD0100PA00X+058742Y+023869X0200Y    R090 S0      
327GND              PR262 -2          A01X+058742Y+023611X0198Y0197R090 S1      
317GND              VIA   -    MD0100PA00X+057602Y+020684X0200Y    R180 S0      
317GND              VIA   -    MD0100PA00X+057852Y+020684X0200Y    R180 S0      
317GND              VIA   -    MD0100PA00X+057459Y+019888X0200Y    R090 S0      
317GND              VIA   -    M      A01X+057777Y+019518X0200Y    R180 S2      
017GND              VIA   -    M      A18X+057777Y+019518X0260Y    R180 S2      
017GND                    -    MD0100PA00X+057777Y+019518                       
317GND              VIA   -    MD0100PA00X+057497Y+019518X0200Y    R180 S0      
317GND              VIA   -    MD0100PA00X+058622Y+015085X0200Y         S0      
327GND              U368  -S          A01X+058228Y+015330X0400Y0560     S1      
317GND              VIA   -    MD0100PA00X+058544Y+013776X0200Y         S0      
317GND              VIA   -    MD0100PA00X+058333Y+014123X0200Y         S0      
327GND              R5668 -2          A01X+058187Y+013884X0198Y0197     S1      
317GND              VIA   -    MD0100PA00X+058143Y+014601X0200Y         S0      
327GND              C3662 -2          A01X+057893Y+014601X0198Y0197R090 S1      
317GND              VIA   -    MD0100PA00X+058544Y+013067X0200Y         S0      
317GND              VIA   -    MD0100PA00X+058544Y+012358X0200Y         S0      
317GND              VIA   -    MD0100PA00X+057469Y+013330X0200Y         S0      
327GND              PC922 -2          A01X+057469Y+013090X0198Y0197R090 S1      
317GND              VIA   -    MD0100PA00X+058544Y+011650X0200Y         S0      
317GND              VIA   -    MD0100PA00X+058169Y+010650X0200Y         S0      
327GND              C2768 -2   M      A01X+058429Y+010650X0198Y0197R180 S1      
317GND              VIA   -    MD0100PA00X+057969Y+010917X0200Y         S0      
317GND              VIA   -    MD0100PA00X+058269Y+010917X0200Y         S0      
317GND              VIA   -    M      A01X+057667Y+010225X0200Y    R180 S2      
017GND              VIA   -    M      A18X+057667Y+010225X0260Y    R180 S2      
017GND                    -    MD0100PA00X+057667Y+010225                       
317GND              VIA   -    MD0100PA00X+058777Y+004477X0200Y    R270 S0      
317GND              VIA   -    MD0100PA00X+058777Y+002477X0200Y    R270 S0      
317GND              VIA   -    MD0100PA00X+058640Y+000447X0200Y    R270 S0      
317GND              VIA   -    MD0100PA00X+057063Y+037545X0200Y         S0      
317GND              VIA   -    MD0100PA00X+059787Y+041151X0200Y    R090 S0      
317GND              VIA   -    MD0100PA00X+059787Y+041646X0200Y    R090 S0      
317GND              VIA   -    MD0100PA00X+059288Y+042568X0200Y    R270 S0      
317GND              VIA   -    MD0100PA00X+059787Y+042568X0200Y    R090 S0      
317GND              VIA   -    MD0100PA00X+060328Y+042352X0200Y    R270 S0      
317GND              VIA   -    MD0100PA00X+059528Y+039734X0200Y    R270 S0      
317GND              VIA   -    MD0100PA00X+060027Y+040229X0200Y    R090 S0      
317GND              VIA   -    MD0100PA00X+059528Y+040229X0200Y    R270 S0      
317GND              VIA   -    MD0100PA00X+060328Y+040935X0200Y    R270 S0      
317GND              VIA   -    MD0100PA00X+060328Y+040440X0200Y    R270 S0      
317GND              VIA   -    MD0100PA00X+060328Y+039518X0200Y    R270 S0      
317GND              VIA   -    MD0100PA00X+060027Y+039734X0200Y    R090 S0      
317GND              VIA   -    MD0100PA00X+060328Y+039022X0200Y    R270 S0      
317GND              VIA   -    MD0100PA00X+059018Y+030976X0200Y         S0      
317GND              VIA   -    MD0100PA00X+059565Y+023871X0200Y    R090 S0      
327GND              PC519 -2          A01X+059565Y+023613X0198Y0197R090 S1      
317GND              VIA   -    MD0100PA00X+059397Y+021354X0200Y    R090 S0      
317GND              VIA   -    MD0100PA00X+059024Y+013776X0200Y         S0      
317GND              VIA   -    MD0100PA00X+059744Y+013776X0200Y         S0      
317GND              VIA   -    MD0100PA00X+059274Y+013067X0200Y         S0      
317GND              VIA   -    MD0100PA00X+059024Y+013067X0200Y         S0      
317GND              VIA   -    MD0100PA00X+059024Y+012358X0200Y         S0      
317GND              VIA   -    MD0100PA00X+059274Y+012358X0200Y         S0      
317GND              VIA   -    MD0100PA00X+059744Y+013067X0200Y         S0      
317GND              VIA   -    MD0100PA00X+059744Y+012358X0200Y         S0      
317GND              VIA   -    MD0100PA00X+059744Y+011650X0200Y         S0      
317GND              VIA   -    MD0100PA00X+059744Y+010941X0200Y         S0      
317GND              VIA   -    MD0100PA00X+059744Y+010232X0200Y         S0      
317GND              VIA   -    MD0100PA00X+059274Y+011650X0200Y         S0      
317GND              VIA   -    MD0100PA00X+059024Y+011650X0200Y         S0      
317GND              VIA   -    MD0100PA00X+059274Y+010941X0200Y         S0      
317GND              VIA   -    MD0100PA00X+059509Y+005360X0200Y    R270 S0      
317GND              VIA   -    MD0100PA00X+062023Y+029380X0200Y         S0      
317GND              VIA   -    MD0100PA00X+061773Y+029380X0200Y         S0      
317GND              VIA   -    MD0100PA00X+061418Y+022873X0200Y    R090 S0      
317GND              VIA   -    MD0100PA00X+061418Y+023123X0200Y    R090 S0      
317GND              VIA   -    MD0100PA00X+061418Y+022623X0200Y    R090 S0      
317GND              VIA   -    MD0100PA00X+061418Y+022373X0200Y    R090 S0      
317GND              VIA   -    MD0100PA00X+061214Y+013776X0200Y         S0      
317GND              VIA   -    MD0100PA00X+060691Y+013776X0200Y    R180 S0      
317GND              VIA   -    MD0100PA00X+060691Y+013067X0200Y    R180 S0      
317GND              VIA   -    MD0100PA00X+061555Y+012358X0200Y         S0      
317GND              VIA   -    MD0100PA00X+061555Y+013067X0200Y         S0      
317GND              VIA   -    MD0100PA00X+060586Y+012458X0200Y    R180 S0      
317GND              VIA   -    MD0100PA00X+061555Y+010941X0200Y         S0      
317GND              VIA   -    MD0100PA00X+061555Y+011650X0200Y         S0      
317GND              VIA   -    MD0100PA00X+060569Y+011650X0200Y    R180 S0      
317GND              VIA   -    MD0100PA00X+060569Y+010941X0200Y    R180 S0      
317GND              VIA   -    MD0100PA00X+060544Y+010232X0200Y    R180 S0      
317GND              VIA   -    MD0100PA00X+061541Y+010304X0200Y         S0      
317GND              VIA   -    MD0100PA00X+060590Y+008558X0200Y         S0      
317GND              VIA   -    MD0100PA00X+060845Y+009285X0200Y         S0      
317GND              VIA   -    MD0100PA00X+060590Y+007518X0200Y         S0      
317GND              VIA   -    MD0100PA00X+060590Y+007778X0200Y         S0      
317GND              VIA   -    MD0100PA00X+060590Y+008298X0200Y         S0      
317GND              VIA   -    MD0100PA00X+060590Y+008038X0200Y         S0      
317GND              VIA   -    MD0100PA00X+061509Y+005360X0200Y    R270 S0      
317GND              VIA   -    MD0100PA00X+059787Y+046861X0200Y    R090 S0      
317GND              VIA   -    MD0100PA00X+059288Y+046861X0200Y    R270 S0      
317GND              VIA   -    MD0100PA00X+059369Y+045075X0200Y         S0      
327GND              U19   -S          A01X+059766Y+045075X0400Y0560     S1      
317GND              VIA   -    MD0100PA00X+059288Y+044481X0200Y    R270 S0      
317GND              VIA   -    MD0100PA00X+059787Y+044481X0200Y    R090 S0      
317GND              VIA   -    MD0100PA00X+059288Y+043064X0200Y    R270 S0      
317GND              VIA   -    MD0100PA00X+059787Y+043064X0200Y    R090 S0      
317GND              VIA   -    MD0100PA00X+059288Y+043986X0200Y    R270 S0      
317GND              VIA   -    MD0100PA00X+059787Y+043986X0200Y    R090 S0      
317GND              VIA   -    MD0100PA00X+060328Y+043770X0200Y    R270 S0      
317GND              VIA   -    MD0100PA00X+060328Y+043274X0200Y    R270 S0      
317GND              VIA   -    MD0100PA00X+060328Y+041857X0200Y    R270 S0      
317GND              VIA   -    MD0100PA00X+059288Y+041151X0200Y    R270 S0      
317GND              VIA   -    MD0100PA00X+059288Y+041646X0200Y    R270 S0      
317GND              VIA   -    M      A01X+063439Y+018873X0200Y         S2      
017GND              VIA   -    M      A18X+063439Y+018873X0260Y         S2      
017GND                    -    MD0100PA00X+063439Y+018873                       
327GND              C313  -2          A01X+063739Y+018740X0198Y0197R090 S1      
317GND              VIA   -    MD0100PA00X+063452Y+019194X0200Y         S0      
327GND              C309  -2          A01X+063730Y+019194X0198Y0197R180 S1      
317GND              VIA   -    MD0100PA00X+063087Y+015154X0200Y         S0      
327GND              R6076 -2          A01X+063365Y+015154X0198Y0197R180 S1      
317GND              VIA   -    MD0100PA00X+062355Y+013776X0200Y    R180 S0      
317GND              VIA   -    MD0100PA00X+063296Y+012957X0200Y         S0      
317GND              VIA   -    MD0100PA00X+062355Y+013067X0200Y    R180 S0      
317GND              VIA   -    MD0100PA00X+062355Y+012358X0200Y    R180 S0      
317GND              VIA   -    MD0100PA00X+063296Y+012462X0200Y         S0      
317GND              VIA   -    MD0100PA00X+062355Y+010232X0200Y    R180 S0      
317GND              VIA   -    MD0100PA00X+063296Y+011540X0200Y         S0      
317GND              VIA   -    MD0100PA00X+062355Y+011650X0200Y    R180 S0      
317GND              VIA   -    MD0100PA00X+062355Y+010941X0200Y    R180 S0      
317GND              VIA   -    MD0100PA00X+063296Y+011044X0200Y         S0      
317GND              VIA   -    MD0100PA00X+063256Y+010170X0200Y    R090 S0      
317GND              VIA   -    MD0100PA00X+063283Y+009402X0200Y         S0      
317GND              VIA   -    MD0100PA00X+062883Y+009402X0200Y         S0      
317GND              VIA   -    MD0100PA00X+063683Y+009402X0200Y         S0      
317GND              VIA   -    MD0100PA00X+063325Y+004488X0200Y    R270 S0      
317GND              VIA   -    MD0100PA00X+060827Y+043770X0200Y    R090 S0      
317GND              VIA   -    MD0100PA00X+060827Y+043274X0200Y    R090 S0      
317GND              VIA   -    MD0100PA00X+060827Y+042352X0200Y    R090 S0      
317GND              VIA   -    MD0100PA00X+060827Y+041857X0200Y    R090 S0      
317GND              VIA   -    MD0100PA00X+060827Y+040935X0200Y    R090 S0      
317GND              VIA   -    MD0100PA00X+060827Y+040440X0200Y    R090 S0      
317GND              VIA   -    MD0100PA00X+060827Y+039518X0200Y    R090 S0      
317GND              VIA   -    MD0100PA00X+060827Y+039022X0200Y    R090 S0      
317GND              VIA   -    MD0100PA00X+063446Y+046754X0200Y         S0      
317GND              VIA   -    MD0100PA00X+063446Y+044585X0200Y         S0      
317GND              VIA   -    MD0100PA00X+063446Y+043876X0200Y         S0      
317GND              VIA   -    MD0100PA00X+063446Y+043167X0200Y         S0      
317GND              VIA   -    MD0100PA00X+063446Y+042459X0200Y         S0      
317GND              VIA   -    MD0100PA00X+063446Y+041750X0200Y         S0      
317GND              VIA   -    MD0100PA00X+063446Y+041041X0200Y         S0      
317GND              VIA   -    MD0100PA00X+063446Y+040333X0200Y         S0      
317GND              VIA   -    MD0100PA00X+063446Y+039624X0200Y         S0      
317GND              VIA   -    MD0100PA00X+063446Y+038915X0200Y         S0      
317GND              VIA   -    MD0100PA00X+063527Y+029076X0200Y         S0      
327GND              PC842 -2          A01X+063527Y+028806X0198Y0197R090 S1      
317GND              VIA   -    MD0100PA00X+062824Y+028819X0200Y         S0      
317GND              VIA   -    MD0100PA00X+062574Y+028569X0200Y         S0      
317GND              VIA   -    MD0100PA00X+062824Y+028569X0200Y         S0      
317GND              VIA   -    MD0100PA00X+062574Y+028819X0200Y         S0      
317GND              VIA   -    MD0100PA00X+063104Y+028569X0200Y         S0      
317GND              VIA   -    MD0100PA00X+063104Y+028819X0200Y         S0      
317GND              VIA   -    MD0100PA00X+063622Y+025654X0200Y         S0      
327GND              PC843 -2          A01X+063622Y+025954X0198Y0197R270 S1      
317GND              VIA   -    MD0100PA00X+062829Y+024889X0200Y    R180 S0      
317GND              VIA   -    MD0100PA00X+063329Y+024889X0200Y    R180 S0      
317GND              VIA   -    MD0100PA00X+063079Y+024889X0200Y    R180 S0      
317GND              VIA   -    MD0100PA00X+062859Y+023661X0200Y    R180 S0      
317GND              VIA   -    MD0100PA00X+063261Y+023179X0200Y    R090 S0      
317GND              VIA   -    MD0100PA00X+063109Y+023661X0200Y    R180 S0      
317GND              VIA   -    MD0100PA00X+063359Y+023661X0200Y    R180 S0      
317GND              VIA   -    MD0100PA00X+062464Y+022896X0200Y    R090 S0      
317GND              VIA   -    MD0100PA00X+062834Y+022614X0200Y         S0      
317GND              VIA   -    MD0100PA00X+062464Y+022646X0200Y    R090 S0      
317GND              VIA   -    M      A01X+063114Y+022614X0200Y         S2      
017GND              VIA   -    M      A18X+063114Y+022614X0260Y         S2      
017GND                    -    MD0100PA00X+063114Y+022614                       
317GND              VIA   -    M      A01X+062464Y+022366X0200Y    R090 S2      
017GND              VIA   -    M      A18X+062464Y+022366X0260Y    R090 S2      
017GND                    -    MD0100PA00X+062464Y+022366                       
317GND              VIA   -    MD0100PA00X+063261Y+022929X0200Y    R090 S0      
317GND              VIA   -    MD0100PA00X+063630Y+022471X0200Y    R090 S0      
317GND              VIA   -    MD0100PA00X+063630Y+022221X0200Y    R090 S0      
317GND              VIA   -    MD0100PA00X+062464Y+023146X0200Y    R090 S0      
317GND              VIA   -    MD0100PA00X+064300Y+020676X0200Y         S0      
317GND              VIA   -    MD0100PA00X+064102Y+018462X0200Y         S0      
327GND              U60   -10         A01X+064388Y+018383X0090Y0240R090 S1      
317GND              VIA   -    MD0100PA00X+064705Y+018516X0200Y         S0      
317GND              VIA   -    MD0100PA00X+065169Y+018512X0200Y         S0      
317GND              VIA   -    MD0100PA00X+065174Y+018053X0200Y         S0      
317GND              VIA   -    MD0100PA00X+064705Y+018057X0200Y         S0      
327GND              U60   -TH  M      A01X+064939Y+018285X0670Y0670R180 S1      
317GND              VIA   -    MD0100PA00X+064535Y+015237X0200Y         S0      
327GND              Q222  -1          A01X+064237Y+015237X0240Y0240R270 S1      
317GND              VIA   -    MD0100PA00X+064835Y+013669X0200Y         S0      
317GND              VIA   -    MD0100PA00X+064336Y+013669X0200Y         S0      
317GND              VIA   -    MD0100PA00X+064645Y+014646X0200Y         S0      
327GND              Q222  -4          A01X+064945Y+014646X0240Y0240R270 S1      
317GND              VIA   -    MD0100PA00X+064835Y+013173X0200Y         S0      
317GND              VIA   -    MD0100PA00X+064835Y+012251X0200Y         S0      
317GND              VIA   -    MD0100PA00X+063795Y+012957X0200Y         S0      
317GND              VIA   -    MD0100PA00X+063795Y+012462X0200Y         S0      
317GND              VIA   -    MD0100PA00X+064336Y+013173X0200Y         S0      
317GND              VIA   -    MD0100PA00X+064336Y+012251X0200Y         S0      
317GND              VIA   -    MD0100PA00X+064011Y+010378X0200Y    R270 S0      
327GND              R425  -1          A01X+064011Y+010135X0198Y0197R270 S1      
317GND              VIA   -    MD0100PA00X+065128Y+010362X0200Y    R090 S0      
327GND              U403  -S          A01X+065128Y+010792X0400Y0560R180 S1      
317GND              VIA   -    MD0100PA00X+064835Y+011756X0200Y         S0      
317GND              VIA   -    MD0100PA00X+063795Y+011540X0200Y         S0      
317GND              VIA   -    MD0100PA00X+063795Y+011044X0200Y         S0      
317GND              VIA   -    MD0100PA00X+064336Y+011756X0200Y         S0      
317GND              VIA   -    MD0100PA00X+064084Y+009402X0200Y         S0      
317GND              VIA   -    MD0100PA00X+064591Y+008014X0200Y         S0      
317GND              VIA   -    MD0100PA00X+064591Y+008414X0200Y         S0      
317GND              VIA   -    MD0100PA00X+064591Y+007614X0200Y         S0      
317GND              VIA   -    MD0100PA00X+065257Y+046754X0200Y         S0      
317GND              VIA   -    MD0100PA00X+064226Y+046754X0200Y    R180 S0      
317GND              VIA   -    MD0100PA00X+064399Y+044585X0200Y    R180 S0      
317GND              VIA   -    MD0100PA00X+065340Y+044795X0200Y         S0      
317GND              VIA   -    MD0100PA00X+065136Y+043645X0200Y         S0      
317GND              VIA   -    MD0100PA00X+065176Y+042983X0200Y         S0      
317GND              VIA   -    MD0100PA00X+064368Y+042630X0200Y    R180 S0      
317GND              VIA   -    MD0100PA00X+065169Y+042286X0200Y         S0      
317GND              VIA   -    MD0100PA00X+065238Y+041482X0200Y         S0      
317GND              VIA   -    MD0100PA00X+064249Y+041257X0200Y    R180 S0      
317GND              VIA   -    MD0100PA00X+064760Y+039624X0200Y         S0      
317GND              VIA   -    MD0100PA00X+064353Y+040491X0200Y    R180 S0      
317GND              VIA   -    MD0100PA00X+064226Y+039624X0200Y    R180 S0      
317GND              VIA   -    MD0100PA00X+064907Y+038915X0200Y         S0      
317GND              VIA   -    MD0100PA00X+064226Y+038915X0200Y    R180 S0      
317GND              VIA   -    MD0100PA00X+065134Y+028834X0200Y    R090 S0      
317GND              VIA   -    MD0100PA00X+065384Y+029084X0200Y    R090 S0      
317GND              VIA   -    MD0100PA00X+065384Y+028834X0200Y    R090 S0      
317GND              VIA   -    M      A01X+064327Y+029076X0200Y         S2      
017GND              VIA   -    M      A18X+064327Y+029076X0260Y         S2      
017GND                    -    MD0100PA00X+064327Y+029076                       
317GND              VIA   -    MD0100PA00X+063927Y+029076X0200Y         S0      
327GND              PR7065-2          A01X+063927Y+028806X0198Y0197R090 S1      
317GND              VIA   -    MD0100PA00X+065384Y+029364X0200Y    R090 S0      
317GND              VIA   -    MD0100PA00X+065134Y+029364X0200Y    R090 S0      
317GND              VIA   -    MD0100PA00X+065134Y+029084X0200Y    R090 S0      
317GND              VIA   -    M      A01X+064935Y+028131X0200Y         S2      
017GND              VIA   -    M      A18X+064935Y+028131X0260Y         S2      
017GND                    -    MD0100PA00X+064935Y+028131                       
317GND              VIA   -    MD0100PA00X+064524Y+027921X0200Y         S0      
317GND              VIA   -    MD0100PA00X+064422Y+025654X0200Y         S0      
327GND              PC847 -2          A01X+064422Y+025954X0198Y0197R270 S1      
317GND              VIA   -    MD0100PA00X+066767Y+038915X0200Y         S0      
317GND              VIA   -    MD0100PA00X+066878Y+025237X0200Y         S0      
327GND              PR7073-2          A01X+067156Y+025237X0198Y0197R180 S1      
317GND              VIA   -    MD0100PA00X+066702Y+021686X0200Y         S0      
327GND              PC396 -2          A01X+066444Y+021686X0198Y0197     S1      
317GND              VIA   -    MD0100PA00X+066702Y+022186X0200Y         S0      
327GND              C2864 -2   M      A01X+066444Y+022186X0198Y0197     S1      
317GND              VIA   -    MD0100PA00X+066702Y+021286X0200Y         S0      
317GND              VIA   -    MD0100PA00X+066702Y+020086X0200Y         S0      
317GND              VIA   -    MD0100PA00X+065546Y+019242X0200Y         S0      
317GND              VIA   -    MD0100PA00X+066699Y+018066X0200Y         S0      
327GND              R564  -2          A01X+066435Y+018066X0198Y0197     S1      
317GND              VIA   -    MD0100PA00X+066699Y+017266X0200Y         S0      
327GND              R563  -2          A01X+066435Y+017266X0198Y0197     S1      
317GND              VIA   -    MD0100PA00X+066906Y+013330X0200Y         S0      
327GND              PC935 -2          A01X+066906Y+013090X0198Y0197R090 S1      
317GND              VIA   -    MD0100PA00X+066946Y+011078X0200Y         S0      
327GND              PU125 -3   M      A01X+067080Y+011368X0100Y0280     S1      
317GND              VIA   -    MD0100PA00X+066681Y+011339X0200Y         S0      
317GND              VIA   -    MD0100PA00X+065928Y+011726X0200Y         S0      
327GND              R6203 -1          A01X+065970Y+011449X0198Y0197R180 S1      
317GND              VIA   -    MD0100PA00X+066068Y+009195X0200Y         S0      
327GND              C2721 -1          A01X+065812Y+009195X0198Y0197R270 S1      
317GND              VIA   -    MD0100PA00X+066542Y+009685X0200Y         S0      
317GND              VIA   -    MD0100PA00X+066621Y+005730X0200Y         S0      
327GND              C2722 -1          A01X+066348Y+005801X0198Y0197R180 S1      
317GND              VIA   -    MD0100PA00X+066865Y+006092X0200Y         S0      
327GND              U131  -4          A01X+066835Y+006472X0240Y0460R180 S1      
317GND              VIA   -    MD0100PA00X+066037Y+044585X0200Y    R180 S0      
317GND              VIA   -    MD0100PA00X+066517Y+044585X0200Y         S0      
317GND              VIA   -    MD0100PA00X+066037Y+043876X0200Y    R180 S0      
317GND              VIA   -    MD0100PA00X+066037Y+043167X0200Y    R180 S0      
317GND              VIA   -    MD0100PA00X+066767Y+043167X0200Y         S0      
317GND              VIA   -    MD0100PA00X+066767Y+043876X0200Y         S0      
317GND              VIA   -    MD0100PA00X+066517Y+043876X0200Y         S0      
317GND              VIA   -    MD0100PA00X+066517Y+043167X0200Y         S0      
317GND              VIA   -    MD0100PA00X+066517Y+041750X0200Y         S0      
317GND              VIA   -    MD0100PA00X+066037Y+042459X0200Y    R180 S0      
317GND              VIA   -    MD0100PA00X+066037Y+041750X0200Y    R180 S0      
317GND              VIA   -    MD0100PA00X+066767Y+042459X0200Y         S0      
317GND              VIA   -    MD0100PA00X+066517Y+042459X0200Y         S0      
317GND              VIA   -    MD0100PA00X+066767Y+041750X0200Y         S0      
317GND              VIA   -    MD0100PA00X+066037Y+039624X0200Y    R180 S0      
317GND              VIA   -    MD0100PA00X+066767Y+041041X0200Y         S0      
317GND              VIA   -    MD0100PA00X+066517Y+041041X0200Y         S0      
317GND              VIA   -    MD0100PA00X+066767Y+040333X0200Y         S0      
317GND              VIA   -    MD0100PA00X+066517Y+040333X0200Y         S0      
317GND              VIA   -    MD0100PA00X+066767Y+039624X0200Y         S0      
317GND              VIA   -    MD0100PA00X+066517Y+039624X0200Y         S0      
317GND              VIA   -    MD0100PA00X+066037Y+041041X0200Y    R180 S0      
317GND              VIA   -    MD0100PA00X+066037Y+040333X0200Y    R180 S0      
317GND              VIA   -    MD0100PA00X+066037Y+038915X0200Y    R180 S0      
317GND              VIA   -    MD0100PA00X+066037Y+046754X0200Y    R180 S0      
317GND              VIA   -    MD0100PA00X+066767Y+046754X0200Y         S0      
317GND              VIA   -    MD0100PA00X+067247Y+040333X0200Y         S0      
317GND              VIA   -    MD0100PA00X+067247Y+039624X0200Y         S0      
317GND              VIA   -    M      A01X+068535Y+040472X0200Y    R180 S2      
017GND              VIA   -    M      A18X+068535Y+040472X0260Y    R180 S2      
017GND                    -    MD0100PA00X+068535Y+040472                       
327GND              R172  -2          A01X+068778Y+040472X0198Y0197R180 S1      
317GND              VIA   -    MD0100PA00X+068535Y+040072X0200Y    R180 S0      
327GND              R174  -2          A01X+068778Y+040072X0198Y0197R180 S1      
317GND              VIA   -    MD0100PA00X+068535Y+040872X0200Y    R180 S0      
327GND              R171  -2          A01X+068778Y+040872X0198Y0197R180 S1      
317GND              VIA   -    MD0100PA00X+067247Y+041041X0200Y         S0      
317GND              VIA   -    MD0100PA00X+067247Y+038915X0200Y         S0      
317GND              VIA   -    MD0100PA00X+068535Y+039272X0200Y    R180 S0      
327GND              R181  -2          A01X+068778Y+039272X0198Y0197R180 S1      
317GND              VIA   -    MD0100PA00X+068601Y+033980X0200Y         S0      
317GND              VIA   -    MD0100PA00X+068326Y+025320X0200Y         S0      
327GND              Q202  -1          A01X+068027Y+025320X0240Y0240R270 S1      
317GND              VIA   -    MD0100PA00X+068334Y+023612X0200Y    R090 S0      
327GND              PC504 -2          A01X+068590Y+023612X0198Y0197R090 S1      
317GND              VIA   -    MD0100PA00X+068038Y+023859X0200Y    R090 S0      
327GND              C2890 -2          A01X+068038Y+023601X0198Y0197R090 S1      
317GND              VIA   -    MD0100PA00X+068088Y+020684X0200Y    R180 S0      
317GND              VIA   -    MD0100PA00X+067838Y+020684X0200Y    R180 S0      
317GND              VIA   -    MD0100PA00X+067469Y+020339X0200Y    R180 S0      
317GND              VIA   -    M      A01X+067695Y+020168X0200Y    R090 S2      
017GND              VIA   -    M      A18X+067695Y+020168X0260Y    R090 S2      
017GND                    -    MD0100PA00X+067695Y+020168                       
317GND              VIA   -    MD0100PA00X+067219Y+020339X0200Y    R180 S0      
317GND              VIA   -    M      A01X+068013Y+019518X0200Y    R180 S2      
017GND              VIA   -    M      A18X+068013Y+019518X0260Y    R180 S2      
017GND                    -    MD0100PA00X+068013Y+019518                       
317GND              VIA   -    MD0100PA00X+067695Y+019888X0200Y         S0      
317GND              VIA   -    MD0100PA00X+067733Y+019518X0200Y         S0      
317GND              VIA   -    MD0100PA00X+067483Y+019518X0200Y    R180 S0      
317GND              VIA   -    MD0100PA00X+067233Y+019518X0200Y    R180 S0      
317GND              VIA   -    MD0100PA00X+068570Y+014123X0200Y         S0      
327GND              R5679 -2          A01X+068423Y+013884X0198Y0197     S1      
317GND              VIA   -    MD0100PA00X+068379Y+014601X0200Y         S0      
327GND              C3665 -2          A01X+068129Y+014601X0198Y0197R090 S1      
317GND              VIA   -    MD0100PA00X+067120Y+013458X0200Y         S0      
327GND              U389  -3          A01X+066809Y+013674X0240Y0240     S1      
317GND              VIA   -    MD0100PA00X+067706Y+013330X0200Y         S0      
327GND              PC930 -2          A01X+067706Y+013090X0198Y0197R090 S1      
317GND              VIA   -    MD0100PA00X+068406Y+010650X0200Y         S0      
327GND              C2769 -2   M      A01X+068665Y+010650X0198Y0197R180 S1      
317GND              VIA   -    MD0100PA00X+068505Y+010917X0200Y         S0      
317GND              VIA   -    MD0100PA00X+068205Y+010917X0200Y         S0      
317GND              VIA   -    M      A01X+067903Y+010225X0200Y    R180 S2      
017GND              VIA   -    M      A18X+067903Y+010225X0260Y    R180 S2      
017GND                    -    MD0100PA00X+067903Y+010225                       
317GND              VIA   -    MD0100PA00X+067247Y+046754X0200Y         S0      
317GND              VIA   -    MD0100PA00X+067247Y+043167X0200Y         S0      
317GND              VIA   -    MD0100PA00X+067247Y+043876X0200Y         S0      
317GND              VIA   -    M      A01X+068535Y+041272X0200Y    R180 S2      
017GND              VIA   -    M      A18X+068535Y+041272X0260Y    R180 S2      
017GND                    -    MD0100PA00X+068535Y+041272                       
327GND              R173  -2          A01X+068778Y+041272X0198Y0197R180 S1      
317GND              VIA   -    MD0100PA00X+067247Y+041750X0200Y         S0      
317GND              VIA   -    MD0100PA00X+067247Y+042459X0200Y         S0      
317GND              VIA   -    MD0100PA00X+069739Y+005362X0200Y    R270 S0      
317GND              VIA   -    MD0100PA00X+069007Y+004466X0200Y    R270 S0      
317GND              VIA   -    MD0100PA00X+069055Y+024729X0200Y         S0      
327GND              Q202  -4          A01X+068736Y+024729X0240Y0240R270 S1      
317GND              VIA   -    MD0100PA00X+068978Y+023869X0200Y    R090 S0      
327GND              PR266 -2          A01X+068978Y+023611X0198Y0197R090 S1      
317GND              VIA   -    MD0100PA00X+069801Y+023871X0200Y    R090 S0      
327GND              PC531 -2          A01X+069801Y+023613X0198Y0197R090 S1      
317GND              VIA   -    MD0100PA00X+069633Y+021354X0200Y    R090 S0      
317GND              VIA   -    MD0100PA00X+068858Y+015085X0200Y         S0      
327GND              U369  -S          A01X+068464Y+015330X0400Y0560     S1      
317GND              VIA   -    MD0100PA00X+069980Y+013776X0200Y         S0      
317GND              VIA   -    MD0100PA00X+069260Y+013776X0200Y         S0      
317GND              VIA   -    MD0100PA00X+068780Y+013776X0200Y         S0      
317GND              VIA   -    MD0100PA00X+069980Y+013067X0200Y         S0      
317GND              VIA   -    MD0100PA00X+069980Y+012358X0200Y         S0      
317GND              VIA   -    MD0100PA00X+069510Y+013067X0200Y         S0      
317GND              VIA   -    MD0100PA00X+069260Y+013067X0200Y         S0      
317GND              VIA   -    MD0100PA00X+068780Y+013067X0200Y         S0      
317GND              VIA   -    MD0100PA00X+069260Y+012358X0200Y         S0      
317GND              VIA   -    MD0100PA00X+069510Y+012358X0200Y         S0      
317GND              VIA   -    MD0100PA00X+068780Y+012358X0200Y         S0      
317GND              VIA   -    MD0100PA00X+069980Y+010232X0200Y         S0      
317GND              VIA   -    MD0100PA00X+069980Y+010941X0200Y         S0      
317GND              VIA   -    MD0100PA00X+069980Y+011650X0200Y         S0      
317GND              VIA   -    MD0100PA00X+069510Y+011650X0200Y         S0      
317GND              VIA   -    MD0100PA00X+069260Y+011650X0200Y         S0      
317GND              VIA   -    MD0100PA00X+068780Y+011650X0200Y         S0      
317GND              VIA   -    MD0100PA00X+069510Y+010941X0200Y         S0      
317GND              VIA   -    MD0100PA00X+070927Y+013776X0200Y    R180 S0      
317GND              VIA   -    MD0100PA00X+071450Y+013776X0200Y         S0      
317GND              VIA   -    MD0100PA00X+070928Y+013067X0200Y    R180 S0      
317GND              VIA   -    MD0100PA00X+071791Y+012358X0200Y         S0      
317GND              VIA   -    MD0100PA00X+071791Y+013067X0200Y         S0      
317GND              VIA   -    MD0100PA00X+070822Y+012458X0200Y    R180 S0      
317GND              VIA   -    MD0100PA00X+071791Y+010941X0200Y         S0      
317GND              VIA   -    MD0100PA00X+071791Y+011650X0200Y         S0      
317GND              VIA   -    MD0100PA00X+070805Y+011650X0200Y    R180 S0      
317GND              VIA   -    MD0100PA00X+070805Y+010941X0200Y    R180 S0      
317GND              VIA   -    MD0100PA00X+070780Y+010232X0200Y    R180 S0      
317GND              VIA   -    MD0100PA00X+071778Y+010304X0200Y         S0      
317GND              VIA   -    MD0100PA00X+070826Y+008558X0200Y         S0      
317GND              VIA   -    MD0100PA00X+071082Y+009285X0200Y         S0      
317GND              VIA   -    MD0100PA00X+070826Y+007518X0200Y         S0      
317GND              VIA   -    MD0100PA00X+070826Y+007778X0200Y         S0      
317GND              VIA   -    MD0100PA00X+070826Y+008038X0200Y         S0      
317GND              VIA   -    MD0100PA00X+070826Y+008298X0200Y         S0      
317GND              VIA   -    MD0100PA00X+071739Y+005362X0200Y    R270 S0      
317GND              VIA   -    MD0100PA00X+072591Y+010941X0200Y    R180 S0      
317GND              VIA   -    MD0100PA00X+072591Y+011650X0200Y    R180 S0      
317GND              VIA   -    MD0100PA00X+073492Y+010170X0200Y    R090 S0      
317GND              VIA   -    MD0100PA00X+073119Y+009402X0200Y         S0      
317GND              VIA   -    MD0100PA00X+073519Y+009402X0200Y         S0      
317GND              VIA   -    MD0100PA00X+071869Y+046549X0200Y         S0      
317GND              VIA   -    MD0100PA00X+071176Y+044987X0200Y         S0      
327GND              R191  -2          A01X+070936Y+044987X0198Y0197     S1      
317GND              VIA   -    MD0100PA00X+071316Y+043449X0200Y         S0      
317GND              VIA   -    MD0100PA00X+071654Y+022373X0200Y    R090 S0      
317GND              VIA   -    MD0100PA00X+071654Y+022623X0200Y    R090 S0      
317GND              VIA   -    MD0100PA00X+071654Y+023123X0200Y    R090 S0      
317GND              VIA   -    MD0100PA00X+071654Y+022873X0200Y    R090 S0      
317GND              VIA   -    MD0100PA00X+072349Y+045132X0200Y         S0      
317GND              VIA   -    MD0100PA00X+072349Y+045841X0200Y         S0      
317GND              VIA   -    MD0100PA00X+072303Y+043010X0200Y    R270 S0      
317GND              VIA   -    MD0100PA00X+072303Y+043260X0200Y    R270 S0      
317GND              VIA   -    MD0100PA00X+072303Y+043510X0200Y    R270 S0      
317GND              VIA   -    MD0100PA00X+072303Y+043760X0200Y    R270 S0      
317GND              VIA   -    MD0100PA00X+072303Y+044010X0200Y    R270 S0      
317GND              VIA   -    MD0100PA00X+072210Y+040331X0200Y         S0      
317GND              VIA   -    MD0100PA00X+072210Y+041039X0200Y         S0      
317GND              VIA   -    MD0100PA00X+073461Y+037956X0200Y         S0      
317GND              VIA   -    MD0100PA00X+073151Y+039050X0200Y         S0      
327GND              R176  -2          A18X+073151Y+038800X0198Y0197     S2      
317GND              VIA   -    MD0100PA00X+073340Y+028819X0200Y         S0      
317GND              VIA   -    MD0100PA00X+073060Y+028819X0200Y         S0      
317GND              VIA   -    MD0100PA00X+072810Y+028569X0200Y         S0      
317GND              VIA   -    MD0100PA00X+073060Y+028569X0200Y         S0      
317GND              VIA   -    MD0100PA00X+072810Y+028819X0200Y         S0      
317GND              VIA   -    MD0100PA00X+072259Y+029380X0200Y         S0      
317GND              VIA   -    MD0100PA00X+072009Y+029380X0200Y         S0      
317GND              VIA   -    MD0100PA00X+073340Y+028569X0200Y         S0      
317GND              VIA   -    MD0100PA00X+073065Y+024889X0200Y    R180 S0      
317GND              VIA   -    MD0100PA00X+073315Y+024889X0200Y    R180 S0      
317GND              VIA   -    MD0100PA00X+073497Y+023179X0200Y    R090 S0      
317GND              VIA   -    MD0100PA00X+073095Y+023661X0200Y    R180 S0      
317GND              VIA   -    MD0100PA00X+073345Y+023661X0200Y    R180 S0      
317GND              VIA   -    MD0100PA00X+072700Y+023146X0200Y    R090 S0      
317GND              VIA   -    MD0100PA00X+073497Y+022929X0200Y    R090 S0      
317GND              VIA   -    M      A01X+072700Y+022366X0200Y    R090 S2      
017GND              VIA   -    M      A18X+072700Y+022366X0260Y    R090 S2      
017GND                    -    MD0100PA00X+072700Y+022366                       
317GND              VIA   -    M      A01X+073351Y+022614X0200Y         S2      
017GND              VIA   -    M      A18X+073351Y+022614X0260Y         S2      
017GND                    -    MD0100PA00X+073351Y+022614                       
317GND              VIA   -    MD0100PA00X+072700Y+022646X0200Y    R090 S0      
317GND              VIA   -    MD0100PA00X+073071Y+022614X0200Y         S0      
317GND              VIA   -    MD0100PA00X+072700Y+022896X0200Y    R090 S0      
327GND              C316  -2          A01X+073975Y+018740X0198Y0197R090 S1      
317GND              VIA   -    M      A01X+073675Y+018873X0200Y         S2      
017GND              VIA   -    M      A18X+073675Y+018873X0260Y         S2      
017GND                    -    MD0100PA00X+073675Y+018873                       
317GND              VIA   -    MD0100PA00X+073323Y+015154X0200Y         S0      
327GND              R6077 -2          A01X+073601Y+015154X0198Y0197R180 S1      
317GND              VIA   -    MD0100PA00X+072591Y+013776X0200Y    R180 S0      
317GND              VIA   -    MD0100PA00X+072591Y+012358X0200Y    R180 S0      
317GND              VIA   -    MD0100PA00X+072591Y+013067X0200Y    R180 S0      
317GND              VIA   -    MD0100PA00X+072591Y+010232X0200Y    R180 S0      
317GND              VIA   -    MD0100PA00X+074881Y+014646X0200Y         S0      
327GND              Q223  -4          A01X+075182Y+014646X0240Y0240R270 S1      
317GND              VIA   -    MD0100PA00X+074572Y+013669X0200Y         S0      
317GND              VIA   -    MD0100PA00X+075071Y+013669X0200Y         S0      
317GND              VIA   -    MD0100PA00X+075071Y+012251X0200Y         S0      
317GND              VIA   -    MD0100PA00X+075071Y+013173X0200Y         S0      
317GND              VIA   -    MD0100PA00X+073532Y+012957X0200Y         S0      
317GND              VIA   -    MD0100PA00X+073532Y+012462X0200Y         S0      
317GND              VIA   -    MD0100PA00X+074031Y+012462X0200Y         S0      
317GND              VIA   -    MD0100PA00X+074031Y+012957X0200Y         S0      
317GND              VIA   -    MD0100PA00X+074572Y+012251X0200Y         S0      
317GND              VIA   -    MD0100PA00X+074572Y+013173X0200Y         S0      
317GND              VIA   -    MD0100PA00X+074247Y+010378X0200Y    R270 S0      
327GND              R428  -1          A01X+074247Y+010135X0198Y0197R270 S1      
317GND              VIA   -    MD0100PA00X+073532Y+011540X0200Y         S0      
317GND              VIA   -    MD0100PA00X+073532Y+011044X0200Y         S0      
317GND              VIA   -    MD0100PA00X+074031Y+011044X0200Y         S0      
317GND              VIA   -    MD0100PA00X+074031Y+011540X0200Y         S0      
317GND              VIA   -    MD0100PA00X+074572Y+011756X0200Y         S0      
317GND              VIA   -    MD0100PA00X+075071Y+011756X0200Y         S0      
317GND              VIA   -    MD0100PA00X+073919Y+009402X0200Y         S0      
317GND              VIA   -    MD0100PA00X+074320Y+009402X0200Y         S0      
317GND              VIA   -    MD0100PA00X+074827Y+008014X0200Y         S0      
317GND              VIA   -    MD0100PA00X+074827Y+007614X0200Y         S0      
317GND              VIA   -    MD0100PA00X+074827Y+008414X0200Y         S0      
317GND              VIA   -    MD0100PA00X+073556Y+004477X0200Y    R270 S0      
317GND              VIA   -    MD0100PA00X+073556Y+002477X0200Y    R270 S0      
317GND              VIA   -    MD0100PA00X+073624Y+000537X0200Y    R270 S0      
317GND              VIA   -    MD0100PA00X+072332Y+046226X0200Y         S0      
327GND              C887  -2          A18X+072718Y+046348X0198Y0197     S2      
317GND              VIA   -    MD0100PA00X+073129Y+046603X0200Y    R180 S0      
317GND              VIA   -    MD0100PA00X+072349Y+046549X0200Y         S0      
317GND              VIA   -    MD0100PA00X+074122Y+043707X0200Y    R180 S0      
317GND              VIA   -    MD0100PA00X+074140Y+043357X0200Y    R180 S0      
317GND              VIA   -    MD0100PA00X+074138Y+043076X0200Y    R180 S0      
317GND              VIA   -    MD0100PA00X+074126Y+043996X0200Y    R180 S0      
317GND              VIA   -    MD0100PA00X+074959Y+040331X0200Y    R180 S0      
317GND              VIA   -    MD0100PA00X+074959Y+041039X0200Y    R180 S0      
317GND              VIA   -    MD0100PA00X+074116Y+038150X0200Y         S0      
327GND              R175  -2          A18X+074116Y+038450X0198Y0197R180 S2      
317GND              VIA   -    M      A01X+074563Y+029076X0200Y         S2      
017GND              VIA   -    M      A18X+074563Y+029076X0260Y         S2      
017GND                    -    MD0100PA00X+074563Y+029076                       
317GND              VIA   -    MD0100PA00X+073763Y+029076X0200Y         S0      
327GND              PC852 -2          A01X+073763Y+028806X0198Y0197R090 S1      
317GND              VIA   -    MD0100PA00X+074163Y+029076X0200Y         S0      
327GND              PR7070-2          A01X+074163Y+028806X0198Y0197R090 S1      
317GND              VIA   -    M      A01X+075171Y+028131X0200Y         S2      
017GND              VIA   -    M      A18X+075171Y+028131X0260Y         S2      
017GND                    -    MD0100PA00X+075171Y+028131                       
317GND              VIA   -    MD0100PA00X+074761Y+027921X0200Y         S0      
317GND              VIA   -    MD0100PA00X+074658Y+025654X0200Y         S0      
327GND              PC850 -2          A01X+074658Y+025954X0198Y0197R270 S1      
317GND              VIA   -    MD0100PA00X+073858Y+025654X0200Y         S0      
327GND              PC853 -2          A01X+073858Y+025954X0198Y0197R270 S1      
317GND              VIA   -    MD0100PA00X+073565Y+024889X0200Y    R180 S0      
317GND              VIA   -    MD0100PA00X+073595Y+023661X0200Y    R180 S0      
317GND              VIA   -    MD0100PA00X+073866Y+022221X0200Y    R090 S0      
317GND              VIA   -    MD0100PA00X+073866Y+022471X0200Y    R090 S0      
317GND              VIA   -    MD0100PA00X+074536Y+020676X0200Y         S0      
317GND              VIA   -    MD0100PA00X+073688Y+019194X0200Y         S0      
327GND              C318  -2          A01X+073966Y+019194X0198Y0197R180 S1      
317GND              VIA   -    MD0100PA00X+074338Y+018462X0200Y         S0      
327GND              U61   -10         A01X+074624Y+018383X0090Y0240R090 S1      
317GND              VIA   -    MD0100PA00X+074942Y+018516X0200Y         S0      
317GND              VIA   -    MD0100PA00X+074942Y+018057X0200Y         S0      
317GND              VIA   -    MD0100PA00X+074772Y+015237X0200Y         S0      
327GND              Q223  -1          A01X+074473Y+015237X0240Y0240R270 S1      
317GND              VIA   -    MD0100PA00X+076710Y+031673X0200Y    R090 S0      
327GND              Q4    -4          A01X+076440Y+031673X0170Y0240R270 S1      
317GND              VIA   -    MD0100PA00X+076041Y+032449X0200Y    R090 S0      
327GND              Q4    -1          A01X+075692Y+032185X0170Y0240R270 S1      
317GND              VIA   -    MD0100PA00X+075620Y+029364X0200Y         S0      
317GND              VIA   -    MD0100PA00X+075370Y+029364X0200Y         S0      
317GND              VIA   -    MD0100PA00X+075370Y+029084X0200Y         S0      
317GND              VIA   -    MD0100PA00X+075370Y+028834X0200Y         S0      
317GND              VIA   -    MD0100PA00X+075620Y+029084X0200Y         S0      
317GND              VIA   -    MD0100PA00X+075620Y+028834X0200Y         S0      
317GND              VIA   -    MD0100PA00X+075405Y+018512X0200Y         S0      
317GND              VIA   -    MD0100PA00X+075782Y+019242X0200Y         S0      
317GND              VIA   -    MD0100PA00X+075410Y+018053X0200Y         S0      
327GND              U61   -TH  M      A01X+075176Y+018285X0670Y0670R180 S1      
317GND              VIA   -    MD0100PA00X+075364Y+010362X0200Y    R090 S0      
327GND              U404  -S          A01X+075364Y+010792X0400Y0560R180 S1      
317GND              VIA   -    MD0100PA00X+076206Y+011704X0200Y         S0      
327GND              R6204 -1          A01X+076206Y+011449X0198Y0197R180 S1      
317GND              VIA   -    MD0100PA00X+076304Y+009195X0200Y    R180 S0      
327GND              C2723 -1          A01X+076048Y+009195X0198Y0197R270 S1      
317GND              VIA   -    MD0100PA00X+076585Y+005551X0200Y         S0      
327GND              C2724 -1          A01X+076585Y+005801X0198Y0197R180 S1      
317GND              VIA   -    MD0100PA00X+075514Y+000300X0200Y    R270 S0      
317GND              VIA   -    MD0100PA00X+074940Y+046549X0200Y    R180 S0      
317GND              VIA   -    MD0100PA00X+073933Y+047014X0200Y         S0      
327GND              R177  -2          A18X+073933Y+046737X0198Y0197R180 S2      
317GND              VIA   -    MD0100PA00X+074157Y+046025X0200Y         S0      
317GND              VIA   -    MD0100PA00X+074160Y+046549X0200Y         S0      
317GND              VIA   -    MD0100PA00X+074940Y+045841X0200Y    R180 S0      
317GND              VIA   -    MD0100PA00X+074146Y+045202X0200Y    R180 S0      
317GND              VIA   -    MD0100PA00X+074152Y+045474X0200Y    R180 S0      
317GND              VIA   -    MD0100PA00X+074150Y+044318X0200Y    R180 S0      
317GND              VIA   -    MD0100PA00X+076935Y+018066X0200Y         S0      
327GND              R575  -2          A01X+076671Y+018066X0198Y0197     S1      
317GND              VIA   -    MD0100PA00X+076935Y+017266X0200Y         S0      
327GND              R574  -2          A01X+076671Y+017266X0198Y0197     S1      
317GND              VIA   -    MD0100PA00X+077356Y+013458X0200Y         S0      
327GND              U388  -3          A01X+077045Y+013674X0240Y0240     S1      
317GND              VIA   -    MD0100PA00X+076793Y+009689X0200Y         S0      
317GND              VIA   -    MD0100PA00X+077101Y+006092X0200Y         S0      
327GND              U132  -4          A01X+077071Y+006472X0240Y0460R180 S1      
317GND              VIA   -    MD0100PA00X+077514Y+000300X0200Y    R270 S0      
317GND              VIA   -    MD0100PA00X+075559Y+044591X0200Y         S0      
327GND              C900  -2          A18X+075559Y+044863X0198Y0197R090 S2      
317GND              VIA   -    MD0100PA00X+075954Y+044579X0200Y         S0      
327GND              C897  -2          A18X+075954Y+044863X0198Y0197R090 S2      
317GND              VIA   -    MD0100PA00X+075838Y+039539X0200Y         S0      
317GND              VIA   -    MD0100PA00X+075680Y+040382X0200Y         S0      
317GND              VIA   -    MD0100PA00X+075234Y+040715X0200Y         S0      
317GND              VIA   -    MD0100PA00X+076634Y+040192X0200Y         S0      
327GND              R170  -2          A18X+076394Y+040192X0198Y0197R180 S2      
317GND              VIA   -    MD0100PA00X+076634Y+040592X0200Y         S0      
327GND              R169  -2          A18X+076394Y+040592X0198Y0197R180 S2      
317GND              VIA   -    MD0100PA00X+076634Y+040992X0200Y         S0      
317GND              VIA   -    MD0100PA00X+075804Y+038114X0200Y         S0      
317GND              VIA   -    MD0100PA00X+076634Y+038591X0200Y         S0      
327GND              R166  -2          A18X+076394Y+038591X0198Y0197R180 S2      
317GND              VIA   -    MD0100PA00X+076634Y+038991X0200Y         S0      
327GND              R167  -2          A18X+076394Y+038991X0198Y0197R180 S2      
317GND              VIA   -    MD0100PA00X+076634Y+039392X0200Y         S0      
317GND              VIA   -    MD0100PA00X+075903Y+033202X0200Y    R270 S0      
327GND              C412  -2          A01X+076163Y+033202X0198Y0197R090 S1      
317GND              VIA   -    MD0100PA00X+076390Y+034232X0200Y         S0      
327GND              U25   -3          A01X+076037Y+034232X0160Y0360R270 S1      
317GND              VIA   -    MD0100PA00X+079746Y+010941X0200Y         S0      
317GND              VIA   -    MD0100PA00X+078642Y+010650X0200Y         S0      
327GND              C2770 -2   M      A01X+078901Y+010650X0198Y0197R180 S1      
317GND              VIA   -    MD0100PA00X+079016Y+011650X0200Y         S0      
317GND              VIA   -    MD0100PA00X+079746Y+011650X0200Y         S0      
317GND              VIA   -    MD0100PA00X+079496Y+011650X0200Y         S0      
317GND              VIA   -    MD0100PA00X+079981Y+005360X0200Y    R270 S0      
317GND              VIA   -    MD0100PA00X+079249Y+004477X0200Y    R270 S0      
317GND              VIA   -    MD0100PA00X+079249Y+002477X0200Y    R270 S0      
317GND              VIA   -    MD0100PA00X+079113Y+000447X0200Y    R270 S0      
317GND              VIA   -    MD0100PA00X+077558Y+047148X0200Y    R270 S0      
317GND              VIA   -    MD0100PA00X+078058Y+046653X0200Y    R090 S0      
317GND              VIA   -    MD0100PA00X+077558Y+046653X0200Y    R270 S0      
317GND              VIA   -    MD0100PA00X+078058Y+047148X0200Y    R090 S0      
317GND              VIA   -    MD0100PA00X+077903Y+045051X0200Y    R180 S0      
327GND              R187  -2          A01X+078155Y+045051X0198Y0197R180 S1      
317GND              VIA   -    MD0100PA00X+077888Y+044651X0200Y    R180 S0      
327GND              R185  -2          A01X+078155Y+044651X0198Y0197R180 S1      
317GND              VIA   -    MD0100PA00X+077898Y+044250X0200Y    R180 S0      
317GND              VIA   -    MD0100PA00X+077757Y+035351X0200Y         S0      
327GND              C902  -2          A01X+077757Y+035085X0198Y0197     S1      
317GND              VIA   -    MD0100PA00X+077299Y+033632X0200Y         S0      
327GND              U26   -3          A01X+077736Y+033632X0220Y0530R090 S1      
317GND              VIA   -    MD0100PA00X+077694Y+032165X0200Y    R180 S0      
327GND              U27   -3          A01X+078051Y+032165X0400Y0500     S1      
317GND              VIA   -    MD0100PA00X+078097Y+030384X0200Y         S0      
327GND              C904  -2          A01X+078097Y+030665X0198Y0197R180 S1      
317GND              VIA   -    MD0100PA00X+077114Y+025237X0200Y         S0      
327GND              PR7074-2          A01X+077392Y+025237X0198Y0197R180 S1      
317GND              VIA   -    MD0100PA00X+078274Y+023859X0200Y    R090 S0      
327GND              C2891 -2          A01X+078274Y+023601X0198Y0197R090 S1      
317GND              VIA   -    MD0100PA00X+076938Y+021686X0200Y         S0      
327GND              PC372 -2          A01X+076680Y+021686X0198Y0197     S1      
317GND              VIA   -    MD0100PA00X+076938Y+022186X0200Y         S0      
327GND              C2866 -2          A01X+076680Y+022186X0198Y0197     S1      
317GND              VIA   -    MD0100PA00X+076938Y+021286X0200Y         S0      
317GND              VIA   -    MD0100PA00X+076938Y+020086X0200Y         S0      
317GND              VIA   -    MD0100PA00X+077455Y+020339X0200Y    R180 S0      
317GND              VIA   -    M      A01X+077931Y+020168X0200Y    R090 S2      
017GND              VIA   -    M      A18X+077931Y+020168X0260Y    R090 S2      
017GND                    -    MD0100PA00X+077931Y+020168                       
317GND              VIA   -    MD0100PA00X+077705Y+020339X0200Y    R180 S0      
317GND              VIA   -    MD0100PA00X+078324Y+020684X0200Y    R180 S0      
317GND              VIA   -    MD0100PA00X+078074Y+020684X0200Y    R180 S0      
317GND              VIA   -    MD0100PA00X+077469Y+019518X0200Y    R180 S0      
317GND              VIA   -    M      A01X+078249Y+019518X0200Y    R180 S2      
017GND              VIA   -    M      A18X+078249Y+019518X0260Y    R180 S2      
017GND                    -    MD0100PA00X+078249Y+019518                       
317GND              VIA   -    MD0100PA00X+077719Y+019518X0200Y    R180 S0      
317GND              VIA   -    MD0100PA00X+077931Y+019888X0200Y    R090 S0      
317GND              VIA   -    MD0100PA00X+077969Y+019518X0200Y    R180 S0      
317GND              VIA   -    MD0100PA00X+081062Y+007518X0200Y         S0      
317GND              VIA   -    MD0100PA00X+081062Y+008038X0200Y         S0      
317GND              VIA   -    MD0100PA00X+081062Y+008298X0200Y         S0      
317GND              VIA   -    MD0100PA00X+078459Y+041600X0200Y    R180 S0      
317GND              VIA   -    MD0100PA00X+078459Y+041350X0200Y    R180 S0      
317GND              VIA   -    MD0100PA00X+078459Y+041850X0200Y    R180 S0      
317GND              VIA   -    MD0100PA00X+078459Y+042100X0200Y    R180 S0      
317GND              VIA   -    MD0100PA00X+079256Y+040641X0200Y    R180 S0      
317GND              VIA   -    MD0100PA00X+079994Y+034734X0200Y         S0      
317GND              VIA   -    MD0100PA00X+078852Y+029030X0200Y         S0      
317GND              VIA   -    MD0100PA00X+078562Y+025320X0200Y         S0      
327GND              Q203  -1          A01X+078264Y+025320X0240Y0240R270 S1      
317GND              VIA   -    MD0100PA00X+078570Y+023612X0200Y    R090 S0      
327GND              PC528 -2          A01X+078826Y+023612X0198Y0197R090 S1      
317GND              VIA   -    MD0100PA00X+079214Y+023869X0200Y    R090 S0      
327GND              PR269 -2          A01X+079214Y+023611X0198Y0197R090 S1      
317GND              VIA   -    MD0100PA00X+079291Y+024729X0200Y         S0      
327GND              Q203  -4          A01X+078972Y+024729X0240Y0240R270 S1      
317GND              VIA   -    MD0100PA00X+079869Y+021354X0200Y    R090 S0      
317GND              VIA   -    MD0100PA00X+079094Y+015085X0200Y         S0      
327GND              U370  -S          A01X+078700Y+015330X0400Y0560     S1      
317GND              VIA   -    MD0100PA00X+078615Y+014601X0200Y         S0      
327GND              C3666 -2          A01X+078365Y+014601X0198Y0197R090 S1      
317GND              VIA   -    MD0100PA00X+078806Y+014123X0200Y         S0      
327GND              R5676 -2          A01X+078659Y+013884X0198Y0197     S1      
317GND              VIA   -    MD0100PA00X+079016Y+013776X0200Y         S0      
317GND              VIA   -    MD0100PA00X+079496Y+013776X0200Y         S0      
317GND              VIA   -    MD0100PA00X+079016Y+013067X0200Y         S0      
317GND              VIA   -    MD0100PA00X+079746Y+013067X0200Y         S0      
317GND              VIA   -    MD0100PA00X+079496Y+013067X0200Y         S0      
317GND              VIA   -    MD0100PA00X+079016Y+012358X0200Y         S0      
317GND              VIA   -    MD0100PA00X+079496Y+012358X0200Y         S0      
317GND              VIA   -    MD0100PA00X+079746Y+012358X0200Y         S0      
317GND              VIA   -    MD0100PA00X+080037Y+023871X0200Y    R090 S0      
327GND              PC542 -2          A01X+080037Y+023613X0198Y0197R090 S1      
317GND              VIA   -    MD0100PA00X+080216Y+013776X0200Y         S0      
317GND              VIA   -    MD0100PA00X+081163Y+013776X0200Y    R180 S0      
317GND              VIA   -    MD0100PA00X+080216Y+012358X0200Y         S0      
317GND              VIA   -    MD0100PA00X+080216Y+013067X0200Y         S0      
317GND              VIA   -    MD0100PA00X+081164Y+013067X0200Y    R180 S0      
317GND              VIA   -    MD0100PA00X+081058Y+012458X0200Y    R180 S0      
317GND              VIA   -    MD0100PA00X+080216Y+010232X0200Y         S0      
317GND              VIA   -    MD0100PA00X+080216Y+010941X0200Y         S0      
317GND              VIA   -    MD0100PA00X+080216Y+011650X0200Y         S0      
317GND              VIA   -    MD0100PA00X+081041Y+011650X0200Y    R180 S0      
317GND              VIA   -    MD0100PA00X+081041Y+010941X0200Y    R180 S0      
317GND              VIA   -    MD0100PA00X+081016Y+010232X0200Y    R180 S0      
317GND              VIA   -    MD0100PA00X+081062Y+008558X0200Y         S0      
317GND              VIA   -    MD0100PA00X+081318Y+009285X0200Y         S0      
317GND              VIA   -    MD0100PA00X+081062Y+007778X0200Y         S0      
317GND              VIA   -    MD0100PA00X+082938Y+034804X0200Y    R090 S0      
317GND              VIA   -    MD0100PA00X+082579Y+030522X0200Y         S0      
327GND              U330  -12         A01X+083296Y+030890X0240Y0540R270 S1      
317GND              VIA   -    MD0100PA00X+083047Y+028819X0200Y         S0      
317GND              VIA   -    MD0100PA00X+083047Y+028569X0200Y         S0      
317GND              VIA   -    MD0100PA00X+082245Y+029380X0200Y         S0      
317GND              VIA   -    MD0100PA00X+082495Y+029380X0200Y         S0      
317GND              VIA   -    MD0100PA00X+081891Y+022373X0200Y    R090 S0      
317GND              VIA   -    MD0100PA00X+081891Y+022623X0200Y    R090 S0      
317GND              VIA   -    MD0100PA00X+081891Y+023123X0200Y    R090 S0      
317GND              VIA   -    MD0100PA00X+081891Y+022873X0200Y    R090 S0      
317GND              VIA   -    M      A01X+082936Y+022366X0200Y    R090 S2      
017GND              VIA   -    M      A18X+082936Y+022366X0260Y    R090 S2      
017GND                    -    MD0100PA00X+082936Y+022366                       
317GND              VIA   -    MD0100PA00X+082936Y+022646X0200Y    R090 S0      
317GND              VIA   -    MD0100PA00X+082936Y+022896X0200Y    R090 S0      
317GND              VIA   -    MD0100PA00X+082936Y+023146X0200Y    R090 S0      
317GND              VIA   -    MD0100PA00X+082827Y+013776X0200Y    R180 S0      
317GND              VIA   -    MD0100PA00X+081664Y+013776X0200Y         S0      
317GND              VIA   -    MD0100PA00X+082827Y+012358X0200Y    R180 S0      
317GND              VIA   -    MD0100PA00X+082827Y+013067X0200Y    R180 S0      
317GND              VIA   -    MD0100PA00X+082027Y+012358X0200Y         S0      
317GND              VIA   -    MD0100PA00X+082027Y+013067X0200Y         S0      
317GND              VIA   -    MD0100PA00X+082827Y+010232X0200Y    R180 S0      
317GND              VIA   -    MD0100PA00X+082827Y+010941X0200Y    R180 S0      
317GND              VIA   -    MD0100PA00X+082827Y+011650X0200Y    R180 S0      
317GND              VIA   -    MD0100PA00X+082027Y+010941X0200Y         S0      
317GND              VIA   -    MD0100PA00X+082027Y+011650X0200Y         S0      
317GND              VIA   -    MD0100PA00X+082014Y+010304X0200Y         S0      
317GND              VIA   -    MD0100PA00X+081981Y+005360X0200Y    R270 S0      
317GND              VIA   -    MD0100PA00X+084772Y+020676X0200Y         S0      
317GND              VIA   -    MD0100PA00X+084574Y+018462X0200Y         S0      
327GND              U62   -10         A01X+084861Y+018383X0090Y0240R090 S1      
317GND              VIA   -    MD0100PA00X+083924Y+019194X0200Y         S0      
327GND              C312  -2          A01X+084203Y+019194X0198Y0197R180 S1      
317GND              VIA   -    M      A01X+083911Y+018873X0200Y         S2      
017GND              VIA   -    M      A18X+083911Y+018873X0260Y         S2      
017GND                    -    MD0100PA00X+083911Y+018873                       
327GND              C319  -2          A01X+084211Y+018740X0198Y0197R090 S1      
317GND              VIA   -    MD0100PA00X+084808Y+013669X0200Y         S0      
317GND              VIA   -    MD0100PA00X+084808Y+012251X0200Y         S0      
317GND              VIA   -    MD0100PA00X+084808Y+013173X0200Y         S0      
317GND              VIA   -    MD0100PA00X+083768Y+012957X0200Y         S0      
317GND              VIA   -    MD0100PA00X+083768Y+012462X0200Y         S0      
317GND              VIA   -    MD0100PA00X+084267Y+012462X0200Y         S0      
317GND              VIA   -    MD0100PA00X+084267Y+012957X0200Y         S0      
317GND              VIA   -    MD0100PA00X+084483Y+010378X0200Y    R270 S0      
327GND              R432  -1          A01X+084483Y+010135X0198Y0197R270 S1      
317GND              VIA   -    MD0100PA00X+084267Y+011044X0200Y         S0      
317GND              VIA   -    MD0100PA00X+084267Y+011540X0200Y         S0      
317GND              VIA   -    MD0100PA00X+084808Y+011756X0200Y         S0      
317GND              VIA   -    MD0100PA00X+083768Y+011540X0200Y         S0      
317GND              VIA   -    MD0100PA00X+083768Y+011044X0200Y         S0      
317GND              VIA   -    MD0100PA00X+083728Y+010170X0200Y    R090 S0      
317GND              VIA   -    MD0100PA00X+083355Y+009402X0200Y         S0      
317GND              VIA   -    MD0100PA00X+084556Y+009402X0200Y         S0      
317GND              VIA   -    MD0100PA00X+083755Y+009402X0200Y         S0      
317GND              VIA   -    MD0100PA00X+084155Y+009402X0200Y         S0      
317GND              VIA   -    MD0100PA00X+083792Y+004477X0200Y    R270 S0      
317GND              VIA   -    MD0100PA00X+083792Y+002477X0200Y    R270 S0      
317GND              VIA   -    MD0100PA00X+083861Y+000537X0200Y    R270 S0      
317GND              VIA   -    MD0100PA00X+082353Y+046719X0200Y         S0      
317GND              VIA   -    MD0100PA00X+082626Y+045933X0200Y    R090 S0      
317GND              VIA   -    MD0100PA00X+082626Y+046233X0200Y    R090 S0      
317GND              VIA   -    MD0100PA00X+083957Y+032533X0200Y    R090 S0      
317GND              VIA   -    M      A01X+084799Y+029076X0200Y         S2      
017GND              VIA   -    M      A18X+084799Y+029076X0260Y         S2      
017GND                    -    MD0100PA00X+084799Y+029076                       
317GND              VIA   -    MD0100PA00X+083999Y+029076X0200Y         S0      
327GND              PC855 -2          A01X+083999Y+028806X0198Y0197R090 S1      
317GND              VIA   -    MD0100PA00X+084399Y+029076X0200Y         S0      
327GND              PR7069-2          A01X+084399Y+028806X0198Y0197R090 S1      
317GND              VIA   -    MD0100PA00X+083577Y+028569X0200Y         S0      
317GND              VIA   -    MD0100PA00X+083577Y+028819X0200Y         S0      
317GND              VIA   -    MD0100PA00X+083297Y+028569X0200Y         S0      
317GND              VIA   -    MD0100PA00X+083297Y+028819X0200Y         S0      
317GND              VIA   -    MD0100PA00X+083551Y+024889X0200Y    R180 S0      
317GND              VIA   -    MD0100PA00X+083801Y+024889X0200Y    R180 S0      
317GND              VIA   -    MD0100PA00X+084094Y+025654X0200Y         S0      
327GND              PC851 -2          A01X+084094Y+025954X0198Y0197R270 S1      
317GND              VIA   -    MD0100PA00X+084894Y+025654X0200Y         S0      
317GND              VIA   -    MD0100PA00X+083301Y+024889X0200Y    R180 S0      
317GND              VIA   -    MD0100PA00X+083733Y+023179X0200Y    R090 S0      
317GND              VIA   -    MD0100PA00X+083331Y+023661X0200Y    R180 S0      
317GND              VIA   -    MD0100PA00X+083831Y+023661X0200Y    R180 S0      
317GND              VIA   -    MD0100PA00X+083581Y+023661X0200Y    R180 S0      
317GND              VIA   -    M      A01X+083587Y+022614X0200Y         S2      
017GND              VIA   -    M      A18X+083587Y+022614X0260Y         S2      
017GND                    -    MD0100PA00X+083587Y+022614                       
317GND              VIA   -    MD0100PA00X+083307Y+022614X0200Y         S0      
317GND              VIA   -    MD0100PA00X+084102Y+022221X0200Y    R090 S0      
317GND              VIA   -    MD0100PA00X+084102Y+022471X0200Y    R090 S0      
317GND              VIA   -    MD0100PA00X+083733Y+022929X0200Y    R090 S0      
317GND              VIA   -    MD0100PA00X+085063Y+007614X0200Y         S0      
317GND              VIA   -    MD0100PA00X+085063Y+008014X0200Y         S0      
317GND              VIA   -    MD0100PA00X+085063Y+008414X0200Y         S0      
317GND              VIA   -    MD0100PA00X+085014Y+000300X0200Y    R270 S0      
317GND              VIA   -    MD0100PA00X+085793Y+040018X0200Y    R270 S0      
317GND              VIA   -    MD0100PA00X+086257Y+040487X0200Y    R270 S0      
317GND              VIA   -    MD0100PA00X+086252Y+040023X0200Y    R270 S0      
317GND              VIA   -    MD0100PA00X+085797Y+040487X0200Y    R270 S0      
327GND              U82   -TH  M      A01X+086025Y+040253X0670Y0670R090 S1      
317GND              VIA   -    MD0100PA00X+085859Y+038500X0200Y         S0      
327GND              R719  -2          A01X+085859Y+038742X0198Y0197R270 S1      
317GND              VIA   -    MD0100PA00X+085409Y+038500X0200Y         S0      
327GND              R718  -2          A01X+085409Y+038742X0198Y0197R270 S1      
317GND              VIA   -    MD0100PA00X+085462Y+035900X0200Y    R090 S0      
317GND              VIA   -    MD0100PA00X+086492Y+034317X0200Y         S0      
327GND              C2809 -2          A01X+086532Y+034045X0198Y0197     S1      
317GND              VIA   -    MD0100PA00X+085606Y+028834X0200Y    R090 S0      
317GND              VIA   -    MD0100PA00X+085856Y+028834X0200Y    R090 S0      
317GND              VIA   -    MD0100PA00X+085606Y+029084X0200Y    R090 S0      
317GND              VIA   -    MD0100PA00X+085606Y+029364X0200Y    R090 S0      
317GND              VIA   -    MD0100PA00X+085856Y+029084X0200Y    R090 S0      
317GND              VIA   -    MD0100PA00X+085856Y+029364X0200Y    R090 S0      
317GND              VIA   -    M      A01X+085407Y+028131X0200Y         S2      
017GND              VIA   -    M      A18X+085407Y+028131X0260Y         S2      
017GND                    -    MD0100PA00X+085407Y+028131                       
317GND              VIA   -    MD0100PA00X+084997Y+027921X0200Y         S0      
317GND              VIA   -    MD0100PA00X+085642Y+018512X0200Y         S0      
317GND              VIA   -    MD0100PA00X+085178Y+018516X0200Y         S0      
317GND              VIA   -    MD0100PA00X+086018Y+019242X0200Y         S0      
317GND              VIA   -    MD0100PA00X+085646Y+018053X0200Y         S0      
317GND              VIA   -    MD0100PA00X+085178Y+018057X0200Y         S0      
327GND              U62   -TH  M      A01X+085412Y+018285X0670Y0670R180 S1      
317GND              VIA   -    MD0100PA00X+085308Y+013669X0200Y         S0      
317GND              VIA   -    MD0100PA00X+085308Y+012251X0200Y         S0      
317GND              VIA   -    MD0100PA00X+085308Y+013173X0200Y         S0      
317GND              VIA   -    MD0100PA00X+085600Y+010362X0200Y    R090 S0      
327GND              U405  -S          A01X+085600Y+010792X0400Y0560R180 S1      
317GND              VIA   -    MD0100PA00X+085308Y+011756X0200Y         S0      
317GND              VIA   -    MD0100PA00X+086401Y+011726X0200Y         S0      
327GND              R6205 -1          A01X+086443Y+011449X0198Y0197R180 S1      
317GND              VIA   -    MD0100PA00X+085073Y+046138X0200Y         S0      
327GND              PC494 -2          A01X+084833Y+046138X0198Y0197     S1      
317GND              VIA   -    MD0100PA00X+085488Y+046879X0200Y    R270 S0      
317GND              VIA   -    MD0100PA00X+085488Y+046599X0200Y    R270 S0      
317GND              VIA   -    MD0100PA00X+086288Y+046599X0200Y    R270 S0      
317GND              VIA   -    MD0100PA00X+086288Y+046879X0200Y    R270 S0      
317GND              VIA   -    MD0100PA00X+086202Y+041090X0200Y    R270 S0      
327GND              U82   -10         A01X+086124Y+040804X0090Y0240     S1      
317GND              VIA   -    MD0100PA00X+087174Y+022186X0200Y         S0      
327GND              C2868 -2          A01X+086916Y+022186X0198Y0197     S1      
317GND              VIA   -    MD0100PA00X+087174Y+021686X0200Y         S0      
327GND              PC384 -2          A01X+086916Y+021686X0198Y0197     S1      
317GND              VIA   -    MD0100PA00X+087174Y+021286X0200Y         S0      
317GND              VIA   -    MD0100PA00X+087174Y+020086X0200Y         S0      
317GND              VIA   -    MD0100PA00X+087171Y+018066X0200Y         S0      
327GND              R586  -2          A01X+086907Y+018066X0198Y0197     S1      
317GND              VIA   -    MD0100PA00X+087171Y+017266X0200Y         S0      
327GND              R585  -2          A01X+086907Y+017266X0198Y0197     S1      
317GND              VIA   -    MD0100PA00X+086540Y+009195X0200Y         S0      
327GND              C2725 -1          A01X+086284Y+009195X0198Y0197R270 S1      
317GND              VIA   -    MD0100PA00X+087040Y+009674X0200Y         S0      
317GND              VIA   -    MD0100PA00X+086821Y+005551X0200Y         S0      
327GND              C2726 -1          A01X+086821Y+005801X0198Y0197R180 S1      
317GND              VIA   -    MD0100PA00X+087337Y+006092X0200Y         S0      
327GND              U133  -4          A01X+087307Y+006472X0240Y0460R180 S1      
317GND              VIA   -    MD0100PA00X+087088Y+046879X0200Y    R270 S0      
317GND              VIA   -    MD0100PA00X+087088Y+046599X0200Y    R270 S0      
317GND              VIA   -    MD0100PA00X+088091Y+046638X0200Y    R270 S0      
317GND              VIA   -    MD0100PA00X+088091Y+046918X0200Y    R270 S0      
317GND              VIA   -    MD0100PA00X+088091Y+047198X0200Y    R270 S0      
317GND              VIA   -    MD0100PA00X+086934Y+041740X0200Y    R270 S0      
327GND              C903  -2          A01X+086934Y+041462X0198Y0197R090 S1      
317GND              VIA   -    MD0100PA00X+086613Y+041753X0200Y    R270 S0      
327GND              C419  -2          A01X+086481Y+041453X0198Y0197     S1      
317GND              VIA   -    MD0100PA00X+087232Y+040859X0200Y    R270 S0      
317GND              VIA   -    MD0100PA00X+087274Y+038312X0200Y    R270 S0      
317GND              VIA   -    MD0100PA00X+087138Y+037397X0200Y    R090 S0      
317GND              VIA   -    MD0100PA00X+087373Y+035784X0200Y    R090 S0      
317GND              VIA   -    MD0100PA00X+087388Y+034089X0200Y    R090 S0      
327GND              R4266 -2          A01X+087251Y+033734X0198Y0197R180 S1      
317GND              VIA   -    MD0100PA00X+087625Y+030275X0200Y         S0      
317GND              VIA   -    MD0100PA00X+089702Y+042695X0200Y         S0      
317GND              VIA   -    MD0100PA00X+089202Y+042695X0200Y         S0      
317GND              VIA   -    MD0100PA00X+088710Y+043726X0200Y         S0      
317GND              VIA   -    MD0100PA00X+089639Y+043761X0200Y         S0      
317GND              VIA   -    MD0100PA00X+088960Y+043726X0200Y         S0      
317GND              VIA   -    MD0100PA00X+089452Y+042695X0200Y         S0      
317GND              VIA   -    MD0100PA00X+089734Y+041898X0200Y         S0      
317GND              VIA   -    MD0100PA00X+089170Y+042324X0200Y    R270 S0      
317GND              VIA   -    MD0100PA00X+089027Y+041529X0200Y         S0      
317GND              VIA   -    M      A01X+089170Y+042044X0200Y    R270 S2      
017GND              VIA   -    M      A18X+089170Y+042044X0260Y    R270 S2      
017GND                    -    MD0100PA00X+089170Y+042044                       
317GND              VIA   -    MD0100PA00X+088777Y+041529X0200Y         S0      
317GND              VIA   -    M      A01X+088922Y+042695X0200Y         S2      
017GND              VIA   -    M      A18X+088922Y+042695X0260Y         S2      
017GND                    -    MD0100PA00X+088922Y+042695                       
317GND              VIA   -    MD0100PA00X+089484Y+041898X0200Y         S0      
317GND              VIA   -    MD0100PA00X+088874Y+038312X0200Y    R270 S0      
327GND              PC469 -2          A01X+088874Y+038570X0198Y0197R270 S1      
317GND              VIA   -    MD0100PA00X+089374Y+038312X0200Y    R270 S0      
327GND              C2859 -2          A01X+089374Y+038570X0198Y0197R270 S1      
317GND              VIA   -    MD0100PA00X+088474Y+038312X0200Y    R270 S0      
317GND              VIA   -    MD0100PA00X+089659Y+037037X0200Y    R090 S0      
327GND              R5441 -2          A01X+089918Y+037037X0198Y0197R180 S1      
317GND              VIA   -    MD0100PA00X+089659Y+036637X0200Y    R090 S0      
327GND              R1021 -1          A01X+089918Y+036637X0198Y0197     S1      
317GND              VIA   -    MD0100PA00X+089659Y+036237X0200Y    R090 S0      
327GND              R1022 -2          A01X+089918Y+036237X0198Y0197R180 S1      
317GND              VIA   -    MD0100PA00X+088603Y+034658X0200Y    R090 S0      
317GND              VIA   -    MD0100PA00X+088574Y+026115X0200Y         S0      
317GND              VIA   -    MD0100PA00X+088626Y+025209X0200Y         S0      
317GND              VIA   -    MD0100PA00X+089578Y+023263X0200Y         S0      
317GND              VIA   -    MD0100PA00X+089578Y+023752X0200Y         S0      
317GND              VIA   -    MD0100PA00X+088601Y+015410X0200Y         S0      
327GND              R6088 -2          A01X+088601Y+015154X0198Y0197R180 S1      
317GND              VIA   -    MD0100PA00X+089090Y+046638X0200Y    R270 S0      
317GND              VIA   -    MD0100PA00X+089090Y+047198X0200Y    R270 S0      
317GND              VIA   -    MD0100PA00X+089090Y+046918X0200Y    R270 S0      
317GND              VIA   -    MD0100PA00X+091004Y+035353X0200Y    R090 S0      
327GND              C2618 -2          A18X+091266Y+035353X0198Y0197R090 S2      
317GND              VIA   -    MD0100PA00X+090512Y+030484X0200Y    R090 S0      
317GND              VIA   -    MD0100PA00X+091008Y+030484X0200Y    R090 S0      
317GND              VIA   -    MD0100PA00X+090185Y+031274X0200Y         S0      
327GND              U110  -3          A01X+090470Y+031262X0070Y0200R270 S1      
317GND              VIA   -    MD0100PA00X+090185Y+030778X0200Y         S0      
317GND              VIA   -    MD0100PA00X+089885Y+026693X0200Y         S0      
317GND              VIA   -    MD0100PA00X+091098Y+026693X0200Y         S0      
317GND              VIA   -    MD0100PA00X+089885Y+027402X0200Y         S0      
317GND              VIA   -    MD0100PA00X+091098Y+025748X0200Y         S0      
317GND              VIA   -    MD0100PA00X+091098Y+025276X0200Y         S0      
317GND              VIA   -    MD0100PA00X+089858Y+025306X0200Y         S0      
317GND              VIA   -    MD0100PA00X+089885Y+025984X0200Y         S0      
317GND              VIA   -    MD0100PA00X+091098Y+023858X0200Y         S0      
317GND              VIA   -    MD0100PA00X+089885Y+024567X0200Y         S0      
317GND              VIA   -    MD0100PA00X+089885Y+023858X0200Y         S0      
317GND              VIA   -    MD0100PA00X+089885Y+023150X0200Y         S0      
317GND              VIA   -    MD0100PA00X+089772Y+015237X0200Y         S0      
327GND              Q224  -1          A01X+089473Y+015237X0240Y0240R270 S1      
317GND              VIA   -    MD0100PA00X+089881Y+014646X0200Y         S0      
327GND              Q224  -4          A01X+090182Y+014646X0240Y0240R270 S1      
317GND              VIA   -    MD0100PA00X+091078Y+047138X0200Y    R270 S0      
317GND              VIA   -    MD0100PA00X+090717Y+044308X0200Y    R180 S0      
327GND              PC627 -2   M      A01X+090717Y+044560X0198Y0197R270 S1      
317GND              VIA   -    MD0100PA00X+089889Y+043761X0200Y         S0      
317GND              VIA   -    MD0100PA00X+090717Y+044058X0200Y    R180 S0      
317GND              VIA   -    MD0100PA00X+090771Y+043673X0200Y    R180 S0      
317GND              VIA   -    MD0100PA00X+090271Y+043673X0200Y    R180 S0      
317GND              VIA   -    MD0100PA00X+090521Y+043673X0200Y    R180 S0      
317GND              VIA   -    MD0100PA00X+090759Y+042458X0200Y    R180 S0      
317GND              VIA   -    MD0100PA00X+090259Y+042458X0200Y    R180 S0      
317GND              VIA   -    MD0100PA00X+090509Y+042458X0200Y    R180 S0      
317GND              VIA   -    MD0100PA00X+090217Y+041550X0200Y    R090 S0      
317GND              VIA   -    MD0100PA00X+090217Y+041800X0200Y    R090 S0      
317GND              VIA   -    MD0100PA00X+090217Y+041300X0200Y    R090 S0      
317GND              VIA   -    MD0100PA00X+091973Y+027458X0200Y    R180 S0      
317GND              VIA   -    MD0100PA00X+091958Y+025512X0200Y    R180 S0      
317GND              VIA   -    MD0100PA00X+091958Y+025984X0200Y    R180 S0      
317GND              VIA   -    MD0100PA00X+091968Y+023692X0200Y    R180 S0      
317GND              VIA   -    MD0100PA00X+091958Y+023386X0200Y    R180 S0      
317GND              VIA   -    MD0100PA00X+091958Y+024567X0200Y    R180 S0      
317GND              VIA   -    MD0100PA00X+091961Y+023100X0200Y    R180 S0      
317GND              VIA   -    MD0100PA00X+092998Y+018405X0200Y    R090 S0      
317GND              VIA   -    MD0100PA00X+092772Y+018856X0200Y    R180 S0      
317GND              VIA   -    M      A01X+092998Y+018685X0200Y    R090 S2      
017GND              VIA   -    M      A18X+092998Y+018685X0260Y    R090 S2      
017GND                    -    MD0100PA00X+092998Y+018685                       
317GND              VIA   -    MD0100PA00X+092522Y+018856X0200Y    R180 S0      
317GND              VIA   -    MD0100PA00X+092786Y+018035X0200Y    R180 S0      
317GND              VIA   -    MD0100PA00X+092536Y+018035X0200Y    R180 S0      
317GND              VIA   -    MD0100PA00X+092356Y+013458X0200Y         S0      
327GND              U391  -3          A01X+092045Y+013674X0240Y0240     S1      
317GND              VIA   -    MD0100PA00X+092942Y+013330X0200Y         S0      
327GND              PC940 -2          A01X+092942Y+013090X0198Y0197R090 S1      
317GND              VIA   -    MD0100PA00X+092142Y+013330X0200Y         S0      
327GND              PC945 -2          A01X+092142Y+013090X0198Y0197R090 S1      
317GND              VIA   -    MD0100PA00X+092739Y+010225X0200Y    R180 S0      
327GND              PR7115-2   M      A01X+092739Y+010475X0198Y0197R270 S1      
317GND              VIA   -    MD0100PA00X+092339Y+010225X0200Y    R180 S0      
327GND              PR7116-2   M      A01X+092339Y+010475X0198Y0197R270 S1      
317GND              VIA   -    MD0100PA00X+092182Y+011078X0200Y         S0      
327GND              PU127 -3   M      A01X+092316Y+011368X0100Y0280     S1      
317GND              VIA   -    MD0100PA00X+091918Y+011339X0200Y         S0      
317GND              VIA   -    M      A01X+093139Y+010225X0200Y    R180 S2      
017GND              VIA   -    M      A18X+093139Y+010225X0260Y    R180 S2      
017GND                    -    MD0100PA00X+093139Y+010225                       
317GND              VIA   -    MD0100PA00X+093014Y+000300X0200Y    R270 S0      
317GND              VIA   -    MD0100PA00X+094496Y+013067X0200Y         S0      
317GND              VIA   -    MD0100PA00X+094016Y+013067X0200Y         S0      
317GND              VIA   -    MD0100PA00X+094496Y+012358X0200Y         S0      
317GND              VIA   -    MD0100PA00X+094016Y+012358X0200Y         S0      
317GND              VIA   -    MD0100PA00X+094016Y+011650X0200Y         S0      
317GND              VIA   -    MD0100PA00X+093741Y+010917X0200Y         S0      
317GND              VIA   -    MD0100PA00X+093642Y+010650X0200Y         S0      
327GND              C2771 -2   M      A01X+093901Y+010650X0198Y0197R180 S1      
317GND              VIA   -    MD0100PA00X+093441Y+010917X0200Y         S0      
317GND              VIA   -    MD0100PA00X+094496Y+011650X0200Y         S0      
317GND              VIA   -    MD0100PA00X+094249Y+004477X0200Y    R270 S0      
317GND              VIA   -    MD0100PA00X+094249Y+002477X0200Y    R270 S0      
317GND              VIA   -    MD0100PA00X+094113Y+000447X0200Y    R270 S0      
317GND              VIA   -    MD0100PA00X+092905Y+045032X0200Y    R270 S0      
327GND              PU74  -2          A01X+092451Y+045054X0100Y0320R090 S1      
317GND              VIA   -    MD0100PA00X+092764Y+045250X0200Y    R270 S0      
327GND              PU74  -3          A01X+092451Y+045250X0100Y0320R090 S1      
317GND              VIA   -    MD0100PA00X+091420Y+041550X0200Y    R090 S0      
317GND              VIA   -    MD0100PA00X+091420Y+041300X0200Y    R090 S0      
317GND              VIA   -    MD0100PA00X+091420Y+041800X0200Y    R090 S0      
317GND              VIA   -    MD0100PA00X+092307Y+038699X0200Y    R090 S0      
327GND              R5439 -2          A01X+092307Y+038448X0198Y0197R090 S1      
317GND              VIA   -    MD0100PA00X+091907Y+038699X0200Y    R090 S0      
327GND              R1007 -2          A01X+091907Y+038448X0198Y0197R090 S1      
317GND              VIA   -    MD0100PA00X+092707Y+038699X0200Y    R090 S0      
327GND              C2624 -2          A01X+092707Y+038448X0198Y0197R090 S1      
317GND              VIA   -    MD0100PA00X+091540Y+036921X0200Y    R090 S0      
317GND              VIA   -    MD0100PA00X+092147Y+036921X0200Y    R090 S0      
317GND              VIA   -    MD0100PA00X+092731Y+036921X0200Y    R090 S0      
317GND              VIA   -    MD0100PA00X+092731Y+036324X0200Y    R090 S0      
317GND              VIA   -    MD0100PA00X+091540Y+036321X0200Y    R090 S0      
317GND              VIA   -    MD0100PA00X+091540Y+035727X0200Y    R090 S0      
317GND              VIA   -    MD0100PA00X+092139Y+035727X0200Y    R090 S0      
317GND              VIA   -    MD0100PA00X+092731Y+035727X0200Y    R090 S0      
327GND              U112  -TH  M      A01X+092134Y+036325X1400Y1400R090 S1      
317GND              VIA   -    MD0100PA00X+092014Y+030850X0200Y         S0      
327GND              C2612 -2          A18X+092005Y+031223X0198Y0197R180 S2      
327GND              R1003 -2          A01X+092014Y+031098X0198Y0197     S1      
317GND              VIA   -    MD0100PA00X+091279Y+030670X0200Y         S0      
317GND              VIA   -    MD0100PA00X+094746Y+010941X0200Y         S0      
317GND              VIA   -    MD0100PA00X+095216Y+010232X0200Y         S0      
317GND              VIA   -    MD0100PA00X+095216Y+010941X0200Y         S0      
317GND              VIA   -    MD0100PA00X+095216Y+011650X0200Y         S0      
317GND              VIA   -    MD0100PA00X+094746Y+011650X0200Y         S0      
317GND              VIA   -    MD0100PA00X+096041Y+011650X0200Y    R180 S0      
317GND              VIA   -    MD0100PA00X+096041Y+010941X0200Y    R180 S0      
317GND              VIA   -    MD0100PA00X+096016Y+010232X0200Y    R180 S0      
317GND              VIA   -    MD0100PA00X+096062Y+008558X0200Y         S0      
317GND              VIA   -    MD0100PA00X+096062Y+007518X0200Y         S0      
317GND              VIA   -    MD0100PA00X+096062Y+008038X0200Y         S0      
317GND              VIA   -    MD0100PA00X+096062Y+007778X0200Y         S0      
317GND              VIA   -    MD0100PA00X+096062Y+008298X0200Y         S0      
317GND              VIA   -    MD0100PA00X+094981Y+005360X0200Y    R270 S0      
317GND              VIA   -    MD0100PA00X+094150Y+046344X0200Y    R180 S0      
327GND              PC633 -2   M      A01X+093907Y+046344X0198Y0197     S1      
317GND              VIA   -    MD0100PA00X+094490Y+036370X0200Y    R090 S0      
317GND              VIA   -    MD0100PA00X+094840Y+037004X0200Y    R090 S0      
317GND              VIA   -    MD0100PA00X+094366Y+035567X0200Y    R090 S0      
317GND              VIA   -    MD0100PA00X+094606Y+025300X0200Y    R090 S0      
317GND              VIA   -    MD0100PA00X+094016Y+024571X0200Y    R090 S0      
327GND              Q204  -1          A01X+094016Y+024272X0240Y0240     S1      
317GND              VIA   -    MD0100PA00X+093637Y+022129X0200Y    R090 S0      
327GND              PC553 -2          A01X+093893Y+022129X0198Y0197R090 S1      
317GND              VIA   -    MD0100PA00X+094280Y+022386X0200Y    R090 S0      
327GND              PR273 -2          A01X+094280Y+022128X0198Y0197R090 S1      
317GND              VIA   -    MD0100PA00X+093812Y+023089X0200Y    R090 S0      
327GND              PR7079-2          A01X+093812Y+023367X0198Y0197R270 S1      
317GND              VIA   -    MD0100PA00X+093391Y+019201X0200Y    R180 S0      
317GND              VIA   -    MD0100PA00X+093141Y+019201X0200Y    R180 S0      
317GND              VIA   -    M      A01X+093316Y+018035X0200Y    R180 S2      
017GND              VIA   -    M      A18X+093316Y+018035X0260Y    R180 S2      
017GND                    -    MD0100PA00X+093316Y+018035                       
317GND              VIA   -    MD0100PA00X+093036Y+018035X0200Y    R180 S0      
317GND              VIA   -    MD0100PA00X+094094Y+015085X0200Y         S0      
327GND              U371  -S          A01X+093700Y+015330X0400Y0560     S1      
317GND              VIA   -    MD0100PA00X+093806Y+014123X0200Y         S0      
327GND              R5687 -2          A01X+093659Y+013884X0198Y0197     S1      
317GND              VIA   -    MD0100PA00X+093615Y+014601X0200Y         S0      
327GND              C3675 -2          A01X+093365Y+014601X0198Y0197R090 S1      
317GND              VIA   -    MD0100PA00X+094496Y+013776X0200Y         S0      
317GND              VIA   -    MD0100PA00X+094016Y+013776X0200Y         S0      
317GND              VIA   -    MD0100PA00X+097715Y+032847X0200Y    R180 S0      
327GND              R1062 -1          A01X+097955Y+032847X0198Y0197     S1      
317GND              VIA   -    MD0100PA00X+097215Y+032368X0200Y         S0      
317GND              VIA   -    MD0100PA00X+097676Y+030730X0200Y    R270 S0      
317GND              VIA   -    MD0100PA00X+097245Y+029380X0200Y         S0      
317GND              VIA   -    MD0100PA00X+097495Y+029380X0200Y         S0      
317GND              VIA   -    MD0100PA00X+096891Y+022623X0200Y    R090 S0      
317GND              VIA   -    M      A01X+097936Y+022366X0200Y    R090 S2      
017GND              VIA   -    M      A18X+097936Y+022366X0260Y    R090 S2      
017GND                    -    MD0100PA00X+097936Y+022366                       
317GND              VIA   -    MD0100PA00X+096891Y+023123X0200Y    R090 S0      
317GND              VIA   -    MD0100PA00X+096891Y+022873X0200Y    R090 S0      
317GND              VIA   -    MD0100PA00X+096891Y+022373X0200Y    R090 S0      
317GND              VIA   -    MD0100PA00X+097827Y+013776X0200Y    R180 S0      
317GND              VIA   -    MD0100PA00X+096635Y+013776X0200Y         S0      
317GND              VIA   -    MD0100PA00X+096336Y+012146X0200Y    R180 S0      
317GND              VIA   -    MD0100PA00X+097827Y+012358X0200Y    R180 S0      
317GND              VIA   -    MD0100PA00X+097827Y+013067X0200Y    R180 S0      
317GND              VIA   -    MD0100PA00X+097027Y+012358X0200Y         S0      
317GND              VIA   -    MD0100PA00X+097027Y+013067X0200Y         S0      
317GND              VIA   -    MD0100PA00X+097827Y+011650X0200Y    R180 S0      
317GND              VIA   -    MD0100PA00X+097027Y+010941X0200Y         S0      
317GND              VIA   -    MD0100PA00X+097027Y+011650X0200Y         S0      
317GND              VIA   -    MD0100PA00X+097014Y+010304X0200Y         S0      
317GND              VIA   -    MD0100PA00X+097827Y+010232X0200Y    R180 S0      
317GND              VIA   -    MD0100PA00X+097827Y+010941X0200Y    R180 S0      
317GND              VIA   -    MD0100PA00X+096318Y+009285X0200Y         S0      
317GND              VIA   -    MD0100PA00X+096981Y+005360X0200Y    R270 S0      
317GND              VIA   -    MD0100PA00X+095032Y+046485X0200Y    R180 S0      
317GND              VIA   -    MD0100PA00X+095686Y+045147X0200Y         S0      
327GND              Q216  -4          A01X+095686Y+045438X0240Y0240R180 S1      
317GND              VIA   -    MD0100PA00X+095489Y+036951X0200Y    R090 S0      
317GND              VIA   -    MD0100PA00X+095217Y+035613X0200Y    R090 S0      
317GND              VIA   -    MD0100PA00X+095882Y+036280X0200Y    R090 S0      
317GND              VIA   -    MD0100PA00X+095635Y+035637X0200Y    R090 S0      
317GND              VIA   -    MD0100PA00X+095104Y+022388X0200Y    R090 S0      
327GND              PC554 -2          A01X+095104Y+022130X0198Y0197R090 S1      
317GND              VIA   -    MD0100PA00X+094944Y+020821X0200Y         S0      
327GND              C2893 -2          A18X+093743Y+020515X0198Y0197R090 S2      
317GND              VIA   -    MD0100PA00X+094936Y+019871X0200Y    R090 S0      
317GND              VIA   -    MD0100PA00X+095216Y+013776X0200Y         S0      
317GND              VIA   -    MD0100PA00X+096163Y+013776X0200Y    R180 S0      
317GND              VIA   -    MD0100PA00X+094746Y+012358X0200Y         S0      
317GND              VIA   -    MD0100PA00X+095216Y+012358X0200Y         S0      
317GND              VIA   -    MD0100PA00X+095216Y+013067X0200Y         S0      
317GND              VIA   -    MD0100PA00X+094746Y+013067X0200Y         S0      
317GND              VIA   -    MD0100PA00X+096164Y+013067X0200Y    R180 S0      
317GND              VIA   -    MD0100PA00X+098560Y+015154X0200Y         S0      
327GND              R6089 -2          A01X+098837Y+015154X0198Y0197R180 S1      
317GND              VIA   -    MD0100PA00X+099267Y+012957X0200Y         S0      
317GND              VIA   -    MD0100PA00X+098768Y+012957X0200Y         S0      
317GND              VIA   -    MD0100PA00X+098768Y+012462X0200Y         S0      
317GND              VIA   -    MD0100PA00X+099267Y+012462X0200Y         S0      
317GND              VIA   -    MD0100PA00X+099483Y+010378X0200Y    R270 S0      
317GND              VIA   -    MD0100PA00X+098768Y+011044X0200Y         S0      
317GND              VIA   -    MD0100PA00X+099267Y+011044X0200Y         S0      
317GND              VIA   -    MD0100PA00X+099267Y+011540X0200Y         S0      
317GND              VIA   -    MD0100PA00X+098768Y+011540X0200Y         S0      
317GND              VIA   -    MD0100PA00X+098728Y+010170X0200Y    R090 S0      
317GND              VIA   -    MD0100PA00X+099155Y+009402X0200Y         S0      
317GND              VIA   -    MD0100PA00X+098755Y+009402X0200Y         S0      
317GND              VIA   -    MD0100PA00X+098355Y+009402X0200Y         S0      
317GND              VIA   -    MD0100PA00X+098792Y+004477X0200Y    R270 S0      
317GND              VIA   -    MD0100PA00X+098792Y+002477X0200Y    R270 S0      
317GND              VIA   -    MD0100PA00X+098861Y+000537X0200Y    R270 S0      
317GND              VIA   -    MD0100PA00X+096911Y+044935X0200Y         S0      
327GND              PC899 -2          A01X+096911Y+045176X0198Y0197R270 S1      
317GND              VIA   -    MD0100PA00X+097370Y+044887X0200Y         S0      
327GND              PU119 -3          A01X+097536Y+045156X0100Y0280     S1      
317GND              VIA   -    MD0100PA00X+096277Y+045847X0200Y         S0      
327GND              Q216  -1          A01X+096277Y+046146X0240Y0240R180 S1      
317GND              VIA   -    MD0100PA00X+097193Y+043751X0200Y         S0      
327GND              PR7100-2          A01X+097193Y+043992X0198Y0197R270 S1      
317GND              VIA   -    MD0100PA00X+097593Y+043751X0200Y         S0      
327GND              PR7099-2          A01X+097593Y+043992X0198Y0197R270 S1      
317GND              VIA   -    MD0100PA00X+096358Y+042639X0200Y    R270 S0      
317GND              VIA   -    MD0100PA00X+096962Y+040561X0200Y    R270 S0      
317GND              VIA   -    MD0100PA00X+097715Y+033547X0200Y    R180 S0      
327GND              R1061 -1          A01X+097955Y+033547X0198Y0197     S1      
317GND              VIA   -    MD0100PA00X+097334Y+034502X0200Y    R090 S0      
317GND              VIA   -    MD0100PA00X+100063Y+008014X0200Y         S0      
317GND              VIA   -    MD0100PA00X+100063Y+007614X0200Y         S0      
317GND              VIA   -    MD0100PA00X+100063Y+008414X0200Y         S0      
317GND              VIA   -    MD0100PA00X+100751Y+000300X0200Y    R270 S0      
317GND              VIA   -    MD0100PA00X+098267Y+045020X0200Y         S0      
317GND              VIA   -    MD0100PA00X+098279Y+044727X0200Y         S0      
317GND              VIA   -    MD0100PA00X+097993Y+043751X0200Y         S0      
327GND              PC904 -2          A01X+097993Y+043992X0198Y0197R270 S1      
317GND              VIA   -    MD0100PA00X+098804Y+036656X0200Y    R090 S0      
327GND              R1070 -1          A01X+098804Y+036416X0198Y0197R270 S1      
317GND              VIA   -    MD0100PA00X+098404Y+036656X0200Y    R090 S0      
327GND              C2652 -2          A01X+098404Y+036416X0198Y0197R090 S1      
317GND              VIA   -    MD0100PA00X+099204Y+036656X0200Y    R090 S0      
327GND              R1066 -1   M      A01X+099204Y+036416X0198Y0197R270 S1      
317GND              VIA   -    MD0100PA00X+099342Y+033795X0200Y    R270 S0      
327GND              C2650 -2          A18X+099702Y+033695X0280Y0320R090 S2      
317GND              VIA   -    MD0100PA00X+099392Y+033545X0200Y    R270 S0      
327GND              C2638 -2          A18X+099492Y+033185X0280Y0320     S2      
317GND              VIA   -    MD0100PA00X+098706Y+032027X0200Y    R270 S0      
317GND              VIA   -    MD0100PA00X+099324Y+032132X0200Y    R270 S0      
317GND              VIA   -    MD0100PA00X+099313Y+031094X0200Y    R270 S0      
317GND              VIA   -    MD0100PA00X+098999Y+029076X0200Y         S0      
327GND              PC860 -2          A01X+098999Y+028806X0198Y0197R090 S1      
317GND              VIA   -    MD0100PA00X+099399Y+029076X0200Y         S0      
327GND              PR7075-2          A01X+099399Y+028806X0198Y0197R090 S1      
317GND              VIA   -    MD0100PA00X+098047Y+028569X0200Y         S0      
317GND              VIA   -    MD0100PA00X+098047Y+028819X0200Y         S0      
317GND              VIA   -    MD0100PA00X+098297Y+028569X0200Y         S0      
317GND              VIA   -    MD0100PA00X+098577Y+028569X0200Y         S0      
317GND              VIA   -    MD0100PA00X+098297Y+028819X0200Y         S0      
317GND              VIA   -    MD0100PA00X+098577Y+028819X0200Y         S0      
317GND              VIA   -    MD0100PA00X+099094Y+025654X0200Y         S0      
327GND              PC865 -2          A01X+099094Y+025954X0198Y0197R270 S1      
317GND              VIA   -    MD0100PA00X+098551Y+024889X0200Y    R180 S0      
317GND              VIA   -    MD0100PA00X+098801Y+024889X0200Y    R180 S0      
317GND              VIA   -    MD0100PA00X+098301Y+024889X0200Y    R180 S0      
317GND              VIA   -    MD0100PA00X+098331Y+023661X0200Y    R180 S0      
317GND              VIA   -    MD0100PA00X+098831Y+023661X0200Y    R180 S0      
317GND              VIA   -    MD0100PA00X+098581Y+023661X0200Y    R180 S0      
317GND              VIA   -    MD0100PA00X+098733Y+023179X0200Y    R090 S0      
317GND              VIA   -    MD0100PA00X+097936Y+022646X0200Y    R090 S0      
317GND              VIA   -    MD0100PA00X+097936Y+022896X0200Y    R090 S0      
317GND              VIA   -    MD0100PA00X+097936Y+023146X0200Y    R090 S0      
317GND              VIA   -    M      A01X+098587Y+022614X0200Y         S2      
017GND              VIA   -    M      A18X+098587Y+022614X0260Y         S2      
017GND                    -    MD0100PA00X+098587Y+022614                       
317GND              VIA   -    MD0100PA00X+098307Y+022614X0200Y         S0      
317GND              VIA   -    MD0100PA00X+099102Y+022221X0200Y    R090 S0      
317GND              VIA   -    MD0100PA00X+099102Y+022471X0200Y    R090 S0      
317GND              VIA   -    MD0100PA00X+098733Y+022929X0200Y    R090 S0      
317GND              VIA   -    M      A01X+098911Y+018873X0200Y         S2      
017GND              VIA   -    M      A18X+098911Y+018873X0260Y         S2      
017GND                    -    MD0100PA00X+098911Y+018873                       
327GND              C322  -2          A01X+099211Y+018740X0198Y0197R090 S1      
317GND              VIA   -    MD0100PA00X+098924Y+019194X0200Y         S0      
327GND              C321  -2          A01X+099203Y+019194X0198Y0197R180 S1      
317GND              VIA   -    MD0100PA00X+100864Y+030028X0200Y    R270 S0      
327GND              R1065 -1          A01X+100864Y+030268X0198Y0197R090 S1      
317GND              VIA   -    MD0100PA00X+100464Y+030028X0200Y    R270 S0      
327GND              R1068 -1          A01X+100464Y+030268X0198Y0197R090 S1      
317GND              VIA   -    M      A01X+099799Y+029076X0200Y         S2      
017GND              VIA   -    M      A18X+099799Y+029076X0260Y         S2      
017GND                    -    MD0100PA00X+099799Y+029076                       
317GND              VIA   -    MD0100PA00X+100856Y+028834X0200Y    R090 S0      
317GND              VIA   -    MD0100PA00X+100856Y+029084X0200Y    R090 S0      
317GND              VIA   -    MD0100PA00X+100606Y+028834X0200Y    R090 S0      
317GND              VIA   -    MD0100PA00X+100606Y+029084X0200Y    R090 S0      
317GND              VIA   -    MD0100PA00X+100606Y+029364X0200Y    R090 S0      
317GND              VIA   -    MD0100PA00X+100856Y+029364X0200Y    R090 S0      
317GND              VIA   -    M      A01X+100406Y+028081X0200Y         S2      
017GND              VIA   -    M      A18X+100406Y+028081X0260Y         S2      
017GND                    -    MD0100PA00X+100406Y+028081                       
317GND              VIA   -    MD0100PA00X+099983Y+027873X0200Y         S0      
317GND              VIA   -    MD0100PA00X+099894Y+025654X0200Y         S0      
327GND              PC866 -2          A01X+099894Y+025954X0198Y0197R270 S1      
317GND              VIA   -    MD0100PA00X+099772Y+020676X0200Y         S0      
317GND              VIA   -    MD0100PA00X+099574Y+018462X0200Y         S0      
327GND              U71   -10         A01X+099861Y+018383X0090Y0240R090 S1      
317GND              VIA   -    MD0100PA00X+100642Y+018512X0200Y         S0      
317GND              VIA   -    MD0100PA00X+100178Y+018516X0200Y         S0      
317GND              VIA   -    MD0100PA00X+101018Y+019242X0200Y         S0      
317GND              VIA   -    MD0100PA00X+100646Y+018053X0200Y         S0      
317GND              VIA   -    MD0100PA00X+100178Y+018057X0200Y         S0      
327GND              U71   -TH  M      A01X+100412Y+018285X0670Y0670R180 S1      
317GND              VIA   -    MD0100PA00X+100008Y+015237X0200Y         S0      
327GND              Q225  -1          A01X+099709Y+015237X0240Y0240R270 S1      
317GND              VIA   -    MD0100PA00X+099808Y+013669X0200Y         S0      
317GND              VIA   -    MD0100PA00X+100308Y+013669X0200Y         S0      
317GND              VIA   -    MD0100PA00X+100118Y+014646X0200Y         S0      
327GND              Q225  -4          A01X+100418Y+014646X0240Y0240R270 S1      
317GND              VIA   -    MD0100PA00X+099808Y+013173X0200Y         S0      
317GND              VIA   -    MD0100PA00X+099808Y+012251X0200Y         S0      
317GND              VIA   -    MD0100PA00X+100308Y+013173X0200Y         S0      
317GND              VIA   -    MD0100PA00X+100308Y+012251X0200Y         S0      
317GND              VIA   -    MD0100PA00X+099808Y+011756X0200Y         S0      
317GND              VIA   -    MD0100PA00X+100308Y+011756X0200Y         S0      
317GND              VIA   -    MD0100PA00X+100600Y+010362X0200Y    R090 S0      
327GND              U412  -S          A01X+100600Y+010792X0400Y0560R180 S1      
317GND              VIA   -    MD0100PA00X+099556Y+009402X0200Y         S0      
317GND              VIA   -    MD0100PA00X+102350Y+025237X0200Y         S0      
327GND              PR7080-2          A01X+102628Y+025237X0198Y0197R180 S1      
317GND              VIA   -    MD0100PA00X+102174Y+021686X0200Y         S0      
327GND              PC408 -2          A01X+101916Y+021686X0198Y0197     S1      
317GND              VIA   -    MD0100PA00X+102174Y+022186X0200Y         S0      
327GND              C2869 -2   M      A01X+101916Y+022186X0198Y0197     S1      
317GND              VIA   -    MD0100PA00X+102174Y+020086X0200Y         S0      
317GND              VIA   -    MD0100PA00X+102174Y+021286X0200Y         S0      
317GND              VIA   -    MD0100PA00X+102692Y+020339X0200Y         S0      
317GND              VIA   -    MD0100PA00X+102706Y+019518X0200Y    R180 S0      
317GND              VIA   -    MD0100PA00X+102171Y+017266X0200Y         S0      
327GND              R597  -2          A01X+101907Y+017266X0198Y0197     S1      
317GND              VIA   -    MD0100PA00X+102171Y+018066X0200Y         S0      
327GND              R598  -2          A01X+101907Y+018066X0198Y0197     S1      
317GND              VIA   -    MD0100PA00X+102593Y+013458X0200Y         S0      
327GND              U390  -3          A01X+102282Y+013674X0240Y0240     S1      
317GND              VIA   -    MD0100PA00X+102429Y+013090X0200Y         S0      
327GND              PC947 -2          A01X+102178Y+013090X0198Y0197R090 S1      
317GND              VIA   -    MD0100PA00X+102419Y+011078X0200Y         S0      
327GND              PU128 -3   M      A01X+102552Y+011368X0100Y0280     S1      
317GND              VIA   -    MD0100PA00X+102576Y+010225X0200Y    R180 S0      
327GND              PR7118-2   M      A01X+102576Y+010475X0198Y0197R270 S1      
317GND              VIA   -    MD0100PA00X+102154Y+011339X0200Y         S0      
317GND              VIA   -    MD0100PA00X+101401Y+011726X0200Y         S0      
327GND              R6206 -1          A01X+101443Y+011449X0198Y0197R180 S1      
317GND              VIA   -    MD0100PA00X+101540Y+009195X0200Y    R180 S0      
327GND              C2727 -1          A01X+101284Y+009195X0198Y0197R270 S1      
317GND              VIA   -    MD0100PA00X+102025Y+009707X0200Y         S0      
317GND              VIA   -    MD0100PA00X+101821Y+005551X0200Y         S0      
327GND              C2728 -1          A01X+101821Y+005801X0198Y0197R180 S1      
317GND              VIA   -    MD0100PA00X+102337Y+006092X0200Y         S0      
327GND              U134  -4          A01X+102307Y+006472X0240Y0460R180 S1      
317GND              VIA   -    MD0100PA00X+102751Y+000300X0200Y    R270 S0      
327GND              R1067 -1          A01X+099604Y+036416X0198Y0197R270 S1      
317GND              VIA   -    MD0100PA00X+100042Y+034895X0200Y    R270 S0      
327GND              C2642 -2          A18X+100352Y+034895X0280Y0320R090 S2      
317GND              VIA   -    MD0100PA00X+099792Y+033365X0200Y         S0      
327GND              C2640 -2          A18X+099968Y+033098X0198Y0197R270 S2      
317GND              VIA   -    MD0100PA00X+100493Y+031454X0200Y         S0      
327GND              C2634 -2   M      A18X+100912Y+031639X0280Y0320R090 S2      
317GND              VIA   -    MD0100PA00X+100454Y+031805X0200Y         S0      
327GND              U113  -A14 M      A01X+100709Y+031912X0070Y0220R090 S1      
317GND              VIA   -    MD0100PA00X+099867Y+032224X0200Y    R270 S0      
317GND              VIA   -    MD0100PA00X+103135Y+032290X0200Y    R270 S0      
317GND              VIA   -    MD0100PA00X+104150Y+030028X0200Y    R270 S0      
327GND              R1059 -1          A01X+104150Y+030268X0198Y0197R090 S1      
317GND              VIA   -    MD0100PA00X+103311Y+029879X0200Y    R090 S0      
317GND              VIA   -    MD0100PA00X+103807Y+029879X0200Y    R090 S0      
317GND              VIA   -    MD0100PA00X+103798Y+025320X0200Y         S0      
327GND              Q205  -1          A01X+103500Y+025320X0240Y0240R270 S1      
317GND              VIA   -    MD0100PA00X+103510Y+023859X0200Y    R090 S0      
327GND              C2895 -2          A01X+103510Y+023601X0198Y0197R090 S1      
317GND              VIA   -    MD0100PA00X+103806Y+023612X0200Y    R090 S0      
327GND              PC552 -2          A01X+104063Y+023612X0198Y0197R090 S1      
317GND              VIA   -    M      A01X+103167Y+020168X0200Y    R090 S2      
017GND              VIA   -    M      A18X+103167Y+020168X0260Y    R090 S2      
017GND                    -    MD0100PA00X+103167Y+020168                       
317GND              VIA   -    MD0100PA00X+102942Y+020339X0200Y    R180 S0      
317GND              VIA   -    MD0100PA00X+103560Y+020684X0200Y    R180 S0      
317GND              VIA   -    MD0100PA00X+103310Y+020684X0200Y    R180 S0      
317GND              VIA   -    M      A01X+103486Y+019518X0200Y    R180 S2      
017GND              VIA   -    M      A18X+103486Y+019518X0260Y    R180 S2      
017GND                    -    MD0100PA00X+103486Y+019518                       
317GND              VIA   -    MD0100PA00X+102956Y+019518X0200Y    R180 S0      
317GND              VIA   -    MD0100PA00X+103167Y+019888X0200Y    R090 S0      
317GND              VIA   -    MD0100PA00X+103206Y+019518X0200Y    R180 S0      
317GND              VIA   -    MD0100PA00X+104331Y+015085X0200Y         S0      
317GND              VIA   -    MD0100PA00X+104252Y+013776X0200Y         S0      
317GND              VIA   -    MD0100PA00X+104042Y+014123X0200Y         S0      
327GND              R5684 -2          A01X+103895Y+013884X0198Y0197     S1      
317GND              VIA   -    MD0100PA00X+103851Y+014601X0200Y         S0      
327GND              C3669 -2          A01X+103601Y+014601X0198Y0197R090 S1      
317GND              VIA   -    MD0100PA00X+104252Y+012358X0200Y         S0      
317GND              VIA   -    MD0100PA00X+104252Y+013067X0200Y         S0      
317GND              VIA   -    MD0100PA00X+103178Y+013330X0200Y         S0      
327GND              PC942 -2          A01X+103178Y+013090X0198Y0197R090 S1      
317GND              VIA   -    MD0100PA00X+104252Y+011650X0200Y         S0      
317GND              VIA   -    MD0100PA00X+102976Y+010225X0200Y    R180 S0      
327GND              PR7117-2   M      A01X+102976Y+010475X0198Y0197R270 S1      
317GND              VIA   -    MD0100PA00X+103878Y+010650X0200Y         S0      
327GND              C2772 -2   M      A01X+104137Y+010650X0198Y0197R180 S1      
317GND              VIA   -    MD0100PA00X+103977Y+010917X0200Y         S0      
317GND              VIA   -    MD0100PA00X+103677Y+010917X0200Y         S0      
317GND              VIA   -    M      A01X+103376Y+010225X0200Y    R180 S2      
017GND              VIA   -    M      A18X+103376Y+010225X0260Y    R180 S2      
017GND                    -    MD0100PA00X+103376Y+010225                       
317GND              VIA   -    MD0100PA00X+104349Y+000447X0200Y    R270 S0      
317GND              VIA   -    MD0100PA00X+101520Y+042830X0200Y         S0      
327GND              C4002 -2          A01X+104141Y+044551X0198Y0197R270 S1      
317GND              VIA   -    MD0100PA00X+101331Y+033991X0200Y         S0      
317GND              VIA   -    MD0100PA00X+102284Y+034094X0200Y         S0      
317GND              VIA   -    MD0100PA00X+101332Y+033319X0200Y         S0      
317GND              VIA   -    MD0100PA00X+101333Y+032745X0200Y         S0      
317GND              VIA   -    MD0100PA00X+102603Y+032291X0200Y    R090 S0      
317GND              VIA   -    MD0100PA00X+102145Y+032288X0200Y    R090 S0      
317GND              VIA   -    MD0100PA00X+101335Y+032336X0200Y         S0      
317GND              VIA   -    MD0100PA00X+104667Y+034003X0200Y    R270 S0      
327GND              C2649 -2          A18X+104700Y+033745X0198Y0197R180 S2      
317GND              VIA   -    MD0100PA00X+104870Y+028016X0200Y    R090 S0      
317GND              VIA   -    MD0100PA00X+105274Y+023871X0200Y    R090 S0      
327GND              PC566 -2          A01X+105274Y+023613X0198Y0197R090 S1      
317GND              VIA   -    MD0100PA00X+104528Y+024729X0200Y         S0      
327GND              Q205  -4          A01X+104208Y+024729X0240Y0240R270 S1      
317GND              VIA   -    MD0100PA00X+104450Y+023869X0200Y    R090 S0      
327GND              PR277 -2          A01X+104450Y+023611X0198Y0197R090 S1      
317GND              VIA   -    MD0100PA00X+105106Y+021354X0200Y    R090 S0      
317GND              VIA   -    MD0100PA00X+104732Y+013776X0200Y         S0      
317GND              VIA   -    MD0100PA00X+105452Y+013776X0200Y         S0      
317GND              VIA   -    MD0100PA00X+105452Y+012358X0200Y         S0      
317GND              VIA   -    MD0100PA00X+105452Y+013067X0200Y         S0      
317GND              VIA   -    MD0100PA00X+104982Y+012358X0200Y         S0      
317GND              VIA   -    MD0100PA00X+104732Y+012358X0200Y         S0      
317GND              VIA   -    MD0100PA00X+104732Y+013067X0200Y         S0      
317GND              VIA   -    MD0100PA00X+104982Y+013067X0200Y         S0      
317GND              VIA   -    MD0100PA00X+104732Y+011650X0200Y         S0      
317GND              VIA   -    MD0100PA00X+104982Y+011650X0200Y         S0      
317GND              VIA   -    MD0100PA00X+105452Y+010232X0200Y         S0      
317GND              VIA   -    MD0100PA00X+105452Y+010941X0200Y         S0      
317GND              VIA   -    MD0100PA00X+105452Y+011650X0200Y         S0      
317GND              VIA   -    MD0100PA00X+104982Y+010941X0200Y         S0      
317GND              VIA   -    MD0100PA00X+105217Y+005360X0200Y    R270 S0      
317GND              VIA   -    MD0100PA00X+104485Y+004477X0200Y    R270 S0      
317GND              VIA   -    MD0100PA00X+104485Y+002477X0200Y    R270 S0      
317GND              VIA   -    MD0100PA00X+103136Y+032927X0200Y         S0      
317GND              VIA   -    MD0100PA00X+103138Y+033367X0200Y         S0      
317GND              VIA   -    MD0100PA00X+103131Y+033789X0200Y         S0      
317GND              VIA   -    MD0100PA00X+103138Y+034095X0200Y         S0      
317GND              VIA   -    MD0100PA00X+103135Y+032590X0200Y         S0      
327GND              U113  -C1  M      A01X+102235Y+033192X2008Y2008     S1      
317GND              VIA   -    MD0100PA00X+107127Y+023123X0200Y    R090 S0      
317GND              VIA   -    MD0100PA00X+107127Y+022873X0200Y    R090 S0      
317GND              VIA   -    MD0100PA00X+106400Y+013776X0200Y    R180 S0      
317GND              VIA   -    MD0100PA00X+106922Y+013776X0200Y         S0      
317GND              VIA   -    MD0100PA00X+106400Y+013067X0200Y    R180 S0      
317GND              VIA   -    MD0100PA00X+107263Y+012358X0200Y         S0      
317GND              VIA   -    MD0100PA00X+107263Y+013067X0200Y         S0      
317GND              VIA   -    MD0100PA00X+106295Y+012458X0200Y    R180 S0      
317GND              VIA   -    MD0100PA00X+107263Y+010941X0200Y         S0      
317GND              VIA   -    MD0100PA00X+107263Y+011650X0200Y         S0      
317GND              VIA   -    MD0100PA00X+106278Y+011650X0200Y    R180 S0      
317GND              VIA   -    MD0100PA00X+106278Y+010941X0200Y    R180 S0      
317GND              VIA   -    MD0100PA00X+106252Y+010232X0200Y    R180 S0      
317GND              VIA   -    MD0100PA00X+107250Y+010304X0200Y         S0      
317GND              VIA   -    MD0100PA00X+106298Y+008558X0200Y         S0      
317GND              VIA   -    MD0100PA00X+106554Y+009285X0200Y         S0      
317GND              VIA   -    MD0100PA00X+106298Y+008038X0200Y         S0      
317GND              VIA   -    MD0100PA00X+106298Y+007778X0200Y         S0      
317GND              VIA   -    MD0100PA00X+106298Y+007518X0200Y         S0      
317GND              VIA   -    MD0100PA00X+106298Y+008298X0200Y         S0      
317GND              VIA   -    MD0100PA00X+107217Y+005360X0200Y    R270 S0      
317GND              VIA   -    MD0100PA00X+105496Y+046861X0200Y    R090 S0      
317GND              VIA   -    MD0100PA00X+104997Y+046861X0200Y    R270 S0      
317GND              VIA   -    MD0100PA00X+105496Y+044481X0200Y    R090 S0      
317GND              VIA   -    MD0100PA00X+105078Y+045075X0200Y         S0      
327GND              U29   -S          A01X+105475Y+045075X0400Y0560     S1      
317GND              VIA   -    MD0100PA00X+104997Y+044481X0200Y    R270 S0      
317GND              VIA   -    MD0100PA00X+105496Y+043986X0200Y    R090 S0      
317GND              VIA   -    MD0100PA00X+104997Y+043064X0200Y    R270 S0      
317GND              VIA   -    MD0100PA00X+105496Y+043064X0200Y    R090 S0      
317GND              VIA   -    MD0100PA00X+104997Y+043986X0200Y    R270 S0      
317GND              VIA   -    MD0100PA00X+105496Y+041646X0200Y    R090 S0      
317GND              VIA   -    MD0100PA00X+104997Y+042568X0200Y    R270 S0      
317GND              VIA   -    MD0100PA00X+105496Y+042568X0200Y    R090 S0      
317GND              VIA   -    MD0100PA00X+104997Y+041151X0200Y    R270 S0      
317GND              VIA   -    MD0100PA00X+104997Y+041646X0200Y    R270 S0      
317GND              VIA   -    MD0100PA00X+105496Y+041151X0200Y    R090 S0      
317GND              VIA   -    MD0100PA00X+105736Y+039734X0200Y    R090 S0      
317GND              VIA   -    MD0100PA00X+105237Y+039734X0200Y    R270 S0      
317GND              VIA   -    MD0100PA00X+105736Y+040229X0200Y    R090 S0      
317GND              VIA   -    MD0100PA00X+105237Y+040229X0200Y    R270 S0      
317GND              VIA   -    MD0100PA00X+104597Y+034681X0200Y    R270 S0      
327GND              C2644 -2          A18X+104882Y+034395X0280Y0320R270 S2      
317GND              VIA   -    MD0100PA00X+108964Y+010170X0200Y    R090 S0      
317GND              VIA   -    MD0100PA00X+108592Y+009402X0200Y         S0      
317GND              VIA   -    MD0100PA00X+108992Y+009402X0200Y         S0      
317GND              VIA   -    MD0100PA00X+109028Y+004477X0200Y    R270 S0      
317GND              VIA   -    MD0100PA00X+106536Y+043770X0200Y    R090 S0      
317GND              VIA   -    MD0100PA00X+106536Y+043274X0200Y    R090 S0      
317GND              VIA   -    MD0100PA00X+106037Y+043770X0200Y    R270 S0      
317GND              VIA   -    MD0100PA00X+106037Y+043274X0200Y    R270 S0      
317GND              VIA   -    MD0100PA00X+106536Y+041857X0200Y    R090 S0      
317GND              VIA   -    MD0100PA00X+106536Y+042352X0200Y    R090 S0      
317GND              VIA   -    MD0100PA00X+106037Y+042352X0200Y    R270 S0      
317GND              VIA   -    MD0100PA00X+106037Y+041857X0200Y    R270 S0      
317GND              VIA   -    MD0100PA00X+106536Y+040935X0200Y    R090 S0      
317GND              VIA   -    MD0100PA00X+106536Y+040440X0200Y    R090 S0      
317GND              VIA   -    MD0100PA00X+106536Y+039518X0200Y    R090 S0      
317GND              VIA   -    MD0100PA00X+106037Y+040935X0200Y    R270 S0      
317GND              VIA   -    MD0100PA00X+106037Y+040440X0200Y    R270 S0      
317GND              VIA   -    MD0100PA00X+106037Y+039518X0200Y    R270 S0      
317GND              VIA   -    MD0100PA00X+106536Y+039022X0200Y    R090 S0      
317GND              VIA   -    MD0100PA00X+106037Y+039022X0200Y    R270 S0      
317GND              VIA   -    MD0100PA00X+106068Y+036428X0200Y         S0      
327GND              R1064 -1          A01X+105828Y+036428X0198Y0197R180 S1      
317GND              VIA   -    MD0100PA00X+106068Y+036015X0200Y         S0      
327GND              R1063 -1          A01X+105828Y+036015X0198Y0197R180 S1      
317GND              VIA   -    MD0100PA00X+106132Y+033951X0200Y         S0      
327GND              R1069 -1          A01X+105869Y+033951X0198Y0197R180 S1      
317GND              VIA   -    MD0100PA00X+107481Y+029380X0200Y         S0      
317GND              VIA   -    MD0100PA00X+107127Y+022373X0200Y    R090 S0      
317GND              VIA   -    MD0100PA00X+107127Y+022623X0200Y    R090 S0      
317GND              VIA   -    MD0100PA00X+107986Y+034566X0200Y    R090 S0      
317GND              VIA   -    MD0100PA00X+107786Y+033243X0200Y    R180 S0      
317GND              VIA   -    MD0100PA00X+107760Y+031406X0200Y         S0      
327GND              R1060 -1          A01X+105880Y+031454X0198Y0197R180 S1      
327GND              C2630 -2          A18X+105282Y+031695X0280Y0320R270 S2      
317GND              VIA   -    MD0100PA00X+107725Y+031856X0200Y    R180 S0      
317GND              VIA   -    MD0100PA00X+107725Y+032352X0200Y    R180 S0      
317GND              VIA   -    MD0100PA00X+107786Y+032748X0200Y    R180 S0      
317GND              VIA   -    MD0100PA00X+109235Y+029076X0200Y         S0      
317GND              VIA   -    MD0100PA00X+107731Y+029380X0200Y         S0      
317GND              VIA   -    MD0100PA00X+108283Y+028819X0200Y         S0      
317GND              VIA   -    MD0100PA00X+108533Y+028569X0200Y         S0      
317GND              VIA   -    MD0100PA00X+108283Y+028569X0200Y         S0      
317GND              VIA   -    MD0100PA00X+108533Y+028819X0200Y         S0      
317GND              VIA   -    MD0100PA00X+108813Y+028819X0200Y         S0      
317GND              VIA   -    MD0100PA00X+108813Y+028569X0200Y         S0      
317GND              VIA   -    MD0100PA00X+108538Y+024889X0200Y    R180 S0      
317GND              VIA   -    MD0100PA00X+108788Y+024889X0200Y    R180 S0      
317GND              VIA   -    MD0100PA00X+109038Y+024889X0200Y    R180 S0      
317GND              VIA   -    MD0100PA00X+109067Y+023661X0200Y    R180 S0      
317GND              VIA   -    MD0100PA00X+108817Y+023661X0200Y    R180 S0      
317GND              VIA   -    MD0100PA00X+108567Y+023661X0200Y    R180 S0      
317GND              VIA   -    MD0100PA00X+108969Y+023179X0200Y    R090 S0      
317GND              VIA   -    MD0100PA00X+108172Y+022896X0200Y    R090 S0      
317GND              VIA   -    MD0100PA00X+108172Y+023146X0200Y    R090 S0      
317GND              VIA   -    MD0100PA00X+108969Y+022929X0200Y    R090 S0      
317GND              VIA   -    M      A01X+108172Y+022366X0200Y    R090 S2      
017GND              VIA   -    M      A18X+108172Y+022366X0260Y    R090 S2      
017GND                    -    MD0100PA00X+108172Y+022366                       
317GND              VIA   -    M      A01X+108823Y+022614X0200Y         S2      
017GND              VIA   -    M      A18X+108823Y+022614X0260Y         S2      
017GND                    -    MD0100PA00X+108823Y+022614                       
317GND              VIA   -    MD0100PA00X+108172Y+022646X0200Y    R090 S0      
317GND              VIA   -    MD0100PA00X+108543Y+022614X0200Y         S0      
317GND              VIA   -    M      A01X+109147Y+018873X0200Y         S2      
017GND              VIA   -    M      A18X+109147Y+018873X0260Y         S2      
017GND                    -    MD0100PA00X+109147Y+018873                       
327GND              C325  -2          A01X+109447Y+018740X0198Y0197R090 S1      
317GND              VIA   -    MD0100PA00X+109161Y+019194X0200Y         S0      
327GND              C330  -2          A01X+109439Y+019194X0198Y0197R180 S1      
317GND              VIA   -    MD0100PA00X+108796Y+015154X0200Y         S0      
327GND              R6100 -2          A01X+109074Y+015154X0198Y0197R180 S1      
317GND              VIA   -    MD0100PA00X+108063Y+013776X0200Y    R180 S0      
317GND              VIA   -    MD0100PA00X+109004Y+012957X0200Y         S0      
317GND              VIA   -    MD0100PA00X+109004Y+012462X0200Y         S0      
317GND              VIA   -    MD0100PA00X+108063Y+012358X0200Y    R180 S0      
317GND              VIA   -    MD0100PA00X+108063Y+013067X0200Y    R180 S0      
317GND              VIA   -    MD0100PA00X+108063Y+010941X0200Y    R180 S0      
317GND              VIA   -    MD0100PA00X+108063Y+011650X0200Y    R180 S0      
317GND              VIA   -    MD0100PA00X+108063Y+010232X0200Y    R180 S0      
317GND              VIA   -    MD0100PA00X+109004Y+011540X0200Y         S0      
317GND              VIA   -    MD0100PA00X+109004Y+011044X0200Y         S0      
317GND              VIA   -    MD0100PA00X+109339Y+022221X0200Y    R090 S0      
317GND              VIA   -    MD0100PA00X+110009Y+020676X0200Y         S0      
317GND              VIA   -    MD0100PA00X+109811Y+018462X0200Y         S0      
327GND              U72   -10         A01X+110097Y+018383X0090Y0240R090 S1      
317GND              VIA   -    MD0100PA00X+110878Y+018512X0200Y         S0      
317GND              VIA   -    MD0100PA00X+110414Y+018516X0200Y         S0      
317GND              VIA   -    MD0100PA00X+110882Y+018053X0200Y         S0      
317GND              VIA   -    MD0100PA00X+110414Y+018057X0200Y         S0      
327GND              U72   -TH  M      A01X+110648Y+018285X0670Y0670R180 S1      
317GND              VIA   -    MD0100PA00X+110244Y+015237X0200Y         S0      
327GND              Q226  -1          A01X+109945Y+015237X0240Y0240R270 S1      
317GND              VIA   -    MD0100PA00X+110544Y+013669X0200Y         S0      
317GND              VIA   -    MD0100PA00X+110045Y+013669X0200Y         S0      
317GND              VIA   -    MD0100PA00X+110354Y+014646X0200Y         S0      
327GND              Q226  -4          A01X+110654Y+014646X0240Y0240R270 S1      
317GND              VIA   -    MD0100PA00X+110045Y+012251X0200Y         S0      
317GND              VIA   -    MD0100PA00X+110045Y+013173X0200Y         S0      
317GND              VIA   -    MD0100PA00X+110544Y+012251X0200Y         S0      
317GND              VIA   -    MD0100PA00X+110544Y+013173X0200Y         S0      
317GND              VIA   -    MD0100PA00X+109504Y+012462X0200Y         S0      
317GND              VIA   -    MD0100PA00X+109504Y+012957X0200Y         S0      
317GND              VIA   -    MD0100PA00X+110836Y+010362X0200Y    R090 S0      
317GND              VIA   -    MD0100PA00X+109720Y+010378X0200Y    R270 S0      
327GND              R437  -1          A01X+109720Y+010135X0198Y0197R270 S1      
317GND              VIA   -    MD0100PA00X+110544Y+011756X0200Y         S0      
317GND              VIA   -    MD0100PA00X+109504Y+011044X0200Y         S0      
317GND              VIA   -    MD0100PA00X+109504Y+011540X0200Y         S0      
317GND              VIA   -    MD0100PA00X+110045Y+011756X0200Y         S0      
317GND              VIA   -    MD0100PA00X+109392Y+009402X0200Y         S0      
317GND              VIA   -    MD0100PA00X+109792Y+009402X0200Y         S0      
317GND              VIA   -    MD0100PA00X+110299Y+008014X0200Y         S0      
317GND              VIA   -    MD0100PA00X+110299Y+007614X0200Y         S0      
317GND              VIA   -    MD0100PA00X+110299Y+008414X0200Y         S0      
317GND              VIA   -    MD0100PA00X+109154Y+046754X0200Y         S0      
317GND              VIA   -    MD0100PA00X+109154Y+044585X0200Y         S0      
317GND              VIA   -    MD0100PA00X+109154Y+043876X0200Y         S0      
317GND              VIA   -    MD0100PA00X+109154Y+043167X0200Y         S0      
317GND              VIA   -    MD0100PA00X+109154Y+042459X0200Y         S0      
317GND              VIA   -    MD0100PA00X+109154Y+041750X0200Y         S0      
317GND              VIA   -    MD0100PA00X+109154Y+040333X0200Y         S0      
317GND              VIA   -    MD0100PA00X+109154Y+039624X0200Y         S0      
317GND              VIA   -    MD0100PA00X+109154Y+041041X0200Y         S0      
317GND              VIA   -    MD0100PA00X+109154Y+038915X0200Y         S0      
317GND              VIA   -    MD0100PA00X+112305Y+005751X0200Y         S0      
327GND              C2730 -1          A01X+112057Y+005801X0198Y0197R180 S1      
317GND              VIA   -    MD0100PA00X+109934Y+046754X0200Y    R180 S0      
317GND              VIA   -    MD0100PA00X+110107Y+044585X0200Y    R180 S0      
317GND              VIA   -    MD0100PA00X+110845Y+043645X0200Y         S0      
317GND              VIA   -    MD0100PA00X+110885Y+042983X0200Y         S0      
317GND              VIA   -    MD0100PA00X+110076Y+042630X0200Y    R180 S0      
317GND              VIA   -    MD0100PA00X+110878Y+042286X0200Y         S0      
317GND              VIA   -    MD0100PA00X+109958Y+041257X0200Y    R180 S0      
317GND              VIA   -    MD0100PA00X+110469Y+039624X0200Y         S0      
317GND              VIA   -    MD0100PA00X+110062Y+040491X0200Y    R180 S0      
317GND              VIA   -    MD0100PA00X+109934Y+039624X0200Y    R180 S0      
317GND              VIA   -    MD0100PA00X+110616Y+038915X0200Y         S0      
317GND              VIA   -    MD0100PA00X+109934Y+038915X0200Y    R180 S0      
317GND              VIA   -    MD0100PA00X+109399Y+037400X0200Y         S0      
317GND              VIA   -    MD0100PA00X+110200Y+035350X0200Y         S0      
317GND              VIA   -    MD0100PA00X+110070Y+034056X0200Y         S0      
317GND              VIA   -    M      A01X+110035Y+029076X0200Y         S2      
017GND              VIA   -    M      A18X+110035Y+029076X0260Y         S2      
017GND                    -    MD0100PA00X+110035Y+029076                       
317GND              VIA   -    MD0100PA00X+109635Y+029076X0200Y         S0      
327GND              PR7077-2          A01X+109635Y+028806X0198Y0197R090 S1      
317GND              VIA   -    MD0100PA00X+110842Y+028834X0200Y    R090 S0      
317GND              VIA   -    MD0100PA00X+110842Y+029084X0200Y    R090 S0      
317GND              VIA   -    MD0100PA00X+110842Y+029364X0200Y    R090 S0      
317GND              VIA   -    M      A01X+110644Y+028131X0200Y         S2      
017GND              VIA   -    M      A18X+110644Y+028131X0260Y         S2      
017GND                    -    MD0100PA00X+110644Y+028131                       
317GND              VIA   -    MD0100PA00X+110233Y+027921X0200Y         S0      
317GND              VIA   -    MD0100PA00X+109330Y+025654X0200Y         S0      
327GND              PC863 -2          A01X+109330Y+025954X0198Y0197R270 S1      
317GND              VIA   -    MD0100PA00X+110130Y+025654X0200Y         S0      
327GND              PC867 -2          A01X+110130Y+025954X0198Y0197R270 S1      
317GND              VIA   -    MD0100PA00X+109339Y+022471X0200Y    R090 S0      
317GND              VIA   -    MD0100PA00X+111745Y+041041X0200Y    R180 S0      
317GND              VIA   -    MD0100PA00X+111745Y+040333X0200Y    R180 S0      
317GND              VIA   -    MD0100PA00X+111745Y+039624X0200Y    R180 S0      
317GND              VIA   -    MD0100PA00X+112475Y+041041X0200Y         S0      
317GND              VIA   -    MD0100PA00X+112225Y+041041X0200Y         S0      
317GND              VIA   -    MD0100PA00X+112475Y+040333X0200Y         S0      
317GND              VIA   -    MD0100PA00X+112225Y+040333X0200Y         S0      
317GND              VIA   -    MD0100PA00X+112475Y+039624X0200Y         S0      
317GND              VIA   -    MD0100PA00X+112225Y+039624X0200Y         S0      
317GND              VIA   -    MD0100PA00X+112475Y+038915X0200Y         S0      
317GND              VIA   -    MD0100PA00X+111745Y+038915X0200Y    R180 S0      
317GND              VIA   -    MD0100PA00X+112350Y+033400X0200Y         S0      
327GND              R490  -2          A01X+112592Y+033400X0198Y0197R180 S1      
317GND              VIA   -    MD0100PA00X+112350Y+033900X0200Y         S0      
327GND              R489  -2          A01X+112592Y+033900X0198Y0197R180 S1      
317GND              VIA   -    MD0100PA00X+112350Y+032900X0200Y         S0      
317GND              VIA   -    MD0100PA00X+111092Y+028834X0200Y    R090 S0      
317GND              VIA   -    MD0100PA00X+111092Y+029084X0200Y    R090 S0      
317GND              VIA   -    MD0100PA00X+111092Y+029364X0200Y    R090 S0      
317GND              VIA   -    MD0100PA00X+112411Y+022186X0200Y         S0      
327GND              C2871 -2   M      A01X+112153Y+022186X0198Y0197     S1      
317GND              VIA   -    MD0100PA00X+112411Y+021686X0200Y         S0      
327GND              PC444 -2          A01X+112153Y+021686X0198Y0197     S1      
317GND              VIA   -    MD0100PA00X+112411Y+021286X0200Y         S0      
317GND              VIA   -    MD0100PA00X+112411Y+020086X0200Y         S0      
317GND              VIA   -    MD0100PA00X+111254Y+019242X0200Y         S0      
317GND              VIA   -    MD0100PA00X+112408Y+017266X0200Y         S0      
327GND              R608  -2          A01X+112143Y+017266X0198Y0197     S1      
317GND              VIA   -    MD0100PA00X+112408Y+018066X0200Y         S0      
327GND              R609  -2          A01X+112143Y+018066X0198Y0197     S1      
317GND              VIA   -    MD0100PA00X+112390Y+011339X0200Y         S0      
317GND              VIA   -    MD0100PA00X+111637Y+011726X0200Y         S0      
327GND              R6207 -1          A01X+111679Y+011449X0198Y0197R180 S1      
317GND              VIA   -    MD0100PA00X+111776Y+009195X0200Y    R180 S0      
327GND              C2737 -1          A01X+111521Y+009195X0198Y0197R270 S1      
317GND              VIA   -    MD0100PA00X+112261Y+009704X0200Y         S0      
317GND              VIA   -    MD0100PA00X+112942Y+019518X0200Y    R180 S0      
317GND              VIA   -    M      A01X+113722Y+019518X0200Y    R180 S2      
017GND              VIA   -    M      A18X+113722Y+019518X0260Y    R180 S2      
017GND                    -    MD0100PA00X+113722Y+019518                       
317GND              VIA   -    MD0100PA00X+113192Y+019518X0200Y    R180 S0      
317GND              VIA   -    MD0100PA00X+113442Y+019518X0200Y    R180 S0      
317GND              VIA   -    MD0100PA00X+113404Y+019888X0200Y    R090 S0      
317GND              VIA   -    MD0100PA00X+112829Y+013458X0200Y         S0      
327GND              U393  -3          A01X+112518Y+013674X0240Y0240     S1      
317GND              VIA   -    MD0100PA00X+114088Y+014601X0200Y         S0      
327GND              C3676 -2          A01X+113838Y+014601X0198Y0197R090 S1      
317GND              VIA   -    MD0100PA00X+112614Y+013330X0200Y         S0      
327GND              PC955 -2          A01X+112614Y+013090X0198Y0197R090 S1      
317GND              VIA   -    MD0100PA00X+113414Y+013330X0200Y         S0      
327GND              PC950 -2          A01X+113414Y+013090X0198Y0197R090 S1      
317GND              VIA   -    MD0100PA00X+112655Y+011078X0200Y         S0      
327GND              PU129 -3   M      A01X+112788Y+011368X0100Y0280     S1      
317GND              VIA   -    MD0100PA00X+112812Y+010225X0200Y    R180 S0      
327GND              PR7120-2   M      A01X+112812Y+010475X0198Y0197R270 S1      
317GND              VIA   -    MD0100PA00X+113212Y+010225X0200Y    R180 S0      
327GND              PR7119-2   M      A01X+113212Y+010475X0198Y0197R270 S1      
317GND              VIA   -    MD0100PA00X+114114Y+010650X0200Y         S0      
317GND              VIA   -    MD0100PA00X+113913Y+010917X0200Y         S0      
317GND              VIA   -    M      A01X+113612Y+010225X0200Y    R180 S2      
017GND              VIA   -    M      A18X+113612Y+010225X0260Y    R180 S2      
017GND                    -    MD0100PA00X+113612Y+010225                       
317GND              VIA   -    MD0100PA00X+112574Y+006092X0200Y         S0      
327GND              U135  -4          A01X+112544Y+006472X0240Y0460R180 S1      
317GND              VIA   -    MD0100PA00X+111745Y+046754X0200Y    R180 S0      
317GND              VIA   -    MD0100PA00X+112475Y+046754X0200Y         S0      
317GND              VIA   -    MD0100PA00X+110965Y+046754X0200Y         S0      
317GND              VIA   -    MD0100PA00X+111745Y+044585X0200Y    R180 S0      
317GND              VIA   -    MD0100PA00X+112225Y+044585X0200Y         S0      
317GND              VIA   -    MD0100PA00X+111049Y+044795X0200Y         S0      
317GND              VIA   -    MD0100PA00X+112225Y+043167X0200Y         S0      
317GND              VIA   -    MD0100PA00X+111745Y+043876X0200Y    R180 S0      
317GND              VIA   -    MD0100PA00X+111745Y+043167X0200Y    R180 S0      
317GND              VIA   -    MD0100PA00X+112475Y+043167X0200Y         S0      
317GND              VIA   -    MD0100PA00X+112475Y+043876X0200Y         S0      
317GND              VIA   -    MD0100PA00X+112225Y+043876X0200Y         S0      
317GND              VIA   -    MD0100PA00X+112475Y+041750X0200Y         S0      
317GND              VIA   -    MD0100PA00X+112225Y+041750X0200Y         S0      
317GND              VIA   -    MD0100PA00X+111745Y+042459X0200Y    R180 S0      
317GND              VIA   -    MD0100PA00X+111745Y+041750X0200Y    R180 S0      
317GND              VIA   -    MD0100PA00X+112475Y+042459X0200Y         S0      
317GND              VIA   -    MD0100PA00X+112225Y+042459X0200Y         S0      
317GND              VIA   -    MD0100PA00X+110947Y+041482X0200Y         S0      
317GND              VIA   -    MD0100PA00X+114488Y+011650X0200Y         S0      
317GND              VIA   -    MD0100PA00X+114968Y+011650X0200Y         S0      
317GND              VIA   -    MD0100PA00X+115218Y+011650X0200Y         S0      
317GND              VIA   -    MD0100PA00X+115218Y+010941X0200Y         S0      
317GND              VIA   -    MD0100PA00X+115688Y+010941X0200Y         S0      
317GND              VIA   -    MD0100PA00X+115688Y+010232X0200Y         S0      
317GND              VIA   -    MD0100PA00X+115688Y+011650X0200Y         S0      
317GND              VIA   -    MD0100PA00X+114213Y+010917X0200Y         S0      
317GND              VIA   -    MD0100PA00X+115454Y+005360X0200Y    R270 S0      
317GND              VIA   -    MD0100PA00X+114721Y+004477X0200Y    R270 S0      
317GND              VIA   -    MD0100PA00X+112518Y+045979X0200Y         S0      
317GND              VIA   -    MD0100PA00X+112955Y+046754X0200Y         S0      
317GND              VIA   -    MD0100PA00X+113036Y+045348X0200Y         S0      
317GND              VIA   -    MD0100PA00X+112693Y+045356X0200Y         S0      
317GND              VIA   -    MD0100PA00X+112955Y+043876X0200Y         S0      
317GND              VIA   -    MD0100PA00X+112955Y+043167X0200Y         S0      
317GND              VIA   -    M      A01X+114244Y+041272X0200Y    R180 S2      
017GND              VIA   -    M      A18X+114244Y+041272X0260Y    R180 S2      
017GND                    -    MD0100PA00X+114244Y+041272                       
317GND              VIA   -    MD0100PA00X+112955Y+041750X0200Y         S0      
317GND              VIA   -    MD0100PA00X+112955Y+042459X0200Y         S0      
317GND              VIA   -    M      A01X+114244Y+040472X0200Y    R180 S2      
017GND              VIA   -    M      A18X+114244Y+040472X0260Y    R180 S2      
017GND                    -    MD0100PA00X+114244Y+040472                       
317GND              VIA   -    MD0100PA00X+112955Y+041041X0200Y         S0      
317GND              VIA   -    MD0100PA00X+112955Y+040333X0200Y         S0      
317GND              VIA   -    MD0100PA00X+112955Y+039624X0200Y         S0      
317GND              VIA   -    MD0100PA00X+112955Y+038915X0200Y         S0      
317GND              VIA   -    MD0100PA00X+112586Y+025237X0200Y         S0      
327GND              PR7085-2          A01X+112864Y+025237X0198Y0197R180 S1      
317GND              VIA   -    MD0100PA00X+114035Y+025320X0200Y         S0      
327GND              Q206  -1          A01X+113736Y+025320X0240Y0240R270 S1      
317GND              VIA   -    MD0100PA00X+114043Y+023612X0200Y    R090 S0      
327GND              PC565 -2          A01X+114299Y+023612X0198Y0197R090 S1      
317GND              VIA   -    MD0100PA00X+113746Y+023859X0200Y    R090 S0      
327GND              C2897 -2          A01X+113746Y+023601X0198Y0197R090 S1      
317GND              VIA   -    MD0100PA00X+113546Y+020684X0200Y    R180 S0      
317GND              VIA   -    MD0100PA00X+112928Y+020339X0200Y         S0      
317GND              VIA   -    MD0100PA00X+113178Y+020339X0200Y    R180 S0      
317GND              VIA   -    M      A01X+113404Y+020168X0200Y    R090 S2      
017GND              VIA   -    M      A18X+113404Y+020168X0260Y    R090 S2      
017GND                    -    MD0100PA00X+113404Y+020168                       
317GND              VIA   -    MD0100PA00X+113796Y+020684X0200Y    R180 S0      
317GND              VIA   -    MD0100PA00X+116636Y+013776X0200Y    R180 S0      
317GND              VIA   -    MD0100PA00X+117159Y+013776X0200Y         S0      
317GND              VIA   -    MD0100PA00X+116636Y+013067X0200Y    R180 S0      
317GND              VIA   -    MD0100PA00X+116531Y+012458X0200Y    R180 S0      
317GND              VIA   -    MD0100PA00X+116514Y+011650X0200Y    R180 S0      
317GND              VIA   -    MD0100PA00X+116514Y+010941X0200Y    R180 S0      
317GND              VIA   -    MD0100PA00X+116488Y+010232X0200Y    R180 S0      
317GND              VIA   -    MD0100PA00X+116535Y+008558X0200Y         S0      
317GND              VIA   -    MD0100PA00X+116776Y+009273X0200Y         S0      
317GND              VIA   -    MD0100PA00X+116535Y+008038X0200Y         S0      
317GND              VIA   -    MD0100PA00X+116535Y+007778X0200Y         S0      
317GND              VIA   -    MD0100PA00X+116535Y+007518X0200Y         S0      
317GND              VIA   -    MD0100PA00X+116535Y+008298X0200Y         S0      
317GND              VIA   -    MD0100PA00X+114244Y+040872X0200Y    R180 S0      
327GND              R273  -2          A01X+114486Y+040872X0198Y0197R180 S1      
317GND              VIA   -    MD0100PA00X+114244Y+040072X0200Y    R180 S0      
327GND              R276  -2          A01X+114486Y+040072X0198Y0197R180 S1      
317GND              VIA   -    MD0100PA00X+114244Y+039272X0200Y    R180 S0      
327GND              R283  -2          A01X+114486Y+039272X0198Y0197R180 S1      
317GND              VIA   -    MD0100PA00X+114576Y+032415X0200Y         S0      
327GND              U7    -4          A01X+115091Y+032415X0220Y0680R270 S1      
317GND              VIA   -    MD0100PA00X+114764Y+024729X0200Y         S0      
327GND              Q206  -4          A01X+114445Y+024729X0240Y0240R270 S1      
317GND              VIA   -    MD0100PA00X+115510Y+023871X0200Y    R090 S0      
327GND              PC578 -2          A01X+115510Y+023613X0198Y0197R090 S1      
317GND              VIA   -    MD0100PA00X+114686Y+023869X0200Y    R090 S0      
327GND              PR281 -2          A01X+114686Y+023611X0198Y0197R090 S1      
317GND              VIA   -    MD0100PA00X+115342Y+021354X0200Y    R090 S0      
317GND              VIA   -    MD0100PA00X+114567Y+015085X0200Y         S0      
327GND              U375  -S          A01X+114172Y+015330X0400Y0560     S1      
317GND              VIA   -    MD0100PA00X+114488Y+013776X0200Y         S0      
317GND              VIA   -    MD0100PA00X+114968Y+013776X0200Y         S0      
317GND              VIA   -    MD0100PA00X+115688Y+013776X0200Y         S0      
317GND              VIA   -    MD0100PA00X+114278Y+014123X0200Y         S0      
327GND              R5695 -2          A01X+114132Y+013884X0198Y0197     S1      
317GND              VIA   -    MD0100PA00X+115688Y+012358X0200Y         S0      
317GND              VIA   -    MD0100PA00X+115688Y+013067X0200Y         S0      
317GND              VIA   -    MD0100PA00X+114488Y+012358X0200Y         S0      
317GND              VIA   -    MD0100PA00X+114488Y+013067X0200Y         S0      
317GND              VIA   -    MD0100PA00X+115218Y+012358X0200Y         S0      
317GND              VIA   -    MD0100PA00X+114968Y+012358X0200Y         S0      
317GND              VIA   -    MD0100PA00X+114968Y+013067X0200Y         S0      
317GND              VIA   -    MD0100PA00X+115218Y+013067X0200Y         S0      
317GND              VIA   -    MD0100PA00X+117718Y+029380X0200Y         S0      
317GND              VIA   -    MD0100PA00X+118519Y+028819X0200Y         S0      
317GND              VIA   -    MD0100PA00X+118769Y+028569X0200Y         S0      
317GND              VIA   -    MD0100PA00X+118519Y+028569X0200Y         S0      
317GND              VIA   -    MD0100PA00X+118769Y+028819X0200Y         S0      
317GND              VIA   -    MD0100PA00X+118774Y+024889X0200Y    R180 S0      
317GND              VIA   -    MD0100PA00X+118804Y+023661X0200Y    R180 S0      
317GND              VIA   -    M      A01X+118409Y+022366X0200Y    R090 S2      
017GND              VIA   -    M      A18X+118409Y+022366X0260Y    R090 S2      
017GND                    -    MD0100PA00X+118409Y+022366                       
317GND              VIA   -    M      A01X+119059Y+022614X0200Y         S2      
017GND              VIA   -    M      A18X+119059Y+022614X0260Y         S2      
017GND                    -    MD0100PA00X+119059Y+022614                       
317GND              VIA   -    MD0100PA00X+118409Y+022646X0200Y    R090 S0      
317GND              VIA   -    MD0100PA00X+118779Y+022614X0200Y         S0      
317GND              VIA   -    MD0100PA00X+118409Y+022896X0200Y    R090 S0      
317GND              VIA   -    MD0100PA00X+118409Y+023146X0200Y    R090 S0      
317GND              VIA   -    MD0100PA00X+118300Y+013776X0200Y    R180 S0      
317GND              VIA   -    MD0100PA00X+118300Y+012358X0200Y    R180 S0      
317GND              VIA   -    MD0100PA00X+118300Y+013067X0200Y    R180 S0      
317GND              VIA   -    MD0100PA00X+117500Y+012358X0200Y         S0      
317GND              VIA   -    MD0100PA00X+117500Y+013067X0200Y         S0      
317GND              VIA   -    MD0100PA00X+118300Y+010232X0200Y    R180 S0      
317GND              VIA   -    MD0100PA00X+118300Y+010941X0200Y    R180 S0      
317GND              VIA   -    MD0100PA00X+118300Y+011650X0200Y    R180 S0      
317GND              VIA   -    MD0100PA00X+117500Y+010941X0200Y         S0      
317GND              VIA   -    MD0100PA00X+117500Y+011650X0200Y         S0      
317GND              VIA   -    MD0100PA00X+117486Y+010304X0200Y         S0      
317GND              VIA   -    MD0100PA00X+118828Y+009402X0200Y         S0      
317GND              VIA   -    MD0100PA00X+117454Y+005360X0200Y    R270 S0      
317GND              VIA   -    MD0100PA00X+117126Y+045629X0200Y         S0      
317GND              VIA   -    MD0100PA00X+116885Y+044987X0200Y         S0      
327GND              R293  -2          A01X+116645Y+044987X0198Y0197     S1      
317GND              VIA   -    MD0100PA00X+116917Y+042702X0200Y         S0      
327GND              R285  -2          A18X+116529Y+042702X0198Y0197R180 S2      
317GND              VIA   -    MD0100PA00X+116793Y+043503X0200Y         S0      
327GND              R289  -2          A18X+116526Y+043503X0198Y0197R180 S2      
317GND              VIA   -    MD0100PA00X+116890Y+043103X0200Y         S0      
327GND              R287  -2          A18X+116526Y+043103X0198Y0197R180 S2      
317GND              VIA   -    MD0100PA00X+117363Y+023123X0200Y    R090 S0      
317GND              VIA   -    MD0100PA00X+117363Y+022873X0200Y    R090 S0      
317GND              VIA   -    MD0100PA00X+117363Y+022373X0200Y    R090 S0      
317GND              VIA   -    MD0100PA00X+117363Y+022623X0200Y    R090 S0      
317GND              VIA   -    MD0100PA00X+119201Y+010170X0200Y    R090 S0      
317GND              VIA   -    MD0100PA00X+119228Y+009402X0200Y         S0      
317GND              VIA   -    MD0100PA00X+120029Y+009402X0200Y         S0      
317GND              VIA   -    MD0100PA00X+119628Y+009402X0200Y         S0      
317GND              VIA   -    MD0100PA00X+120536Y+008014X0200Y         S0      
317GND              VIA   -    MD0100PA00X+120536Y+007614X0200Y         S0      
317GND              VIA   -    MD0100PA00X+120536Y+008414X0200Y         S0      
317GND              VIA   -    MD0100PA00X+119264Y+004477X0200Y    R270 S0      
317GND              VIA   -    MD0100PA00X+119264Y+002477X0200Y    R270 S0      
317GND              VIA   -    MD0100PA00X+119333Y+000537X0200Y    R270 S0      
317GND              VIA   -    MD0100PA00X+118058Y+046549X0200Y         S0      
317GND              VIA   -    MD0100PA00X+117578Y+046549X0200Y         S0      
317GND              VIA   -    MD0100PA00X+118040Y+046226X0200Y         S0      
327GND              C421  -2          A18X+118427Y+046348X0198Y0197     S2      
317GND              VIA   -    MD0100PA00X+118838Y+046603X0200Y    R180 S0      
317GND              VIA   -    MD0100PA00X+118058Y+045132X0200Y         S0      
317GND              VIA   -    MD0100PA00X+118058Y+045841X0200Y         S0      
317GND              VIA   -    MD0100PA00X+118012Y+043260X0200Y    R270 S0      
317GND              VIA   -    MD0100PA00X+118012Y+043510X0200Y    R270 S0      
317GND              VIA   -    MD0100PA00X+118012Y+043760X0200Y    R270 S0      
317GND              VIA   -    MD0100PA00X+118012Y+044010X0200Y    R270 S0      
317GND              VIA   -    MD0100PA00X+118012Y+043010X0200Y    R270 S0      
317GND              VIA   -    M      A01X+117918Y+040331X0200Y         S2      
017GND              VIA   -    M      A18X+117918Y+040331X0260Y         S2      
017GND                    -    MD0100PA00X+117918Y+040331                       
317GND              VIA   -    MD0100PA00X+117918Y+041039X0200Y         S0      
317GND              VIA   -    MD0100PA00X+118860Y+039050X0200Y         S0      
327GND              R278  -2          A18X+118860Y+038800X0198Y0197     S2      
317GND              VIA   -    MD0100PA00X+117704Y+033415X0200Y         S0      
327GND              U7    -7          A01X+117171Y+033415X0220Y0680R270 S1      
317GND              VIA   -    MD0100PA00X+118291Y+033652X0200Y         S0      
327GND              C198  -2          A01X+118291Y+033910X0198Y0197     S1      
317GND              VIA   -    MD0100PA00X+117686Y+030653X0200Y    R270 S0      
317GND              VIA   -    MD0100PA00X+117968Y+029380X0200Y         S0      
317GND              VIA   -    MD0100PA00X+119872Y+029076X0200Y         S0      
327GND              PR7081-2          A01X+119872Y+028806X0198Y0197R090 S1      
317GND              VIA   -    MD0100PA00X+119049Y+028819X0200Y         S0      
317GND              VIA   -    MD0100PA00X+119049Y+028569X0200Y         S0      
317GND              VIA   -    MD0100PA00X+120469Y+027921X0200Y         S0      
317GND              VIA   -    MD0100PA00X+119566Y+025654X0200Y         S0      
327GND              PC871 -2          A01X+119566Y+025954X0198Y0197R270 S1      
317GND              VIA   -    MD0100PA00X+120366Y+025654X0200Y         S0      
327GND              PC873 -2          A01X+120366Y+025954X0198Y0197R270 S1      
317GND              VIA   -    MD0100PA00X+119024Y+024889X0200Y    R180 S0      
317GND              VIA   -    MD0100PA00X+119274Y+024889X0200Y    R180 S0      
317GND              VIA   -    MD0100PA00X+119304Y+023661X0200Y    R180 S0      
317GND              VIA   -    MD0100PA00X+119054Y+023661X0200Y    R180 S0      
317GND              VIA   -    MD0100PA00X+119206Y+023179X0200Y    R090 S0      
317GND              VIA   -    MD0100PA00X+119575Y+022221X0200Y    R090 S0      
317GND              VIA   -    MD0100PA00X+119575Y+022471X0200Y    R090 S0      
317GND              VIA   -    MD0100PA00X+119206Y+022929X0200Y    R090 S0      
317GND              VIA   -    MD0100PA00X+120245Y+020676X0200Y         S0      
317GND              VIA   -    M      A01X+119384Y+018873X0200Y         S2      
017GND              VIA   -    M      A18X+119384Y+018873X0260Y         S2      
017GND                    -    MD0100PA00X+119384Y+018873                       
327GND              C328  -2          A01X+119684Y+018740X0198Y0197R090 S1      
317GND              VIA   -    MD0100PA00X+119397Y+019194X0200Y         S0      
327GND              C324  -2          A01X+119675Y+019194X0198Y0197R180 S1      
317GND              VIA   -    MD0100PA00X+120047Y+018462X0200Y         S0      
327GND              U73   -10         A01X+120333Y+018383X0090Y0240R090 S1      
317GND              VIA   -    MD0100PA00X+119032Y+015154X0200Y         S0      
327GND              R6101 -2          A01X+119310Y+015154X0198Y0197R180 S1      
317GND              VIA   -    MD0100PA00X+120480Y+015237X0200Y         S0      
327GND              Q227  -1          A01X+120182Y+015237X0240Y0240R270 S1      
317GND              VIA   -    MD0100PA00X+120281Y+013669X0200Y         S0      
317GND              VIA   -    MD0100PA00X+120590Y+014646X0200Y         S0      
317GND              VIA   -    MD0100PA00X+120281Y+013173X0200Y         S0      
317GND              VIA   -    MD0100PA00X+120281Y+012251X0200Y         S0      
317GND              VIA   -    MD0100PA00X+119241Y+012957X0200Y         S0      
317GND              VIA   -    MD0100PA00X+119241Y+012462X0200Y         S0      
317GND              VIA   -    MD0100PA00X+119740Y+012462X0200Y         S0      
317GND              VIA   -    MD0100PA00X+119740Y+012957X0200Y         S0      
317GND              VIA   -    MD0100PA00X+119956Y+010378X0200Y    R270 S0      
327GND              R440  -1          A01X+119956Y+010135X0198Y0197R270 S1      
317GND              VIA   -    MD0100PA00X+119241Y+011540X0200Y         S0      
317GND              VIA   -    MD0100PA00X+119241Y+011044X0200Y         S0      
317GND              VIA   -    MD0100PA00X+119740Y+011540X0200Y         S0      
317GND              VIA   -    MD0100PA00X+119740Y+011044X0200Y         S0      
317GND              VIA   -    MD0100PA00X+120281Y+011756X0200Y         S0      
317GND              VIA   -    MD0100PA00X+121118Y+018053X0200Y         S0      
317GND              VIA   -    MD0100PA00X+120650Y+018057X0200Y         S0      
317GND              VIA   -    MD0100PA00X+120780Y+013669X0200Y         S0      
317GND              VIA   -    MD0100PA00X+120780Y+013173X0200Y         S0      
317GND              VIA   -    MD0100PA00X+120780Y+012251X0200Y         S0      
317GND              VIA   -    MD0100PA00X+121072Y+010362X0200Y    R090 S0      
327GND              U410  -S          A01X+121072Y+010792X0400Y0560R180 S1      
317GND              VIA   -    MD0100PA00X+120780Y+011756X0200Y         S0      
317GND              VIA   -    MD0100PA00X+121873Y+011726X0200Y         S0      
327GND              R6208 -1          A01X+121915Y+011449X0198Y0197R180 S1      
317GND              VIA   -    MD0100PA00X+122013Y+009195X0200Y    R180 S0      
327GND              C2729 -1          A01X+121757Y+009195X0198Y0197R270 S1      
317GND              VIA   -    MD0100PA00X+121223Y+000300X0200Y    R270 S0      
317GND              VIA   -    MD0100PA00X+119642Y+047014X0200Y         S0      
327GND              R279  -2          A18X+119642Y+046737X0198Y0197R180 S2      
317GND              VIA   -    MD0100PA00X+119866Y+046025X0200Y         S0      
317GND              VIA   -    MD0100PA00X+119869Y+046549X0200Y         S0      
317GND              VIA   -    MD0100PA00X+119861Y+045474X0200Y    R180 S0      
317GND              VIA   -    MD0100PA00X+119859Y+044318X0200Y    R180 S0      
317GND              VIA   -    MD0100PA00X+119855Y+045202X0200Y    R180 S0      
317GND              VIA   -    MD0100PA00X+119835Y+043996X0200Y    R180 S0      
317GND              VIA   -    MD0100PA00X+119830Y+043707X0200Y    R180 S0      
317GND              VIA   -    MD0100PA00X+119849Y+043357X0200Y    R180 S0      
317GND              VIA   -    MD0100PA00X+119847Y+043076X0200Y    R180 S0      
317GND              VIA   -    MD0100PA00X+119825Y+038150X0200Y         S0      
327GND              R277  -2          A18X+119825Y+038450X0198Y0197R180 S2      
317GND              VIA   -    MD0100PA00X+119250Y+032240X0200Y    R270 S0      
317GND              VIA   -    M      A01X+120272Y+029076X0200Y         S2      
017GND              VIA   -    M      A18X+120272Y+029076X0260Y         S2      
017GND                    -    MD0100PA00X+120272Y+029076                       
317GND              VIA   -    MD0100PA00X+119472Y+029076X0200Y         S0      
327GND              PC870 -2          A01X+119472Y+028806X0198Y0197R090 S1      
317GND              VIA   -    MD0100PA00X+122626Y+011339X0200Y         S0      
317GND              VIA   -    MD0100PA00X+122891Y+011078X0200Y         S0      
327GND              PU130 -3   M      A01X+123025Y+011368X0100Y0280     S1      
317GND              VIA   -    M      A01X+123848Y+010225X0200Y    R180 S2      
017GND              VIA   -    M      A18X+123848Y+010225X0260Y    R180 S2      
017GND                    -    MD0100PA00X+123848Y+010225                       
317GND              VIA   -    MD0100PA00X+122504Y+009708X0200Y         S0      
317GND              VIA   -    MD0100PA00X+122810Y+006092X0200Y         S0      
327GND              U136  -4          A01X+122780Y+006472X0240Y0460R180 S1      
317GND              VIA   -    MD0100PA00X+122293Y+005551X0200Y         S0      
327GND              C2732 -1          A01X+122293Y+005801X0198Y0197R180 S1      
317GND              VIA   -    MD0100PA00X+123223Y+000300X0200Y    R270 S0      
317GND              VIA   -    MD0100PA00X+120649Y+046549X0200Y    R180 S0      
317GND              VIA   -    MD0100PA00X+121663Y+044579X0200Y         S0      
327GND              C928  -2          A18X+121663Y+044863X0198Y0197R090 S2      
317GND              VIA   -    MD0100PA00X+121268Y+044591X0200Y         S0      
327GND              C927  -2          A18X+121268Y+044863X0198Y0197R090 S2      
317GND              VIA   -    MD0100PA00X+120649Y+045841X0200Y    R180 S0      
317GND              VIA   -    MD0100PA00X+120667Y+040331X0200Y    R180 S0      
317GND              VIA   -    MD0100PA00X+120667Y+041039X0200Y    R180 S0      
317GND              VIA   -    MD0100PA00X+122098Y+034232X0200Y         S0      
327GND              U35   -3          A01X+121746Y+034232X0160Y0360R270 S1      
317GND              VIA   -    MD0100PA00X+122134Y+033202X0200Y    R270 S0      
327GND              C931  -2          A01X+121872Y+033202X0198Y0197R090 S1      
317GND              VIA   -    MD0100PA00X+121714Y+032414X0200Y    R090 S0      
327GND              Q6    -1          A01X+121401Y+032185X0170Y0240R270 S1      
317GND              VIA   -    MD0100PA00X+121079Y+028834X0200Y    R090 S0      
317GND              VIA   -    MD0100PA00X+121079Y+029084X0200Y    R090 S0      
317GND              VIA   -    MD0100PA00X+121079Y+029364X0200Y    R090 S0      
317GND              VIA   -    MD0100PA00X+121329Y+028834X0200Y    R090 S0      
317GND              VIA   -    MD0100PA00X+121329Y+029084X0200Y    R090 S0      
317GND              VIA   -    MD0100PA00X+121329Y+029364X0200Y    R090 S0      
317GND              VIA   -    M      A01X+120880Y+028131X0200Y         S2      
017GND              VIA   -    M      A18X+120880Y+028131X0260Y         S2      
017GND                    -    MD0100PA00X+120880Y+028131                       
317GND              VIA   -    MD0100PA00X+121114Y+018512X0200Y         S0      
317GND              VIA   -    MD0100PA00X+120650Y+018516X0200Y         S0      
327GND              U73   -TH  M      A01X+120884Y+018285X0670Y0670R180 S1      
317GND              VIA   -    MD0100PA00X+121491Y+019242X0200Y         S0      
317GND              VIA   -    MD0100PA00X+124958Y+004477X0200Y    R270 S0      
317GND              VIA   -    MD0100PA00X+124958Y+002477X0200Y    R270 S0      
317GND              VIA   -    MD0100PA00X+124822Y+000447X0200Y    R270 S0      
317GND              VIA   -    MD0100PA00X+123766Y+047148X0200Y    R090 S0      
317GND              VIA   -    MD0100PA00X+123267Y+047148X0200Y    R270 S0      
317GND              VIA   -    MD0100PA00X+123766Y+046653X0200Y    R090 S0      
317GND              VIA   -    MD0100PA00X+123267Y+046653X0200Y    R270 S0      
317GND              VIA   -    MD0100PA00X+122343Y+040192X0200Y         S0      
327GND              R272  -2          A18X+122103Y+040192X0198Y0197R180 S2      
317GND              VIA   -    MD0100PA00X+122343Y+040592X0200Y         S0      
327GND              R271  -2          A18X+122103Y+040592X0198Y0197R180 S2      
317GND              VIA   -    MD0100PA00X+122343Y+040992X0200Y         S0      
317GND              VIA   -    MD0100PA00X+122343Y+038591X0200Y         S0      
327GND              R268  -2          A18X+122103Y+038591X0198Y0197R180 S2      
317GND              VIA   -    MD0100PA00X+122343Y+038991X0200Y         S0      
327GND              R269  -2          A18X+122103Y+038991X0198Y0197R180 S2      
317GND              VIA   -    MD0100PA00X+122343Y+039392X0200Y         S0      
317GND              VIA   -    MD0100PA00X+123466Y+035351X0200Y         S0      
327GND              C932  -2          A01X+123466Y+035085X0198Y0197     S1      
317GND              VIA   -    MD0100PA00X+123008Y+033632X0200Y         S0      
327GND              U36   -3          A01X+123445Y+033632X0220Y0530R090 S1      
317GND              VIA   -    MD0100PA00X+122419Y+031673X0200Y    R090 S0      
327GND              Q6    -4          A01X+122149Y+031673X0170Y0240R270 S1      
317GND              VIA   -    MD0100PA00X+123410Y+032292X0200Y    R180 S0      
327GND              U37   -3          A01X+123760Y+032165X0400Y0500     S1      
317GND              VIA   -    MD0100PA00X+123806Y+030384X0200Y         S0      
327GND              C930  -2          A01X+123806Y+030665X0198Y0197R180 S1      
317GND              VIA   -    MD0100PA00X+122823Y+025237X0200Y         S0      
327GND              PR7086-2          A01X+123100Y+025237X0198Y0197R180 S1      
317GND              VIA   -    MD0100PA00X+122647Y+022186X0200Y         S0      
327GND              C2873 -2   M      A01X+122389Y+022186X0198Y0197     S1      
317GND              VIA   -    MD0100PA00X+122647Y+021686X0200Y         S0      
327GND              PC361 -2          A01X+122389Y+021686X0198Y0197     S1      
317GND              VIA   -    MD0100PA00X+123783Y+020684X0200Y    R180 S0      
317GND              VIA   -    MD0100PA00X+122647Y+021286X0200Y         S0      
317GND              VIA   -    MD0100PA00X+122647Y+020086X0200Y         S0      
317GND              VIA   -    MD0100PA00X+123164Y+020339X0200Y    R180 S0      
317GND              VIA   -    MD0100PA00X+123414Y+020339X0200Y    R180 S0      
317GND              VIA   -    M      A01X+123640Y+020168X0200Y    R090 S2      
017GND              VIA   -    M      A18X+123640Y+020168X0260Y    R090 S2      
017GND                    -    MD0100PA00X+123640Y+020168                       
317GND              VIA   -    MD0100PA00X+123178Y+019518X0200Y    R180 S0      
317GND              VIA   -    M      A01X+123958Y+019518X0200Y    R180 S2      
017GND              VIA   -    M      A18X+123958Y+019518X0260Y    R180 S2      
017GND                    -    MD0100PA00X+123958Y+019518                       
317GND              VIA   -    MD0100PA00X+123428Y+019518X0200Y    R180 S0      
317GND              VIA   -    MD0100PA00X+123640Y+019888X0200Y    R090 S0      
317GND              VIA   -    MD0100PA00X+123678Y+019518X0200Y    R180 S0      
317GND              VIA   -    MD0100PA00X+122644Y+017266X0200Y         S0      
327GND              R619  -2          A01X+122379Y+017266X0198Y0197     S1      
317GND              VIA   -    MD0100PA00X+122644Y+018066X0200Y         S0      
327GND              R620  -2          A01X+122379Y+018066X0198Y0197     S1      
317GND              VIA   -    MD0100PA00X+123065Y+013458X0200Y         S0      
327GND              U392  -3          A01X+122754Y+013674X0240Y0240     S1      
317GND              VIA   -    MD0100PA00X+123650Y+013330X0200Y         S0      
327GND              PC952 -2          A01X+123650Y+013090X0198Y0197R090 S1      
317GND              VIA   -    MD0100PA00X+122920Y+013090X0200Y         S0      
327GND              PC957 -2          A01X+122650Y+013090X0198Y0197R090 S1      
317GND              VIA   -    MD0100PA00X+123448Y+010225X0200Y    R180 S0      
327GND              PR7121-2   M      A01X+123448Y+010475X0198Y0197R270 S1      
317GND              VIA   -    MD0100PA00X+123048Y+010225X0200Y    R180 S0      
327GND              PR7122-2   M      A01X+123048Y+010475X0198Y0197R270 S1      
317GND              VIA   -    MD0100PA00X+126750Y+010941X0200Y    R180 S0      
317GND              VIA   -    MD0100PA00X+126725Y+010232X0200Y    R180 S0      
317GND              VIA   -    MD0100PA00X+126771Y+008558X0200Y         S0      
317GND              VIA   -    MD0100PA00X+127026Y+009285X0200Y         S0      
317GND              VIA   -    MD0100PA00X+126771Y+008038X0200Y         S0      
317GND              VIA   -    MD0100PA00X+126771Y+007778X0200Y         S0      
317GND              VIA   -    MD0100PA00X+126771Y+007518X0200Y         S0      
317GND              VIA   -    MD0100PA00X+126771Y+008298X0200Y         S0      
317GND              VIA   -    MD0100PA00X+125690Y+005360X0200Y    R270 S0      
317GND              VIA   -    MD0100PA00X+124271Y+025320X0200Y         S0      
327GND              Q207  -1          A01X+123972Y+025320X0240Y0240R270 S1      
317GND              VIA   -    MD0100PA00X+124279Y+023612X0200Y    R090 S0      
327GND              PC577 -2   M      A01X+124535Y+023612X0198Y0197R090 S1      
317GND              VIA   -    MD0100PA00X+123982Y+023859X0200Y    R090 S0      
327GND              C2900 -2          A01X+123982Y+023601X0198Y0197R090 S1      
317GND              VIA   -    MD0100PA00X+125000Y+024729X0200Y         S0      
327GND              Q207  -4          A01X+124681Y+024729X0240Y0240R270 S1      
317GND              VIA   -    MD0100PA00X+124033Y+020684X0200Y    R180 S0      
317GND              VIA   -    MD0100PA00X+124803Y+015085X0200Y         S0      
327GND              U377  -S          A01X+124408Y+015330X0400Y0560     S1      
317GND              VIA   -    MD0100PA00X+125205Y+013776X0200Y         S0      
317GND              VIA   -    MD0100PA00X+124725Y+013776X0200Y         S0      
317GND              VIA   -    MD0100PA00X+124514Y+014123X0200Y         S0      
327GND              R5692 -2          A01X+124368Y+013884X0198Y0197     S1      
317GND              VIA   -    MD0100PA00X+124324Y+014601X0200Y         S0      
327GND              C3671 -2          A01X+124074Y+014601X0198Y0197R090 S1      
317GND              VIA   -    MD0100PA00X+125205Y+013067X0200Y         S0      
317GND              VIA   -    MD0100PA00X+125455Y+013067X0200Y         S0      
317GND              VIA   -    MD0100PA00X+125455Y+012358X0200Y         S0      
317GND              VIA   -    MD0100PA00X+125205Y+012358X0200Y         S0      
317GND              VIA   -    MD0100PA00X+124725Y+013067X0200Y         S0      
317GND              VIA   -    MD0100PA00X+124725Y+012358X0200Y         S0      
317GND              VIA   -    MD0100PA00X+125205Y+011650X0200Y         S0      
317GND              VIA   -    MD0100PA00X+125455Y+011650X0200Y         S0      
317GND              VIA   -    MD0100PA00X+125455Y+010941X0200Y         S0      
317GND              VIA   -    MD0100PA00X+124725Y+011650X0200Y         S0      
317GND              VIA   -    MD0100PA00X+124150Y+010917X0200Y         S0      
317GND              VIA   -    MD0100PA00X+124450Y+010917X0200Y         S0      
317GND              VIA   -    MD0100PA00X+124350Y+010650X0200Y         S0      
327GND              C2774 -2   M      A01X+124610Y+010650X0198Y0197R180 S1      
317GND              VIA   -    MD0100PA00X+128536Y+013067X0200Y    R180 S0      
317GND              VIA   -    MD0100PA00X+127736Y+012358X0200Y         S0      
317GND              VIA   -    MD0100PA00X+127736Y+013067X0200Y         S0      
317GND              VIA   -    MD0100PA00X+128536Y+010232X0200Y    R180 S0      
317GND              VIA   -    MD0100PA00X+128536Y+010941X0200Y    R180 S0      
317GND              VIA   -    MD0100PA00X+128536Y+011650X0200Y    R180 S0      
317GND              VIA   -    MD0100PA00X+127736Y+010941X0200Y         S0      
317GND              VIA   -    MD0100PA00X+127736Y+011650X0200Y         S0      
317GND              VIA   -    MD0100PA00X+127722Y+010304X0200Y         S0      
317GND              VIA   -    MD0100PA00X+127690Y+005360X0200Y    R270 S0      
317GND              VIA   -    MD0100PA00X+125922Y+045833X0200Y    R090 S0      
327GND              PC902 -2          A01X+126162Y+045833X0198Y0197R180 S1      
317GND              VIA   -    MD0100PA00X+126162Y+044749X0200Y    R090 S0      
327GND              PC907 -2          A01X+126162Y+045033X0198Y0197R180 S1      
317GND              VIA   -    MD0100PA00X+126866Y+037717X0200Y    R270 S0      
327GND              R739  -2          A01X+126866Y+037957X0198Y0197R270 S1      
317GND              VIA   -    MD0100PA00X+126622Y+037430X0200Y    R270 S0      
327GND              R741  -2          A01X+126066Y+037957X0198Y0197R270 S1      
317GND              VIA   -    MD0100PA00X+125950Y+033000X0200Y    R180 S0      
317GND              VIA   -    MD0100PA00X+125892Y+032408X0200Y         S0      
327GND              C3992 -1          A01X+125892Y+032700X0198Y0197     S1      
317GND              VIA   -    MD0100PA00X+126448Y+030022X0200Y    R090 S0      
317GND              VIA   -    MD0100PA00X+125746Y+023871X0200Y    R090 S0      
327GND              PC591 -2          A01X+125746Y+023613X0198Y0197R090 S1      
317GND              VIA   -    MD0100PA00X+125578Y+021354X0200Y    R090 S0      
317GND              VIA   -    MD0100PA00X+125925Y+013776X0200Y         S0      
317GND              VIA   -    MD0100PA00X+126872Y+013776X0200Y    R180 S0      
317GND              VIA   -    MD0100PA00X+125925Y+012358X0200Y         S0      
317GND              VIA   -    MD0100PA00X+125925Y+013067X0200Y         S0      
317GND              VIA   -    MD0100PA00X+126872Y+013067X0200Y    R180 S0      
317GND              VIA   -    MD0100PA00X+126767Y+012458X0200Y    R180 S0      
317GND              VIA   -    MD0100PA00X+125925Y+010941X0200Y         S0      
317GND              VIA   -    MD0100PA00X+125925Y+010232X0200Y         S0      
317GND              VIA   -    MD0100PA00X+125925Y+011650X0200Y         S0      
317GND              VIA   -    MD0100PA00X+126750Y+011650X0200Y    R180 S0      
317GND              VIA   -    MD0100PA00X+129569Y+000537X0200Y    R270 S0      
317GND              VIA   -    MD0100PA00X+130223Y+000300X0200Y    R270 S0      
317GND              VIA   -    MD0100PA00X+128062Y+047219X0200Y         S0      
317GND              VIA   -    MD0100PA00X+128346Y+046529X0200Y    R270 S0      
317GND              VIA   -    MD0100PA00X+128346Y+046809X0200Y    R270 S0      
317GND              VIA   -    MD0100PA00X+128174Y+045274X0200Y    R090 S0      
327GND              PU120 -3   M      A01X+127884Y+045408X0100Y0280R090 S1      
317GND              VIA   -    MD0100PA00X+128209Y+044632X0200Y    R270 S0      
317GND              VIA   -    MD0100PA00X+128209Y+044912X0200Y    R270 S0      
317GND              VIA   -    MD0100PA00X+127913Y+045009X0200Y    R090 S0      
317GND              VIA   -    MD0100PA00X+127222Y+043972X0200Y    R270 S0      
317GND              VIA   -    MD0100PA00X+127222Y+044252X0200Y    R270 S0      
317GND              VIA   -    MD0100PA00X+127872Y+040903X0200Y    R270 S0      
327GND              C617  -2          A01X+127872Y+040653X0198Y0197     S1      
317GND              VIA   -    M      A01X+128276Y+040902X0200Y    R270 S2      
017GND              VIA   -    M      A18X+128276Y+040902X0260Y    R270 S2      
017GND                    -    MD0100PA00X+128276Y+040902                       
327GND              C622  -2          A01X+128276Y+040662X0198Y0197R090 S1      
317GND              VIA   -    MD0100PA00X+127598Y+039687X0200Y    R270 S0      
317GND              VIA   -    MD0100PA00X+127139Y+039687X0200Y    R270 S0      
317GND              VIA   -    MD0100PA00X+127541Y+040287X0200Y    R270 S0      
327GND              U84   -10         A01X+127465Y+040004X0090Y0240     S1      
317GND              VIA   -    MD0100PA00X+127135Y+039218X0200Y    R270 S0      
317GND              VIA   -    MD0100PA00X+127594Y+039223X0200Y    R270 S0      
327GND              U84   -TH  M      A01X+127367Y+039452X0670Y0670R090 S1      
317GND              VIA   -    M      A01X+128744Y+037001X0200Y         S2      
017GND              VIA   -    M      A18X+128744Y+037001X0260Y         S2      
017GND                    -    MD0100PA00X+128744Y+037001                       
317GND              VIA   -    MD0100PA00X+128183Y+037484X0200Y    R180 S0      
317GND              VIA   -    MD0100PA00X+128349Y+033950X0200Y         S0      
327GND              U420  -4          A01X+128542Y+033607X0240Y0460R270 S1      
317GND              VIA   -    MD0100PA00X+128204Y+029380X0200Y         S0      
317GND              VIA   -    MD0100PA00X+127954Y+029380X0200Y         S0      
317GND              VIA   -    MD0100PA00X+128645Y+023146X0200Y    R090 S0      
317GND              VIA   -    MD0100PA00X+128645Y+022896X0200Y    R090 S0      
317GND              VIA   -    MD0100PA00X+128645Y+022646X0200Y    R090 S0      
317GND              VIA   -    M      A01X+128645Y+022366X0200Y    R090 S2      
017GND              VIA   -    M      A18X+128645Y+022366X0260Y    R090 S2      
017GND                    -    MD0100PA00X+128645Y+022366                       
317GND              VIA   -    MD0100PA00X+127599Y+022873X0200Y    R090 S0      
317GND              VIA   -    MD0100PA00X+127599Y+023123X0200Y    R090 S0      
317GND              VIA   -    MD0100PA00X+127599Y+022623X0200Y    R090 S0      
317GND              VIA   -    MD0100PA00X+127599Y+022373X0200Y    R090 S0      
317GND              VIA   -    MD0100PA00X+128536Y+013776X0200Y    R180 S0      
317GND              VIA   -    MD0100PA00X+127356Y+013776X0200Y         S0      
317GND              VIA   -    MD0100PA00X+128536Y+012358X0200Y    R180 S0      
317GND              VIA   -    MD0100PA00X+128755Y+028569X0200Y         S0      
317GND              VIA   -    MD0100PA00X+129005Y+028569X0200Y         S0      
317GND              VIA   -    MD0100PA00X+128755Y+028819X0200Y         S0      
317GND              VIA   -    MD0100PA00X+130108Y+029076X0200Y         S0      
327GND              PR7083-2          A01X+130108Y+028806X0198Y0197R090 S1      
317GND              VIA   -    MD0100PA00X+129708Y+029076X0200Y         S0      
327GND              PC874 -2          A01X+129708Y+028806X0198Y0197R090 S1      
317GND              VIA   -    MD0100PA00X+129510Y+024889X0200Y    R180 S0      
317GND              VIA   -    MD0100PA00X+129260Y+024889X0200Y    R180 S0      
317GND              VIA   -    MD0100PA00X+129010Y+024889X0200Y    R180 S0      
317GND              VIA   -    MD0100PA00X+129802Y+025654X0200Y         S0      
327GND              PC875 -2          A01X+129802Y+025954X0198Y0197R270 S1      
317GND              VIA   -    MD0100PA00X+129442Y+023179X0200Y    R090 S0      
317GND              VIA   -    MD0100PA00X+129290Y+023661X0200Y    R180 S0      
317GND              VIA   -    MD0100PA00X+129540Y+023661X0200Y    R180 S0      
317GND              VIA   -    MD0100PA00X+129040Y+023661X0200Y    R180 S0      
317GND              VIA   -    MD0100PA00X+129811Y+022471X0200Y    R090 S0      
317GND              VIA   -    MD0100PA00X+129811Y+022221X0200Y    R090 S0      
317GND              VIA   -    MD0100PA00X+129442Y+022929X0200Y    R090 S0      
317GND              VIA   -    MD0100PA00X+129016Y+022614X0200Y         S0      
317GND              VIA   -    M      A01X+129296Y+022614X0200Y         S2      
017GND              VIA   -    M      A18X+129296Y+022614X0260Y         S2      
017GND                    -    MD0100PA00X+129296Y+022614                       
317GND              VIA   -    M      A01X+129620Y+018873X0200Y         S2      
017GND              VIA   -    M      A18X+129620Y+018873X0260Y         S2      
017GND                    -    MD0100PA00X+129620Y+018873                       
327GND              C331  -2          A01X+129920Y+018740X0198Y0197R090 S1      
317GND              VIA   -    MD0100PA00X+130283Y+018462X0200Y         S0      
327GND              U74   -10         A01X+130569Y+018383X0090Y0240R090 S1      
317GND              VIA   -    MD0100PA00X+129633Y+019194X0200Y         S0      
327GND              C327  -2          A01X+129911Y+019194X0198Y0197R180 S1      
317GND              VIA   -    MD0100PA00X+129477Y+012462X0200Y         S0      
317GND              VIA   -    MD0100PA00X+129976Y+012462X0200Y         S0      
317GND              VIA   -    MD0100PA00X+129976Y+012957X0200Y         S0      
317GND              VIA   -    MD0100PA00X+129477Y+012957X0200Y         S0      
317GND              VIA   -    MD0100PA00X+129477Y+011540X0200Y         S0      
317GND              VIA   -    MD0100PA00X+129477Y+011044X0200Y         S0      
317GND              VIA   -    MD0100PA00X+129976Y+011540X0200Y         S0      
317GND              VIA   -    MD0100PA00X+129976Y+011044X0200Y         S0      
317GND              VIA   -    MD0100PA00X+130192Y+010378X0200Y    R270 S0      
327GND              R443  -1          A01X+130192Y+010135X0198Y0197R270 S1      
317GND              VIA   -    MD0100PA00X+129464Y+009402X0200Y         S0      
317GND              VIA   -    MD0100PA00X+129437Y+010170X0200Y    R090 S0      
317GND              VIA   -    MD0100PA00X+129064Y+009402X0200Y         S0      
317GND              VIA   -    MD0100PA00X+129864Y+009402X0200Y         S0      
317GND              VIA   -    MD0100PA00X+130265Y+009402X0200Y         S0      
317GND              VIA   -    MD0100PA00X+129500Y+004477X0200Y    R270 S0      
317GND              VIA   -    MD0100PA00X+129778Y+003062X0200Y    R270 S0      
327GND              C2734 -1          A01X+130028Y+003062X0198Y0197R090 S1      
317GND              VIA   -    MD0100PA00X+129500Y+002477X0200Y    R270 S0      
317GND              VIA   -    MD0100PA00X+130323Y+002327X0200Y    R270 S0      
327GND              U137  -4          A01X+130699Y+002575X0240Y0460R090 S1      
317GND              VIA   -    MD0100PA00X+130517Y+013669X0200Y         S0      
317GND              VIA   -    MD0100PA00X+131016Y+013669X0200Y         S0      
317GND              VIA   -    MD0100PA00X+130517Y+013173X0200Y         S0      
317GND              VIA   -    MD0100PA00X+130517Y+012251X0200Y         S0      
317GND              VIA   -    MD0100PA00X+131016Y+013173X0200Y         S0      
317GND              VIA   -    MD0100PA00X+131016Y+012251X0200Y         S0      
317GND              VIA   -    MD0100PA00X+131309Y+010362X0200Y    R090 S0      
327GND              U411  -S          A01X+131309Y+010792X0400Y0560R180 S1      
317GND              VIA   -    MD0100PA00X+130517Y+011756X0200Y         S0      
317GND              VIA   -    MD0100PA00X+131016Y+011756X0200Y         S0      
317GND              VIA   -    MD0100PA00X+130772Y+008014X0200Y         S0      
317GND              VIA   -    MD0100PA00X+130772Y+007614X0200Y         S0      
317GND              VIA   -    MD0100PA00X+130772Y+008414X0200Y         S0      
317GND              VIA   -    MD0100PA00X+129027Y+046231X0200Y    R270 S0      
327GND              PC906 -2   M      A01X+128777Y+046231X0198Y0197     S1      
317GND              VIA   -    MD0100PA00X+129027Y+045431X0200Y    R270 S0      
327GND              PR7102-2   M      A01X+128777Y+045431X0198Y0197     S1      
317GND              VIA   -    MD0100PA00X+129027Y+045831X0200Y    R270 S0      
327GND              PR7101-2   M      A01X+128777Y+045831X0198Y0197     S1      
317GND              VIA   -    MD0100PA00X+129976Y+045564X0200Y    R270 S0      
317GND              VIA   -    MD0100PA00X+129976Y+045284X0200Y    R270 S0      
317GND              VIA   -    MD0100PA00X+129976Y+045004X0200Y    R270 S0      
317GND              VIA   -    MD0100PA00X+129009Y+044632X0200Y    R270 S0      
317GND              VIA   -    MD0100PA00X+129009Y+044912X0200Y    R270 S0      
317GND              VIA   -    MD0100PA00X+129116Y+039525X0200Y    R270 S0      
317GND              VIA   -    M      A01X+129941Y+037098X0200Y    R270 S2      
017GND              VIA   -    M      A18X+129941Y+037098X0260Y    R270 S2      
017GND                    -    MD0100PA00X+129941Y+037098                       
317GND              VIA   -    MD0100PA00X+130316Y+037104X0200Y    R270 S0      
317GND              VIA   -    MD0100PA00X+129996Y+035145X0200Y         S0      
327GND              C2681 -2          A01X+130331Y+035145X0280Y0320R090 S1      
317GND              VIA   -    MD0100PA00X+130040Y+034458X0200Y    R180 S0      
317GND              VIA   -    MD0100PA00X+130040Y+033962X0200Y    R180 S0      
317GND              VIA   -    MD0100PA00X+129273Y+033182X0200Y    R180 S0      
317GND              VIA   -    MD0100PA00X+129442Y+032142X0200Y         S0      
327GND              C3993 -1          A01X+129150Y+032142X0198Y0197R090 S1      
317GND              VIA   -    MD0100PA00X+130150Y+032900X0200Y    R180 S0      
317GND              VIA   -    M      A01X+130508Y+029076X0200Y         S2      
017GND              VIA   -    M      A18X+130508Y+029076X0260Y         S2      
017GND                    -    MD0100PA00X+130508Y+029076                       
317GND              VIA   -    MD0100PA00X+129285Y+028569X0200Y         S0      
317GND              VIA   -    MD0100PA00X+129285Y+028819X0200Y         S0      
317GND              VIA   -    MD0100PA00X+129005Y+028819X0200Y         S0      
317GND              VIA   -    MD0100PA00X+130975Y+045284X0200Y    R270 S0      
317GND              VIA   -    MD0100PA00X+130975Y+045004X0200Y    R270 S0      
317GND              VIA   -    M      A01X+130801Y+042394X0200Y         S2      
017GND              VIA   -    M      A18X+130801Y+042394X0260Y         S2      
017GND                    -    MD0100PA00X+130801Y+042394                       
317GND              VIA   -    MD0100PA00X+131081Y+042394X0200Y         S0      
317GND              VIA   -    MD0100PA00X+131331Y+042394X0200Y         S0      
317GND              VIA   -    MD0100PA00X+131581Y+042394X0200Y         S0      
317GND              VIA   -    MD0100PA00X+131587Y+041361X0200Y         S0      
317GND              VIA   -    MD0100PA00X+131337Y+041361X0200Y         S0      
317GND              VIA   -    MD0100PA00X+131087Y+041361X0200Y         S0      
317GND              VIA   -    M      A01X+130807Y+041361X0200Y         S2      
017GND              VIA   -    M      A18X+130807Y+041361X0260Y         S2      
017GND                    -    MD0100PA00X+130807Y+041361                       
317GND              VIA   -    MD0100PA00X+130662Y+040195X0200Y         S0      
317GND              VIA   -    MD0100PA00X+130912Y+039895X0200Y         S0      
317GND              VIA   -    M      A01X+131055Y+040710X0200Y    R270 S2      
017GND              VIA   -    M      A18X+131055Y+040710X0260Y    R270 S2      
017GND                    -    MD0100PA00X+131055Y+040710                       
317GND              VIA   -    MD0100PA00X+131055Y+040990X0200Y    R270 S0      
317GND              VIA   -    MD0100PA00X+131619Y+040264X0200Y         S0      
317GND              VIA   -    MD0100PA00X+131369Y+040264X0200Y         S0      
317GND              VIA   -    MD0100PA00X+130841Y+037090X0200Y         S0      
327GND              C2856 -2          A01X+130841Y+037348X0198Y0197R270 S1      
317GND              VIA   -    MD0100PA00X+131602Y+034989X0200Y         S0      
327GND              U116  -2          A01X+131947Y+034868X0070Y0340R270 S1      
317GND              VIA   -    MD0100PA00X+131758Y+031306X0200Y         S0      
317GND              VIA   -    MD0100PA00X+131207Y+031801X0200Y         S0      
317GND              VIA   -    MD0100PA00X+131457Y+031801X0200Y         S0      
317GND              VIA   -    MD0100PA00X+131565Y+029364X0200Y    R090 S0      
317GND              VIA   -    MD0100PA00X+131565Y+029084X0200Y    R090 S0      
317GND              VIA   -    MD0100PA00X+131565Y+028834X0200Y    R090 S0      
317GND              VIA   -    MD0100PA00X+131315Y+029364X0200Y    R090 S0      
317GND              VIA   -    MD0100PA00X+131315Y+029084X0200Y    R090 S0      
317GND              VIA   -    MD0100PA00X+131315Y+028834X0200Y    R090 S0      
317GND              VIA   -    M      A01X+131116Y+028131X0200Y         S2      
017GND              VIA   -    M      A18X+131116Y+028131X0260Y         S2      
017GND                    -    MD0100PA00X+131116Y+028131                       
317GND              VIA   -    MD0100PA00X+130706Y+027921X0200Y         S0      
317GND              VIA   -    MD0100PA00X+130602Y+025654X0200Y         S0      
327GND              PC877 -2          A01X+130602Y+025954X0198Y0197R270 S1      
317GND              VIA   -    MD0100PA00X+130481Y+020676X0200Y         S0      
317GND              VIA   -    MD0100PA00X+131350Y+018512X0200Y         S0      
317GND              VIA   -    MD0100PA00X+131727Y+019242X0200Y         S0      
317GND              VIA   -    MD0100PA00X+130886Y+018516X0200Y         S0      
317GND              VIA   -    MD0100PA00X+130886Y+018057X0200Y         S0      
317GND              VIA   -    MD0100PA00X+131355Y+018053X0200Y         S0      
327GND              U74   -TH  M      A01X+131120Y+018285X0670Y0670R180 S1      
317GND              VIA   -    MD0100PA00X+132856Y+042039X0200Y    R180 S0      
317GND              VIA   -    MD0100PA00X+132356Y+042039X0200Y    R180 S0      
317GND              VIA   -    MD0100PA00X+132602Y+042424X0200Y    R180 S0      
317GND              VIA   -    MD0100PA00X+132344Y+040824X0200Y    R180 S0      
317GND              VIA   -    MD0100PA00X+132844Y+040824X0200Y    R180 S0      
317GND              VIA   -    MD0100PA00X+132594Y+040824X0200Y    R180 S0      
317GND              VIA   -    MD0100PA00X+132102Y+039666X0200Y    R090 S0      
317GND              VIA   -    MD0100PA00X+132102Y+040166X0200Y    R090 S0      
317GND              VIA   -    MD0100PA00X+132102Y+039916X0200Y    R090 S0      
317GND              VIA   -    MD0100PA00X+133305Y+039677X0200Y    R090 S0      
317GND              VIA   -    MD0100PA00X+133305Y+040177X0200Y    R090 S0      
317GND              VIA   -    MD0100PA00X+133305Y+039927X0200Y    R090 S0      
317GND              VIA   -    MD0100PA00X+132906Y+037095X0200Y    R270 S0      
327GND              R3512 -2          A01X+132906Y+036832X0198Y0197R090 S1      
317GND              VIA   -    MD0100PA00X+133333Y+037090X0200Y    R270 S0      
317GND              VIA   -    MD0100PA00X+132090Y+037100X0200Y    R270 S0      
327GND              R3511 -2          A01X+132090Y+036832X0198Y0197R090 S1      
317GND              VIA   -    MD0100PA00X+132382Y+034887X0200Y         S0      
317GND              VIA   -    MD0100PA00X+133108Y+034887X0200Y         S0      
317GND              VIA   -    MD0100PA00X+132382Y+034162X0200Y         S0      
317GND              VIA   -    MD0100PA00X+132382Y+033435X0200Y         S0      
317GND              VIA   -    MD0100PA00X+133108Y+033435X0200Y         S0      
317GND              VIA   -    MD0100PA00X+133333Y+031306X0200Y         S0      
317GND              VIA   -    MD0100PA00X+132254Y+031306X0200Y         S0      
317GND              VIA   -    MD0100PA00X+132546Y+031006X0200Y         S0      
317GND              VIA   -    MD0100PA00X+133041Y+031006X0200Y         S0      
317GND              VIA   -    MD0100PA00X+132883Y+021686X0200Y         S0      
327GND              PC432 -2          A01X+132625Y+021686X0198Y0197     S1      
317GND              VIA   -    MD0100PA00X+132883Y+022186X0200Y         S0      
327GND              C2875 -2   M      A01X+132625Y+022186X0198Y0197     S1      
317GND              VIA   -    MD0100PA00X+132883Y+020086X0200Y         S0      
317GND              VIA   -    MD0100PA00X+132883Y+021286X0200Y         S0      
317GND              VIA   -    MD0100PA00X+132880Y+018066X0200Y         S0      
327GND              R631  -2          A01X+132616Y+018066X0198Y0197     S1      
317GND              VIA   -    MD0100PA00X+132880Y+017266X0200Y         S0      
327GND              R630  -2          A01X+132616Y+017266X0198Y0197     S1      
317GND              VIA   -    MD0100PA00X+132109Y+011726X0200Y         S0      
327GND              R6209 -1          A01X+132151Y+011449X0198Y0197R180 S1      
317GND              VIA   -    MD0100PA00X+133422Y+003342X0200Y    R090 S0      
327GND              C2739 -1          A01X+133422Y+003598X0198Y0197R180 S1      
317GND              VIA   -    MD0100PA00X+132223Y+000300X0200Y    R270 S0      
317GND              VIA   -    MD0100PA00X+130801Y+046641X0200Y    R090 S0      
327GND              PC471 -2          A01X+130542Y+046641X0198Y0197     S1      
317GND              VIA   -    MD0100PA00X+130975Y+045564X0200Y    R270 S0      
317GND              VIA   -    MD0100PA00X+135480Y+015237X0200Y         S0      
327GND              Q228  -1          A01X+135182Y+015237X0240Y0240R270 S1      
317GND              VIA   -    MD0100PA00X+135590Y+014646X0200Y         S0      
327GND              Q228  -4          A01X+135890Y+014646X0240Y0240R270 S1      
317GND              VIA   -    MD0100PA00X+136223Y+000300X0200Y    R270 S0      
317GND              VIA   -    MD0100PA00X+134648Y+043616X0200Y    R270 S0      
327GND              PU104 -3          A01X+134336Y+043616X0100Y0320R090 S1      
317GND              VIA   -    MD0100PA00X+134790Y+043398X0200Y    R270 S0      
327GND              PU104 -2          A01X+134336Y+043420X0100Y0320R090 S1      
317GND              VIA   -    MD0100PA00X+133829Y+037090X0200Y    R270 S0      
317GND              VIA   -    MD0100PA00X+133838Y+034883X0200Y         S0      
317GND              VIA   -    MD0100PA00X+133838Y+033435X0200Y         S0      
327GND              U116  -49  M      A01X+133108Y+034159X1660Y1660     S1      
317GND              VIA   -    MD0100PA00X+133829Y+031306X0200Y         S0      
317GND              VIA   -    MD0100PA00X+134032Y+015154X0200Y         S0      
327GND              R6112 -2          A01X+134310Y+015154X0198Y0197R180 S1      
317GND              VIA   -    MD0100PA00X+134223Y+000300X0200Y    R270 S0      
317GND              VIA   -    MD0100PA00X+133293Y+046861X0200Y         S0      
327GND              Q217  -4          A01X+133002Y+046861X0240Y0240R270 S1      
317GND              VIA   -    MD0100PA00X+132963Y+045504X0200Y    R270 S0      
317GND              VIA   -    MD0100PA00X+132602Y+042674X0200Y    R180 S0      
327GND              PC807 -2   M      A01X+132602Y+042926X0198Y0197R270 S1      
317GND              VIA   -    MD0100PA00X+132606Y+042039X0200Y    R180 S0      
317GND              VIA   -    M      A01X+138848Y+010225X0200Y    R180 S2      
017GND              VIA   -    M      A18X+138848Y+010225X0260Y    R180 S2      
017GND                    -    MD0100PA00X+138848Y+010225                       
317GND              VIA   -    MD0100PA00X+139958Y+004477X0200Y    R270 S0      
317GND              VIA   -    MD0100PA00X+139958Y+002477X0200Y    R270 S0      
317GND              VIA   -    MD0100PA00X+139822Y+000447X0200Y    R270 S0      
317GND              VIA   -    MD0100PA00X+137538Y+042900X0200Y    R270 S0      
317GND              VIA   -    MD0100PA00X+137375Y+039776X0200Y    R270 S0      
317GND              VIA   -    MD0100PA00X+138417Y+036264X0200Y    R180 S0      
327GND              R1607 -2          A01X+138788Y+036137X0198Y0197R180 S1      
317GND              VIA   -    MD0100PA00X+138445Y+035687X0200Y    R180 S0      
317GND              VIA   -    MD0100PA00X+138425Y+034683X0200Y    R180 S0      
317GND              VIA   -    MD0100PA00X+137823Y+025237X0200Y         S0      
327GND              PR7091-2          A01X+138100Y+025237X0198Y0197R180 S1      
317GND              VIA   -    M      A01X+138640Y+020168X0200Y    R090 S2      
017GND              VIA   -    M      A18X+138640Y+020168X0260Y    R090 S2      
017GND                    -    MD0100PA00X+138640Y+020168                       
317GND              VIA   -    MD0100PA00X+138164Y+020339X0200Y    R180 S0      
317GND              VIA   -    MD0100PA00X+138414Y+020339X0200Y    R180 S0      
317GND              VIA   -    MD0100PA00X+138178Y+019518X0200Y    R180 S0      
317GND              VIA   -    MD0100PA00X+138428Y+019518X0200Y    R180 S0      
317GND              VIA   -    MD0100PA00X+138065Y+013458X0200Y         S0      
327GND              U395  -3          A01X+137754Y+013674X0240Y0240     S1      
317GND              VIA   -    MD0100PA00X+137850Y+013330X0200Y         S0      
327GND              PC963 -2          A01X+137850Y+013090X0198Y0197R090 S1      
317GND              VIA   -    MD0100PA00X+138448Y+010225X0200Y    R180 S0      
317GND              VIA   -    MD0100PA00X+138048Y+010225X0200Y    R180 S0      
327GND              PR7124-2   M      A01X+138048Y+010475X0198Y0197R270 S1      
317GND              VIA   -    MD0100PA00X+137891Y+011078X0200Y         S0      
327GND              PU131 -3   M      A01X+138025Y+011368X0100Y0280     S1      
317GND              VIA   -    MD0100PA00X+137626Y+011339X0200Y         S0      
317GND              VIA   -    MD0100PA00X+138223Y+000300X0200Y    R270 S0      
317GND              VIA   -    MD0100PA00X+136035Y+044710X0200Y    R180 S0      
327GND              PC816 -2   M      A01X+135792Y+044710X0198Y0197     S1      
317GND              VIA   -    MD0100PA00X+136404Y+035568X0200Y    R180 S0      
317GND              VIA   -    MD0100PA00X+136104Y+034780X0200Y    R180 S0      
317GND              VIA   -    MD0100PA00X+136404Y+035072X0200Y    R180 S0      
317GND              VIA   -    MD0100PA00X+136104Y+034285X0200Y    R180 S0      
317GND              VIA   -    MD0100PA00X+136404Y+033993X0200Y    R180 S0      
317GND              VIA   -    MD0100PA00X+136404Y+033497X0200Y    R180 S0      
317GND              VIA   -    MD0100PA00X+136104Y+033206X0200Y    R180 S0      
317GND              VIA   -    MD0100PA00X+136104Y+032710X0200Y    R180 S0      
317GND              VIA   -    MD0100PA00X+138930Y+040844X0200Y    R270 S0      
317GND              VIA   -    MD0100PA00X+138781Y+039714X0200Y    R270 S0      
317GND              VIA   -    MD0100PA00X+139755Y+039048X0200Y    R270 S0      
317GND              VIA   -    MD0100PA00X+138629Y+035022X0200Y    R180 S0      
317GND              VIA   -    MD0100PA00X+138597Y+033679X0200Y    R180 S0      
317GND              VIA   -    MD0100PA00X+138606Y+034120X0200Y    R180 S0      
317GND              VIA   -    MD0100PA00X+138614Y+033198X0200Y    R180 S0      
317GND              VIA   -    MD0100PA00X+138597Y+032769X0200Y    R180 S0      
317GND              VIA   -    MD0100PA00X+138594Y+032322X0200Y    R180 S0      
317GND              VIA   -    MD0100PA00X+139271Y+025320X0200Y         S0      
327GND              Q208  -1          A01X+138972Y+025320X0240Y0240R270 S1      
317GND              VIA   -    MD0100PA00X+138982Y+023859X0200Y    R090 S0      
327GND              C2894 -2          A01X+138982Y+023601X0198Y0197R090 S1      
317GND              VIA   -    MD0100PA00X+139279Y+023612X0200Y    R090 S0      
327GND              PC576 -2          A01X+139535Y+023612X0198Y0197R090 S1      
317GND              VIA   -    MD0100PA00X+139923Y+023869X0200Y    R090 S0      
327GND              PR274 -2          A01X+139923Y+023611X0198Y0197R090 S1      
317GND              VIA   -    MD0100PA00X+140000Y+024729X0200Y         S0      
327GND              Q208  -4          A01X+139681Y+024729X0240Y0240R270 S1      
317GND              VIA   -    MD0100PA00X+138783Y+020684X0200Y    R180 S0      
317GND              VIA   -    MD0100PA00X+139033Y+020684X0200Y    R180 S0      
317GND              VIA   -    MD0100PA00X+138678Y+019518X0200Y    R180 S0      
317GND              VIA   -    MD0100PA00X+138640Y+019888X0200Y    R090 S0      
317GND              VIA   -    M      A01X+138958Y+019518X0200Y    R180 S2      
017GND              VIA   -    M      A18X+138958Y+019518X0260Y    R180 S2      
017GND                    -    MD0100PA00X+138958Y+019518                       
317GND              VIA   -    MD0100PA00X+139803Y+015085X0200Y         S0      
327GND              U372  -S          A01X+139409Y+015330X0400Y0560     S1      
317GND              VIA   -    MD0100PA00X+139725Y+013776X0200Y         S0      
317GND              VIA   -    MD0100PA00X+139514Y+014123X0200Y         S0      
327GND              R5703 -2          A01X+139368Y+013884X0198Y0197     S1      
317GND              VIA   -    MD0100PA00X+139324Y+014601X0200Y         S0      
327GND              C3672 -2          A01X+139074Y+014601X0198Y0197R090 S1      
317GND              VIA   -    MD0100PA00X+139725Y+012358X0200Y         S0      
317GND              VIA   -    MD0100PA00X+139725Y+013067X0200Y         S0      
317GND              VIA   -    MD0100PA00X+138650Y+013330X0200Y         S0      
327GND              PC961 -2          A01X+138650Y+013090X0198Y0197R090 S1      
317GND              VIA   -    MD0100PA00X+139725Y+011650X0200Y         S0      
317GND              VIA   -    MD0100PA00X+139350Y+010650X0200Y         S0      
327GND              C2775 -2   M      A01X+139610Y+010650X0198Y0197R180 S1      
317GND              VIA   -    MD0100PA00X+139450Y+010917X0200Y         S0      
317GND              VIA   -    MD0100PA00X+139150Y+010917X0200Y         S0      
317GND              VIA   -    MD0100PA00X+142690Y+005360X0200Y    R270 S0      
317GND              VIA   -    MD0100PA00X+141195Y+044847X0200Y         S0      
327GND              Q218  -4          A01X+141195Y+045138X0240Y0240R180 S1      
317GND              VIA   -    MD0100PA00X+141389Y+041564X0200Y    R270 S0      
317GND              VIA   -    MD0100PA00X+141140Y+039803X0200Y    R270 S0      
317GND              VIA   -    MD0100PA00X+141683Y+040713X0200Y    R270 S0      
317GND              VIA   -    MD0100PA00X+141635Y+038437X0200Y    R180 S0      
317GND              VIA   -    MD0100PA00X+140867Y+032473X0200Y         S0      
327GND              U125  -12         A01X+140436Y+032644X0120Y0630R270 S1      
317GND              VIA   -    MD0100PA00X+140746Y+023871X0200Y    R090 S0      
327GND              PC555 -2          A01X+140746Y+023613X0198Y0197R090 S1      
317GND              VIA   -    MD0100PA00X+140578Y+021354X0200Y    R090 S0      
317GND              VIA   -    MD0100PA00X+140205Y+013776X0200Y         S0      
317GND              VIA   -    MD0100PA00X+140925Y+013776X0200Y         S0      
317GND              VIA   -    MD0100PA00X+140455Y+013067X0200Y         S0      
317GND              VIA   -    MD0100PA00X+140925Y+012358X0200Y         S0      
317GND              VIA   -    MD0100PA00X+140925Y+013067X0200Y         S0      
317GND              VIA   -    MD0100PA00X+140455Y+012358X0200Y         S0      
317GND              VIA   -    MD0100PA00X+140205Y+012358X0200Y         S0      
317GND              VIA   -    MD0100PA00X+140205Y+013067X0200Y         S0      
317GND              VIA   -    MD0100PA00X+140925Y+011650X0200Y         S0      
317GND              VIA   -    MD0100PA00X+140455Y+010941X0200Y         S0      
317GND              VIA   -    MD0100PA00X+140205Y+011650X0200Y         S0      
317GND              VIA   -    MD0100PA00X+140455Y+011650X0200Y         S0      
317GND              VIA   -    MD0100PA00X+140925Y+010232X0200Y         S0      
317GND              VIA   -    MD0100PA00X+140925Y+010941X0200Y         S0      
317GND              VIA   -    MD0100PA00X+141725Y+010232X0200Y    R180 S0      
317GND              VIA   -    MD0100PA00X+140690Y+005360X0200Y    R270 S0      
317GND              VIA   -    MD0100PA00X+138879Y+042835X0200Y    R270 S0      
317GND              VIA   -    MD0100PA00X+138681Y+041417X0200Y    R270 S0      
317GND              VIA   -    MD0100PA00X+144437Y+010170X0200Y    R090 S0      
317GND              VIA   -    MD0100PA00X+144064Y+009402X0200Y         S0      
317GND              VIA   -    MD0100PA00X+144500Y+004477X0200Y    R270 S0      
317GND              VIA   -    MD0100PA00X+144500Y+002477X0200Y    R270 S0      
317GND              VIA   -    MD0100PA00X+144569Y+000537X0200Y    R270 S0      
317GND              VIA   -    MD0100PA00X+142290Y+046990X0200Y    R180 S0      
327GND              R6052 -2          A01X+142290Y+046749X0198Y0197R090 S1      
317GND              VIA   -    MD0100PA00X+142748Y+047004X0200Y    R180 S0      
327GND              PC915 -2          A01X+142748Y+046763X0198Y0197R090 S1      
317GND              VIA   -    MD0100PA00X+141786Y+045547X0200Y         S0      
327GND              Q218  -1          A01X+141786Y+045846X0240Y0240R180 S1      
317GND              VIA   -    MD0100PA00X+142878Y+044587X0200Y         S0      
327GND              PU121 -3          A01X+143045Y+044856X0100Y0280     S1      
317GND              VIA   -    MD0100PA00X+142420Y+044635X0200Y         S0      
327GND              PC909 -2          A01X+142420Y+044876X0198Y0197R270 S1      
317GND              VIA   -    MD0100PA00X+142702Y+043451X0200Y         S0      
327GND              PR7104-2          A01X+142702Y+043692X0198Y0197R270 S1      
317GND              VIA   -    MD0100PA00X+143102Y+043451X0200Y         S0      
327GND              PR7103-2          A01X+143102Y+043692X0198Y0197R270 S1      
317GND              VIA   -    MD0100PA00X+143204Y+029380X0200Y         S0      
317GND              VIA   -    MD0100PA00X+142954Y+029380X0200Y         S0      
317GND              VIA   -    MD0100PA00X+142599Y+022373X0200Y    R090 S0      
317GND              VIA   -    MD0100PA00X+142599Y+022623X0200Y    R090 S0      
317GND              VIA   -    MD0100PA00X+142599Y+022873X0200Y    R090 S0      
317GND              VIA   -    MD0100PA00X+142599Y+023123X0200Y    R090 S0      
317GND              VIA   -    MD0100PA00X+141872Y+013776X0200Y    R180 S0      
317GND              VIA   -    MD0100PA00X+142352Y+013776X0200Y         S0      
317GND              VIA   -    MD0100PA00X+141872Y+013067X0200Y    R180 S0      
317GND              VIA   -    MD0100PA00X+142736Y+012358X0200Y         S0      
317GND              VIA   -    MD0100PA00X+142736Y+013067X0200Y         S0      
317GND              VIA   -    MD0100PA00X+142170Y+012290X0200Y    R180 S0      
317GND              VIA   -    MD0100PA00X+142736Y+010941X0200Y         S0      
317GND              VIA   -    MD0100PA00X+142736Y+011650X0200Y         S0      
317GND              VIA   -    MD0100PA00X+141750Y+011650X0200Y    R180 S0      
317GND              VIA   -    MD0100PA00X+141750Y+010941X0200Y    R180 S0      
317GND              VIA   -    MD0100PA00X+142722Y+010304X0200Y         S0      
317GND              VIA   -    MD0100PA00X+141771Y+008558X0200Y         S0      
317GND              VIA   -    MD0100PA00X+142026Y+009285X0200Y         S0      
317GND              VIA   -    MD0100PA00X+141771Y+008038X0200Y         S0      
317GND              VIA   -    MD0100PA00X+141771Y+007778X0200Y         S0      
317GND              VIA   -    MD0100PA00X+141771Y+007518X0200Y         S0      
317GND              VIA   -    MD0100PA00X+141771Y+008298X0200Y         S0      
317GND              VIA   -    MD0100PA00X+143755Y+028819X0200Y         S0      
317GND              VIA   -    MD0100PA00X+144708Y+029076X0200Y         S0      
327GND              PC880 -2          A01X+144708Y+028806X0198Y0197R090 S1      
317GND              VIA   -    MD0100PA00X+144285Y+028569X0200Y         S0      
317GND              VIA   -    MD0100PA00X+144285Y+028819X0200Y         S0      
317GND              VIA   -    MD0100PA00X+144005Y+028819X0200Y         S0      
317GND              VIA   -    MD0100PA00X+143755Y+028569X0200Y         S0      
317GND              VIA   -    MD0100PA00X+144005Y+028569X0200Y         S0      
317GND              VIA   -    MD0100PA00X+144510Y+024889X0200Y    R180 S0      
317GND              VIA   -    MD0100PA00X+144260Y+024889X0200Y    R180 S0      
317GND              VIA   -    MD0100PA00X+144010Y+024889X0200Y    R180 S0      
317GND              VIA   -    MD0100PA00X+144803Y+025654X0200Y         S0      
327GND              PC882 -2          A01X+144803Y+025954X0198Y0197R270 S1      
317GND              VIA   -    MD0100PA00X+144540Y+023661X0200Y    R180 S0      
317GND              VIA   -    MD0100PA00X+144442Y+023179X0200Y    R090 S0      
317GND              VIA   -    MD0100PA00X+144290Y+023661X0200Y    R180 S0      
317GND              VIA   -    MD0100PA00X+144040Y+023661X0200Y    R180 S0      
317GND              VIA   -    MD0100PA00X+143645Y+023146X0200Y    R090 S0      
317GND              VIA   -    MD0100PA00X+144811Y+022471X0200Y    R090 S0      
317GND              VIA   -    MD0100PA00X+144811Y+022221X0200Y    R090 S0      
317GND              VIA   -    M      A01X+143645Y+022366X0200Y    R090 S2      
017GND              VIA   -    M      A18X+143645Y+022366X0260Y    R090 S2      
017GND                    -    MD0100PA00X+143645Y+022366                       
317GND              VIA   -    MD0100PA00X+144016Y+022614X0200Y         S0      
317GND              VIA   -    MD0100PA00X+143645Y+022646X0200Y    R090 S0      
317GND              VIA   -    M      A01X+144296Y+022614X0200Y         S2      
017GND              VIA   -    M      A18X+144296Y+022614X0260Y         S2      
017GND                    -    MD0100PA00X+144296Y+022614                       
317GND              VIA   -    MD0100PA00X+144442Y+022929X0200Y    R090 S0      
317GND              VIA   -    MD0100PA00X+143645Y+022896X0200Y    R090 S0      
317GND              VIA   -    M      A01X+144620Y+018873X0200Y         S2      
017GND              VIA   -    M      A18X+144620Y+018873X0260Y         S2      
017GND                    -    MD0100PA00X+144620Y+018873                       
327GND              C334  -2          A01X+144920Y+018740X0198Y0197R090 S1      
317GND              VIA   -    MD0100PA00X+144633Y+019194X0200Y         S0      
327GND              C333  -2          A01X+144911Y+019194X0198Y0197R180 S1      
317GND              VIA   -    MD0100PA00X+144268Y+015154X0200Y         S0      
327GND              R6113 -2          A01X+144546Y+015154X0198Y0197R180 S1      
317GND              VIA   -    MD0100PA00X+143536Y+013776X0200Y    R180 S0      
317GND              VIA   -    MD0100PA00X+144976Y+012957X0200Y         S0      
317GND              VIA   -    MD0100PA00X+143536Y+012358X0200Y    R180 S0      
317GND              VIA   -    MD0100PA00X+143536Y+013067X0200Y    R180 S0      
317GND              VIA   -    MD0100PA00X+144477Y+012957X0200Y         S0      
317GND              VIA   -    MD0100PA00X+144477Y+012462X0200Y         S0      
317GND              VIA   -    MD0100PA00X+144976Y+012462X0200Y         S0      
317GND              VIA   -    MD0100PA00X+143536Y+010232X0200Y    R180 S0      
317GND              VIA   -    MD0100PA00X+144477Y+011540X0200Y         S0      
317GND              VIA   -    MD0100PA00X+144477Y+011044X0200Y         S0      
317GND              VIA   -    MD0100PA00X+144976Y+011044X0200Y         S0      
317GND              VIA   -    MD0100PA00X+144976Y+011540X0200Y         S0      
317GND              VIA   -    MD0100PA00X+143536Y+010941X0200Y    R180 S0      
317GND              VIA   -    MD0100PA00X+143536Y+011650X0200Y    R180 S0      
317GND              VIA   -    MD0100PA00X+144864Y+009402X0200Y         S0      
317GND              VIA   -    MD0100PA00X+144464Y+009402X0200Y         S0      
317GND              VIA   -    MD0100PA00X+145283Y+018462X0200Y         S0      
327GND              U75   -10         A01X+145569Y+018383X0090Y0240R090 S1      
317GND              VIA   -    MD0100PA00X+146350Y+018512X0200Y         S0      
317GND              VIA   -    MD0100PA00X+145886Y+018516X0200Y         S0      
317GND              VIA   -    MD0100PA00X+145886Y+018057X0200Y         S0      
317GND              VIA   -    MD0100PA00X+146355Y+018053X0200Y         S0      
327GND              U75   -TH  M      A01X+146120Y+018285X0670Y0670R180 S1      
317GND              VIA   -    MD0100PA00X+145716Y+015237X0200Y         S0      
327GND              Q229  -1          A01X+145418Y+015237X0240Y0240R270 S1      
317GND              VIA   -    MD0100PA00X+145517Y+013669X0200Y         S0      
317GND              VIA   -    MD0100PA00X+146016Y+013669X0200Y         S0      
317GND              VIA   -    MD0100PA00X+145826Y+014646X0200Y         S0      
327GND              Q229  -4          A01X+146126Y+014646X0240Y0240R270 S1      
317GND              VIA   -    MD0100PA00X+145517Y+013173X0200Y         S0      
317GND              VIA   -    MD0100PA00X+146016Y+012251X0200Y         S0      
317GND              VIA   -    MD0100PA00X+146016Y+013173X0200Y         S0      
317GND              VIA   -    MD0100PA00X+145517Y+012251X0200Y         S0      
317GND              VIA   -    MD0100PA00X+145192Y+010378X0200Y    R270 S0      
327GND              R447  -1          A01X+145192Y+010135X0198Y0197R270 S1      
317GND              VIA   -    MD0100PA00X+146309Y+010362X0200Y    R090 S0      
327GND              U408  -S          A01X+146309Y+010792X0400Y0560R180 S1      
317GND              VIA   -    MD0100PA00X+145517Y+011756X0200Y         S0      
317GND              VIA   -    MD0100PA00X+146016Y+011756X0200Y         S0      
317GND              VIA   -    MD0100PA00X+145265Y+009402X0200Y         S0      
317GND              VIA   -    MD0100PA00X+145772Y+008014X0200Y         S0      
317GND              VIA   -    MD0100PA00X+145772Y+007614X0200Y         S0      
317GND              VIA   -    MD0100PA00X+145772Y+008414X0200Y         S0      
317GND              VIA   -    MD0100PA00X+146268Y+001433X0200Y    R270 S0      
327GND              U417  -4          A01X+146268Y+001764X0240Y0520R270 S1      
317GND              VIA   -    MD0100PA00X+146459Y+000300X0200Y    R270 S0      
317GND              VIA   -    MD0100PA00X+143548Y+047004X0200Y    R180 S0      
327GND              PC910 -2          A01X+143548Y+046763X0198Y0197R090 S1      
317GND              VIA   -    MD0100PA00X+143788Y+044427X0200Y         S0      
317GND              VIA   -    MD0100PA00X+143776Y+044720X0200Y         S0      
317GND              VIA   -    MD0100PA00X+143502Y+043451X0200Y         S0      
327GND              PC914 -2          A01X+143502Y+043692X0198Y0197R270 S1      
317GND              VIA   -    MD0100PA00X+143859Y+038059X0200Y    R270 S0      
317GND              VIA   -    MD0100PA00X+143776Y+036258X0200Y         S0      
327GND              C2710 -2          A01X+143776Y+035967X0198Y0197     S1      
317GND              VIA   -    MD0100PA00X+144962Y+036329X0200Y    R270 S0      
317GND              VIA   -    MD0100PA00X+144057Y+036957X0200Y    R270 S0      
317GND              VIA   -    MD0100PA00X+148137Y+013090X0200Y         S0      
327GND              PC967 -2          A01X+147887Y+013090X0198Y0197R090 S1      
317GND              VIA   -    MD0100PA00X+148127Y+011078X0200Y         S0      
327GND              PU132 -3   M      A01X+148261Y+011368X0100Y0280     S1      
317GND              VIA   -    MD0100PA00X+147862Y+011339X0200Y         S0      
317GND              VIA   -    MD0100PA00X+147109Y+011726X0200Y         S0      
327GND              R6210 -1          A01X+147151Y+011449X0198Y0197R180 S1      
317GND              VIA   -    MD0100PA00X+147249Y+009195X0200Y    R180 S0      
327GND              C2731 -1          A01X+146993Y+009195X0198Y0197R270 S1      
317GND              VIA   -    MD0100PA00X+147530Y+005551X0200Y         S0      
327GND              C2736 -1          A01X+147530Y+005801X0198Y0197R180 S1      
317GND              VIA   -    MD0100PA00X+148046Y+006092X0200Y         S0      
327GND              U138  -4          A01X+148016Y+006472X0240Y0460R180 S1      
317GND              VIA   -    MD0100PA00X+147682Y+004078X0200Y    R090 S0      
327GND              C3871 -2          A01X+147682Y+003824X0198Y0197R180 S1      
317GND              VIA   -    MD0100PA00X+145821Y+040337X0200Y    R270 S0      
317GND              VIA   -    MD0100PA00X+145598Y+039176X0200Y    R270 S0      
317GND              VIA   -    MD0100PA00X+145898Y+035686X0200Y         S0      
327GND              R1609 -2          A01X+145628Y+035686X0198Y0197     S1      
317GND              VIA   -    MD0100PA00X+145119Y+035045X0200Y    R180 S0      
317GND              VIA   -    MD0100PA00X+145139Y+034561X0200Y    R180 S0      
317GND              VIA   -    MD0100PA00X+145130Y+033222X0200Y    R180 S0      
317GND              VIA   -    MD0100PA00X+145134Y+033662X0200Y    R180 S0      
317GND              VIA   -    MD0100PA00X+145127Y+034097X0200Y    R180 S0      
317GND              VIA   -    MD0100PA00X+145133Y+032759X0200Y    R180 S0      
317GND              VIA   -    MD0100PA00X+145122Y+032319X0200Y    R180 S0      
317GND              VIA   -    MD0100PA00X+146315Y+029364X0200Y    R090 S0      
317GND              VIA   -    MD0100PA00X+146315Y+029084X0200Y    R090 S0      
317GND              VIA   -    MD0100PA00X+146315Y+028834X0200Y    R090 S0      
317GND              VIA   -    MD0100PA00X+146565Y+029084X0200Y    R090 S0      
317GND              VIA   -    MD0100PA00X+146565Y+028834X0200Y    R090 S0      
317GND              VIA   -    MD0100PA00X+145108Y+029076X0200Y         S0      
327GND              PR7087-2          A01X+145108Y+028806X0198Y0197R090 S1      
317GND              VIA   -    M      A01X+145508Y+029076X0200Y         S2      
017GND              VIA   -    M      A18X+145508Y+029076X0260Y         S2      
017GND                    -    MD0100PA00X+145508Y+029076                       
317GND              VIA   -    MD0100PA00X+146565Y+029364X0200Y    R090 S0      
317GND              VIA   -    M      A01X+146116Y+028131X0200Y         S2      
017GND              VIA   -    M      A18X+146116Y+028131X0260Y         S2      
017GND                    -    MD0100PA00X+146116Y+028131                       
317GND              VIA   -    MD0100PA00X+145706Y+027921X0200Y         S0      
317GND              VIA   -    MD0100PA00X+145603Y+025654X0200Y         S0      
327GND              PC884 -2          A01X+145603Y+025954X0198Y0197R270 S1      
317GND              VIA   -    MD0100PA00X+145481Y+020676X0200Y         S0      
317GND              VIA   -    M      A01X+149194Y+019518X0200Y    R180 S2      
017GND              VIA   -    M      A18X+149194Y+019518X0260Y    R180 S2      
017GND                    -    MD0100PA00X+149194Y+019518                       
317GND              VIA   -    MD0100PA00X+148414Y+019518X0200Y    R180 S0      
317GND              VIA   -    MD0100PA00X+148301Y+013458X0200Y         S0      
327GND              U394  -3          A01X+147990Y+013674X0240Y0240     S1      
317GND              VIA   -    MD0100PA00X+149751Y+014123X0200Y         S0      
327GND              R5700 -2          A01X+149604Y+013884X0198Y0197     S1      
317GND              VIA   -    MD0100PA00X+149560Y+014601X0200Y         S0      
327GND              C3670 -2          A01X+149310Y+014601X0198Y0197R090 S1      
317GND              VIA   -    MD0100PA00X+148887Y+013330X0200Y         S0      
327GND              PC965 -2          A01X+148887Y+013090X0198Y0197R090 S1      
317GND              VIA   -    MD0100PA00X+149587Y+010650X0200Y         S0      
327GND              C2776 -2   M      A01X+149846Y+010650X0198Y0197R180 S1      
317GND              VIA   -    MD0100PA00X+149686Y+010917X0200Y         S0      
317GND              VIA   -    MD0100PA00X+149386Y+010917X0200Y         S0      
317GND              VIA   -    MD0100PA00X+148284Y+010225X0200Y    R180 S0      
327GND              PR7126-2   M      A01X+148284Y+010475X0198Y0197R270 S1      
317GND              VIA   -    MD0100PA00X+148684Y+010225X0200Y    R180 S0      
327GND              PR7125-2   M      A01X+148684Y+010475X0198Y0197R270 S1      
317GND              VIA   -    M      A01X+149084Y+010225X0200Y    R180 S2      
017GND              VIA   -    M      A18X+149084Y+010225X0260Y    R180 S2      
017GND                    -    MD0100PA00X+149084Y+010225                       
317GND              VIA   -    MD0100PA00X+149862Y+002704X0200Y    R090 S0      
327GND              R5822 -2          A01X+149620Y+002704X0198Y0197     S1      
317GND              VIA   -    MD0100PA00X+149862Y+003504X0200Y    R090 S0      
327GND              R5821 -2          A01X+149620Y+003504X0198Y0197     S1      
317GND              VIA   -    MD0100PA00X+149862Y+001504X0200Y    R090 S0      
327GND              R5823 -2          A01X+149620Y+001504X0198Y0197     S1      
317GND              VIA   -    MD0100PA00X+148459Y+000300X0200Y    R270 S0      
317GND              VIA   -    MD0100PA00X+147390Y+043310X0200Y         S0      
327GND              C4004 -2          A01X+149850Y+044551X0198Y0197R270 S1      
317GND              VIA   -    MD0100PA00X+146929Y+042882X0200Y    R270 S0      
317GND              VIA   -    MD0100PA00X+147240Y+041734X0200Y    R270 S0      
317GND              VIA   -    MD0100PA00X+147336Y+041072X0200Y    R270 S0      
317GND              VIA   -    MD0100PA00X+148059Y+025237X0200Y         S0      
327GND              PR7092-2          A01X+148337Y+025237X0198Y0197R180 S1      
317GND              VIA   -    MD0100PA00X+147883Y+022186X0200Y         S0      
327GND              C2870 -2   M      A01X+147625Y+022186X0198Y0197     S1      
317GND              VIA   -    MD0100PA00X+147883Y+021686X0200Y         S0      
327GND              PC409 -2          A01X+147625Y+021686X0198Y0197     S1      
317GND              VIA   -    MD0100PA00X+147883Y+021286X0200Y         S0      
317GND              VIA   -    MD0100PA00X+147883Y+020086X0200Y         S0      
317GND              VIA   -    MD0100PA00X+146727Y+019242X0200Y         S0      
317GND              VIA   -    MD0100PA00X+147880Y+017266X0200Y         S0      
327GND              R640  -2          A01X+147616Y+017266X0198Y0197     S1      
317GND              VIA   -    MD0100PA00X+147880Y+018066X0200Y         S0      
327GND              R641  -2          A01X+147616Y+018066X0198Y0197     S1      
317GND              VIA   -    MD0100PA00X+150691Y+010941X0200Y         S0      
317GND              VIA   -    MD0100PA00X+150441Y+011650X0200Y         S0      
317GND              VIA   -    MD0100PA00X+150691Y+011650X0200Y         S0      
317GND              VIA   -    MD0100PA00X+149961Y+011650X0200Y         S0      
317GND              VIA   -    MD0100PA00X+151161Y+010232X0200Y         S0      
317GND              VIA   -    MD0100PA00X+151161Y+010941X0200Y         S0      
317GND              VIA   -    MD0100PA00X+151161Y+011650X0200Y         S0      
317GND              VIA   -    MD0100PA00X+150926Y+005360X0200Y    R270 S0      
317GND              VIA   -    MD0100PA00X+150194Y+004477X0200Y    R270 S0      
317GND              VIA   -    MD0100PA00X+150194Y+002477X0200Y    R270 S0      
317GND              VIA   -    MD0100PA00X+150058Y+000447X0200Y    R270 S0      
317GND              VIA   -    MD0100PA00X+148381Y+036852X0200Y    R090 S0      
317GND              VIA   -    MD0100PA00X+148636Y+035420X0200Y         S0      
327GND              R1759 -2          A01X+148997Y+035420X0198Y0197R180 S1      
317GND              VIA   -    MD0100PA00X+148636Y+035870X0200Y         S0      
327GND              R1758 -2          A01X+148997Y+035870X0198Y0197R180 S1      
317GND              VIA   -    MD0100PA00X+148793Y+034739X0200Y    R180 S0      
317GND              VIA   -    MD0100PA00X+149776Y+033654X0200Y    R180 S0      
317GND              VIA   -    MD0100PA00X+148468Y+033839X0200Y    R180 S0      
317GND              VIA   -    MD0100PA00X+148826Y+034292X0200Y    R180 S0      
317GND              VIA   -    MD0100PA00X+148488Y+032938X0200Y    R180 S0      
317GND              VIA   -    MD0100PA00X+148497Y+032502X0200Y    R180 S0      
317GND              VIA   -    MD0100PA00X+148480Y+032036X0200Y    R180 S0      
317GND              VIA   -    MD0100PA00X+149507Y+025320X0200Y         S0      
327GND              Q209  -1          A01X+149208Y+025320X0240Y0240R270 S1      
317GND              VIA   -    MD0100PA00X+149515Y+023612X0200Y    R090 S0      
327GND              PC564 -2          A01X+149771Y+023612X0198Y0197R090 S1      
317GND              VIA   -    MD0100PA00X+149219Y+023859X0200Y    R090 S0      
327GND              C2896 -2          A01X+149219Y+023601X0198Y0197R090 S1      
317GND              VIA   -    MD0100PA00X+148650Y+020339X0200Y    R180 S0      
317GND              VIA   -    MD0100PA00X+148400Y+020339X0200Y    R180 S0      
317GND              VIA   -    MD0100PA00X+149019Y+020684X0200Y    R180 S0      
317GND              VIA   -    MD0100PA00X+149269Y+020684X0200Y    R180 S0      
317GND              VIA   -    M      A01X+148876Y+020168X0200Y    R090 S2      
017GND              VIA   -    M      A18X+148876Y+020168X0260Y    R090 S2      
017GND                    -    MD0100PA00X+148876Y+020168                       
317GND              VIA   -    MD0100PA00X+148914Y+019518X0200Y    R180 S0      
317GND              VIA   -    MD0100PA00X+148876Y+019888X0200Y    R090 S0      
317GND              VIA   -    MD0100PA00X+148664Y+019518X0200Y    R180 S0      
317GND              VIA   -    MD0100PA00X+150705Y+043064X0200Y    R270 S0      
317GND              VIA   -    MD0100PA00X+151205Y+043064X0200Y    R090 S0      
317GND              VIA   -    MD0100PA00X+150705Y+043986X0200Y    R270 S0      
317GND              VIA   -    MD0100PA00X+151205Y+043986X0200Y    R090 S0      
317GND              VIA   -    MD0100PA00X+151205Y+041646X0200Y    R090 S0      
317GND              VIA   -    MD0100PA00X+150705Y+042568X0200Y    R270 S0      
317GND              VIA   -    MD0100PA00X+151205Y+042568X0200Y    R090 S0      
317GND              VIA   -    MD0100PA00X+150705Y+041151X0200Y    R270 S0      
317GND              VIA   -    MD0100PA00X+150705Y+041646X0200Y    R270 S0      
317GND              VIA   -    MD0100PA00X+151205Y+041151X0200Y    R090 S0      
317GND              VIA   -    MD0100PA00X+151445Y+039734X0200Y    R090 S0      
317GND              VIA   -    MD0100PA00X+150945Y+039734X0200Y    R270 S0      
317GND              VIA   -    MD0100PA00X+151445Y+040229X0200Y    R090 S0      
317GND              VIA   -    MD0100PA00X+150945Y+040229X0200Y    R270 S0      
317GND              VIA   -    MD0100PA00X+150181Y+032377X0200Y         S0      
327GND              U142  -12         A01X+150646Y+032377X0120Y0630R270 S1      
317GND              VIA   -    MD0100PA00X+150048Y+029573X0200Y    R180 S0      
317GND              VIA   -    MD0100PA00X+150159Y+023869X0200Y    R090 S0      
327GND              PR278 -2          A01X+150159Y+023611X0198Y0197R090 S1      
317GND              VIA   -    MD0100PA00X+150236Y+024729X0200Y         S0      
327GND              Q209  -4          A01X+149917Y+024729X0240Y0240R270 S1      
317GND              VIA   -    MD0100PA00X+150982Y+023871X0200Y    R090 S0      
327GND              PC567 -2          A01X+150982Y+023613X0198Y0197R090 S1      
317GND              VIA   -    MD0100PA00X+150814Y+021354X0200Y    R090 S0      
317GND              VIA   -    MD0100PA00X+150039Y+015085X0200Y         S0      
327GND              U374  -S          A01X+149645Y+015330X0400Y0560     S1      
317GND              VIA   -    MD0100PA00X+150441Y+013776X0200Y         S0      
317GND              VIA   -    MD0100PA00X+149961Y+013776X0200Y         S0      
317GND              VIA   -    MD0100PA00X+151161Y+013776X0200Y         S0      
317GND              VIA   -    MD0100PA00X+151161Y+013067X0200Y         S0      
317GND              VIA   -    MD0100PA00X+150691Y+012358X0200Y         S0      
317GND              VIA   -    MD0100PA00X+150441Y+012358X0200Y         S0      
317GND              VIA   -    MD0100PA00X+150441Y+013067X0200Y         S0      
317GND              VIA   -    MD0100PA00X+150691Y+013067X0200Y         S0      
317GND              VIA   -    MD0100PA00X+149961Y+012358X0200Y         S0      
317GND              VIA   -    MD0100PA00X+149961Y+013067X0200Y         S0      
317GND              VIA   -    MD0100PA00X+151161Y+012358X0200Y         S0      
317GND              VIA   -    MD0100PA00X+152245Y+041857X0200Y    R090 S0      
317GND              VIA   -    MD0100PA00X+152245Y+042352X0200Y    R090 S0      
317GND              VIA   -    MD0100PA00X+151746Y+042352X0200Y    R270 S0      
317GND              VIA   -    MD0100PA00X+151746Y+041857X0200Y    R270 S0      
317GND              VIA   -    MD0100PA00X+152245Y+040935X0200Y    R090 S0      
317GND              VIA   -    MD0100PA00X+152245Y+040440X0200Y    R090 S0      
317GND              VIA   -    MD0100PA00X+152245Y+039518X0200Y    R090 S0      
317GND              VIA   -    MD0100PA00X+151746Y+040935X0200Y    R270 S0      
317GND              VIA   -    MD0100PA00X+151746Y+040440X0200Y    R270 S0      
317GND              VIA   -    MD0100PA00X+151746Y+039518X0200Y    R270 S0      
317GND              VIA   -    MD0100PA00X+152245Y+039022X0200Y    R090 S0      
317GND              VIA   -    MD0100PA00X+151746Y+039022X0200Y    R270 S0      
317GND              VIA   -    MD0100PA00X+151578Y+035159X0200Y    R090 S0      
317GND              VIA   -    MD0100PA00X+152836Y+023123X0200Y    R090 S0      
317GND              VIA   -    MD0100PA00X+152836Y+022623X0200Y    R090 S0      
317GND              VIA   -    MD0100PA00X+152836Y+022373X0200Y    R090 S0      
317GND              VIA   -    MD0100PA00X+152836Y+022873X0200Y    R090 S0      
317GND              VIA   -    MD0100PA00X+152108Y+013776X0200Y    R180 S0      
317GND              VIA   -    MD0100PA00X+152631Y+013776X0200Y         S0      
317GND              VIA   -    MD0100PA00X+152109Y+013067X0200Y    R180 S0      
317GND              VIA   -    MD0100PA00X+152972Y+012358X0200Y         S0      
317GND              VIA   -    MD0100PA00X+152972Y+013067X0200Y         S0      
317GND              VIA   -    MD0100PA00X+152003Y+012458X0200Y    R180 S0      
317GND              VIA   -    MD0100PA00X+152972Y+010941X0200Y         S0      
317GND              VIA   -    MD0100PA00X+152972Y+011650X0200Y         S0      
317GND              VIA   -    MD0100PA00X+151986Y+011650X0200Y    R180 S0      
317GND              VIA   -    MD0100PA00X+151986Y+010941X0200Y    R180 S0      
317GND              VIA   -    MD0100PA00X+151961Y+010232X0200Y    R180 S0      
317GND              VIA   -    MD0100PA00X+152959Y+010304X0200Y         S0      
317GND              VIA   -    MD0100PA00X+152007Y+008558X0200Y         S0      
317GND              VIA   -    MD0100PA00X+152263Y+009285X0200Y         S0      
317GND              VIA   -    MD0100PA00X+152007Y+008038X0200Y         S0      
317GND              VIA   -    MD0100PA00X+152007Y+007778X0200Y         S0      
317GND              VIA   -    MD0100PA00X+152007Y+007518X0200Y         S0      
317GND              VIA   -    MD0100PA00X+152007Y+008298X0200Y         S0      
317GND              VIA   -    MD0100PA00X+152926Y+005360X0200Y    R270 S0      
317GND              VIA   -    MD0100PA00X+151205Y+046861X0200Y    R090 S0      
317GND              VIA   -    MD0100PA00X+150705Y+046861X0200Y    R270 S0      
317GND              VIA   -    MD0100PA00X+150786Y+045075X0200Y         S0      
327GND              U39   -S          A01X+151184Y+045075X0400Y0560     S1      
317GND              VIA   -    MD0100PA00X+150705Y+044481X0200Y    R270 S0      
317GND              VIA   -    MD0100PA00X+151205Y+044481X0200Y    R090 S0      
317GND              VIA   -    MD0100PA00X+154496Y+024889X0200Y    R180 S0      
317GND              VIA   -    MD0100PA00X+154246Y+024889X0200Y    R180 S0      
317GND              VIA   -    MD0100PA00X+154678Y+023179X0200Y    R090 S0      
317GND              VIA   -    MD0100PA00X+154526Y+023661X0200Y    R180 S0      
317GND              VIA   -    MD0100PA00X+154276Y+023661X0200Y    R180 S0      
317GND              VIA   -    M      A01X+154532Y+022614X0200Y         S2      
017GND              VIA   -    M      A18X+154532Y+022614X0260Y         S2      
017GND                    -    MD0100PA00X+154532Y+022614                       
317GND              VIA   -    M      A01X+153881Y+022366X0200Y    R090 S2      
017GND              VIA   -    M      A18X+153881Y+022366X0260Y    R090 S2      
017GND                    -    MD0100PA00X+153881Y+022366                       
317GND              VIA   -    MD0100PA00X+154678Y+022929X0200Y    R090 S0      
317GND              VIA   -    MD0100PA00X+153881Y+023146X0200Y    R090 S0      
317GND              VIA   -    MD0100PA00X+153881Y+022896X0200Y    R090 S0      
317GND              VIA   -    MD0100PA00X+154252Y+022614X0200Y         S0      
317GND              VIA   -    MD0100PA00X+153881Y+022646X0200Y    R090 S0      
327GND              C337  -2          A01X+155156Y+018740X0198Y0197R090 S1      
317GND              VIA   -    M      A01X+154856Y+018873X0200Y         S2      
017GND              VIA   -    M      A18X+154856Y+018873X0260Y         S2      
017GND                    -    MD0100PA00X+154856Y+018873                       
317GND              VIA   -    MD0100PA00X+154504Y+015154X0200Y         S0      
327GND              R6124 -2          A01X+154782Y+015154X0198Y0197R180 S1      
317GND              VIA   -    MD0100PA00X+153772Y+013776X0200Y    R180 S0      
317GND              VIA   -    MD0100PA00X+154713Y+012462X0200Y         S0      
317GND              VIA   -    MD0100PA00X+153772Y+012358X0200Y    R180 S0      
317GND              VIA   -    MD0100PA00X+153772Y+013067X0200Y    R180 S0      
317GND              VIA   -    MD0100PA00X+154713Y+012957X0200Y         S0      
317GND              VIA   -    MD0100PA00X+153772Y+010232X0200Y    R180 S0      
317GND              VIA   -    MD0100PA00X+153772Y+010941X0200Y    R180 S0      
317GND              VIA   -    MD0100PA00X+153772Y+011650X0200Y    R180 S0      
317GND              VIA   -    MD0100PA00X+154713Y+011540X0200Y         S0      
317GND              VIA   -    MD0100PA00X+154713Y+011044X0200Y         S0      
317GND              VIA   -    MD0100PA00X+154673Y+010170X0200Y    R090 S0      
317GND              VIA   -    MD0100PA00X+154300Y+009402X0200Y         S0      
317GND              VIA   -    MD0100PA00X+154700Y+009402X0200Y         S0      
317GND              VIA   -    MD0100PA00X+154737Y+004477X0200Y    R270 S0      
317GND              VIA   -    MD0100PA00X+152245Y+043274X0200Y    R090 S0      
317GND              VIA   -    MD0100PA00X+151746Y+043770X0200Y    R270 S0      
317GND              VIA   -    MD0100PA00X+151746Y+043274X0200Y    R270 S0      
317GND              VIA   -    MD0100PA00X+152245Y+043770X0200Y    R090 S0      
317GND              VIA   -    MD0100PA00X+156123Y+018057X0200Y         S0      
317GND              VIA   -    MD0100PA00X+155953Y+015237X0200Y         S0      
327GND              Q230  -1          A01X+155654Y+015237X0240Y0240R270 S1      
317GND              VIA   -    MD0100PA00X+156252Y+013669X0200Y         S0      
317GND              VIA   -    MD0100PA00X+155753Y+013669X0200Y         S0      
317GND              VIA   -    MD0100PA00X+156062Y+014646X0200Y         S0      
327GND              Q230  -4          A01X+156363Y+014646X0240Y0240R270 S1      
317GND              VIA   -    MD0100PA00X+156252Y+013173X0200Y         S0      
317GND              VIA   -    MD0100PA00X+155753Y+012251X0200Y         S0      
317GND              VIA   -    MD0100PA00X+155753Y+013173X0200Y         S0      
317GND              VIA   -    MD0100PA00X+155212Y+012462X0200Y         S0      
317GND              VIA   -    MD0100PA00X+155212Y+012957X0200Y         S0      
317GND              VIA   -    MD0100PA00X+156252Y+012251X0200Y         S0      
317GND              VIA   -    MD0100PA00X+155428Y+010378X0200Y    R270 S0      
327GND              R449  -1          A01X+155428Y+010135X0198Y0197R270 S1      
317GND              VIA   -    MD0100PA00X+155212Y+011044X0200Y         S0      
317GND              VIA   -    MD0100PA00X+155212Y+011540X0200Y         S0      
317GND              VIA   -    MD0100PA00X+155753Y+011756X0200Y         S0      
317GND              VIA   -    MD0100PA00X+156252Y+011756X0200Y         S0      
317GND              VIA   -    MD0100PA00X+155100Y+009402X0200Y         S0      
317GND              VIA   -    MD0100PA00X+155501Y+009402X0200Y         S0      
317GND              VIA   -    MD0100PA00X+156008Y+008014X0200Y         S0      
317GND              VIA   -    MD0100PA00X+156008Y+007614X0200Y         S0      
317GND              VIA   -    MD0100PA00X+156008Y+008414X0200Y         S0      
317GND              VIA   -    MD0100PA00X+154128Y+035455X0200Y         S0      
327GND              C2743 -2          A01X+154128Y+035205X0198Y0197     S1      
317GND              VIA   -    MD0100PA00X+153440Y+029380X0200Y         S0      
317GND              VIA   -    MD0100PA00X+154522Y+028569X0200Y         S0      
317GND              VIA   -    MD0100PA00X+154522Y+028819X0200Y         S0      
317GND              VIA   -    MD0100PA00X+154242Y+028819X0200Y         S0      
317GND              VIA   -    MD0100PA00X+153992Y+028569X0200Y         S0      
317GND              VIA   -    MD0100PA00X+154242Y+028569X0200Y         S0      
317GND              VIA   -    MD0100PA00X+153992Y+028819X0200Y         S0      
317GND              VIA   -    MD0100PA00X+153190Y+029380X0200Y         S0      
317GND              VIA   -    MD0100PA00X+154863Y+039624X0200Y         S0      
317GND              VIA   -    MD0100PA00X+156178Y+039624X0200Y         S0      
317GND              VIA   -    MD0100PA00X+155771Y+040491X0200Y    R180 S0      
317GND              VIA   -    MD0100PA00X+155643Y+039624X0200Y    R180 S0      
317GND              VIA   -    MD0100PA00X+154863Y+041041X0200Y         S0      
317GND              VIA   -    MD0100PA00X+154863Y+040333X0200Y         S0      
317GND              VIA   -    MD0100PA00X+154863Y+038915X0200Y         S0      
317GND              VIA   -    MD0100PA00X+156325Y+038915X0200Y         S0      
317GND              VIA   -    MD0100PA00X+155643Y+038915X0200Y    R180 S0      
317GND              VIA   -    MD0100PA00X+155440Y+035236X0200Y         S0      
327GND              R1761 -2          A01X+155145Y+035236X0198Y0197     S1      
317GND              VIA   -    MD0100PA00X+155635Y+034564X0200Y    R180 S0      
317GND              VIA   -    MD0100PA00X+155650Y+034096X0200Y    R180 S0      
317GND              VIA   -    MD0100PA00X+155638Y+033692X0200Y    R180 S0      
317GND              VIA   -    MD0100PA00X+155644Y+033202X0200Y    R180 S0      
317GND              VIA   -    MD0100PA00X+155629Y+032781X0200Y    R180 S0      
317GND              VIA   -    MD0100PA00X+154153Y+032285X0200Y    R180 S0      
317GND              VIA   -    MD0100PA00X+155615Y+031860X0200Y    R180 S0      
317GND              VIA   -    MD0100PA00X+154797Y+030491X0200Y    R180 S0      
317GND              VIA   -    M      A01X+155744Y+029076X0200Y         S2      
017GND              VIA   -    M      A18X+155744Y+029076X0260Y         S2      
017GND                    -    MD0100PA00X+155744Y+029076                       
317GND              VIA   -    MD0100PA00X+155344Y+029076X0200Y         S0      
327GND              PR7089-2          A01X+155344Y+028806X0198Y0197R090 S1      
317GND              VIA   -    MD0100PA00X+154944Y+029076X0200Y         S0      
327GND              PC885 -2          A01X+154944Y+028806X0198Y0197R090 S1      
317GND              VIA   -    M      A01X+156352Y+028131X0200Y         S2      
017GND              VIA   -    M      A18X+156352Y+028131X0260Y         S2      
017GND                    -    MD0100PA00X+156352Y+028131                       
317GND              VIA   -    MD0100PA00X+155942Y+027921X0200Y         S0      
317GND              VIA   -    MD0100PA00X+154746Y+024889X0200Y    R180 S0      
317GND              VIA   -    MD0100PA00X+155839Y+025654X0200Y         S0      
327GND              PC887 -2          A01X+155839Y+025954X0198Y0197R270 S1      
317GND              VIA   -    MD0100PA00X+155039Y+025654X0200Y         S0      
327GND              PC881 -2          A01X+155039Y+025954X0198Y0197R270 S1      
317GND              VIA   -    MD0100PA00X+154776Y+023661X0200Y    R180 S0      
317GND              VIA   -    MD0100PA00X+155047Y+022471X0200Y    R090 S0      
317GND              VIA   -    MD0100PA00X+155047Y+022221X0200Y    R090 S0      
317GND              VIA   -    MD0100PA00X+155717Y+020676X0200Y         S0      
317GND              VIA   -    MD0100PA00X+156123Y+018516X0200Y         S0      
317GND              VIA   -    MD0100PA00X+155519Y+018462X0200Y         S0      
327GND              U76   -10         A01X+155806Y+018383X0090Y0240R090 S1      
317GND              VIA   -    MD0100PA00X+154869Y+019194X0200Y         S0      
327GND              C406  -2          A01X+155148Y+019194X0198Y0197R180 S1      
317GND              VIA   -    MD0100PA00X+156551Y+029084X0200Y    R090 S0      
317GND              VIA   -    MD0100PA00X+156551Y+029364X0200Y    R090 S0      
317GND              VIA   -    MD0100PA00X+156801Y+028834X0200Y    R090 S0      
317GND              VIA   -    MD0100PA00X+156801Y+029084X0200Y    R090 S0      
317GND              VIA   -    MD0100PA00X+156801Y+029364X0200Y    R090 S0      
317GND              VIA   -    MD0100PA00X+156551Y+028834X0200Y    R090 S0      
317GND              VIA   -    MD0100PA00X+156586Y+018512X0200Y         S0      
317GND              VIA   -    MD0100PA00X+156963Y+019242X0200Y         S0      
317GND              VIA   -    MD0100PA00X+156591Y+018053X0200Y         S0      
327GND              U76   -TH  M      A01X+156357Y+018285X0670Y0670R180 S1      
317GND              VIA   -    MD0100PA00X+156545Y+010362X0200Y    R090 S0      
327GND              U409  -S          A01X+156545Y+010792X0400Y0560R180 S1      
317GND              VIA   -    MD0100PA00X+157346Y+011726X0200Y         S0      
327GND              R6211 -1          A01X+157388Y+011449X0198Y0197R180 S1      
317GND              VIA   -    MD0100PA00X+157485Y+009195X0200Y    R180 S0      
327GND              C2741 -1          A01X+157229Y+009195X0198Y0197R270 S1      
317GND              VIA   -    MD0100PA00X+158033Y+005745X0200Y         S0      
327GND              C2738 -1          A01X+157766Y+005801X0198Y0197R180 S1      
317GND              VIA   -    MD0100PA00X+154863Y+046754X0200Y         S0      
317GND              VIA   -    MD0100PA00X+155643Y+046754X0200Y    R180 S0      
317GND              VIA   -    MD0100PA00X+154863Y+044585X0200Y         S0      
317GND              VIA   -    MD0100PA00X+155816Y+044585X0200Y    R180 S0      
317GND              VIA   -    MD0100PA00X+154863Y+043167X0200Y         S0      
317GND              VIA   -    MD0100PA00X+154863Y+043876X0200Y         S0      
317GND              VIA   -    MD0100PA00X+154863Y+042459X0200Y         S0      
317GND              VIA   -    MD0100PA00X+154863Y+041750X0200Y         S0      
317GND              VIA   -    MD0100PA00X+155785Y+042630X0200Y    R180 S0      
317GND              VIA   -    MD0100PA00X+155666Y+041257X0200Y    R180 S0      
317GND              VIA   -    M      A01X+159320Y+010225X0200Y    R180 S2      
017GND              VIA   -    M      A18X+159320Y+010225X0260Y    R180 S2      
017GND                    -    MD0100PA00X+159320Y+010225                       
317GND              VIA   -    MD0100PA00X+158282Y+006092X0200Y         S0      
327GND              U139  -4          A01X+158252Y+006472X0240Y0460R180 S1      
317GND              VIA   -    MD0100PA00X+157454Y+046754X0200Y    R180 S0      
317GND              VIA   -    MD0100PA00X+156674Y+046754X0200Y         S0      
317GND              VIA   -    MD0100PA00X+157454Y+044585X0200Y    R180 S0      
317GND              VIA   -    MD0100PA00X+157934Y+044585X0200Y         S0      
317GND              VIA   -    MD0100PA00X+156757Y+044795X0200Y         S0      
317GND              VIA   -    MD0100PA00X+157454Y+043167X0200Y    R180 S0      
317GND              VIA   -    MD0100PA00X+157934Y+043876X0200Y         S0      
317GND              VIA   -    MD0100PA00X+157934Y+043167X0200Y         S0      
317GND              VIA   -    MD0100PA00X+157454Y+043876X0200Y    R180 S0      
317GND              VIA   -    MD0100PA00X+156554Y+043645X0200Y         S0      
317GND              VIA   -    MD0100PA00X+156593Y+042983X0200Y         S0      
317GND              VIA   -    MD0100PA00X+157454Y+042459X0200Y    R180 S0      
317GND              VIA   -    MD0100PA00X+157454Y+041750X0200Y    R180 S0      
317GND              VIA   -    MD0100PA00X+157934Y+042459X0200Y         S0      
317GND              VIA   -    MD0100PA00X+157934Y+041750X0200Y         S0      
317GND              VIA   -    MD0100PA00X+156586Y+042286X0200Y         S0      
317GND              VIA   -    MD0100PA00X+156656Y+041482X0200Y         S0      
317GND              VIA   -    MD0100PA00X+157454Y+041041X0200Y    R180 S0      
317GND              VIA   -    MD0100PA00X+157454Y+040333X0200Y    R180 S0      
317GND              VIA   -    MD0100PA00X+157454Y+039624X0200Y    R180 S0      
317GND              VIA   -    MD0100PA00X+157934Y+041041X0200Y         S0      
317GND              VIA   -    MD0100PA00X+157934Y+040333X0200Y         S0      
317GND              VIA   -    MD0100PA00X+157934Y+039624X0200Y         S0      
317GND              VIA   -    MD0100PA00X+157454Y+038915X0200Y    R180 S0      
317GND              VIA   -    MD0100PA00X+157162Y+033355X0200Y         S0      
327GND              C3994 -1          A01X+157162Y+033620X0198Y0197     S1      
317GND              VIA   -    MD0100PA00X+157484Y+033884X0200Y    R180 S0      
317GND              VIA   -    MD0100PA00X+158664Y+042459X0200Y         S0      
317GND              VIA   -    MD0100PA00X+158184Y+042459X0200Y         S0      
317GND              VIA   -    MD0100PA00X+158184Y+041750X0200Y         S0      
317GND              VIA   -    MD0100PA00X+158664Y+041750X0200Y         S0      
317GND              VIA   -    MD0100PA00X+158664Y+040333X0200Y         S0      
317GND              VIA   -    MD0100PA00X+158664Y+039624X0200Y         S0      
317GND              VIA   -    MD0100PA00X+158184Y+039624X0200Y         S0      
317GND              VIA   -    MD0100PA00X+158664Y+041041X0200Y         S0      
317GND              VIA   -    MD0100PA00X+158184Y+041041X0200Y         S0      
317GND              VIA   -    MD0100PA00X+158184Y+040333X0200Y         S0      
317GND              VIA   -    MD0100PA00X+158184Y+038915X0200Y         S0      
317GND              VIA   -    MD0100PA00X+158664Y+038915X0200Y         S0      
317GND              VIA   -    MD0100PA00X+159329Y+033988X0200Y    R180 S0      
317GND              VIA   -    MD0100PA00X+158295Y+025237X0200Y         S0      
327GND              PR7097-2          A01X+158573Y+025237X0198Y0197R180 S1      
317GND              VIA   -    MD0100PA00X+159455Y+023859X0200Y    R090 S0      
327GND              C2898 -2          A01X+159455Y+023601X0198Y0197R090 S1      
317GND              VIA   -    MD0100PA00X+158119Y+021686X0200Y         S0      
327GND              PC445 -2          A01X+157861Y+021686X0198Y0197     S1      
317GND              VIA   -    MD0100PA00X+158119Y+022186X0200Y         S0      
327GND              C2872 -2   M      A01X+157861Y+022186X0198Y0197     S1      
317GND              VIA   -    MD0100PA00X+159255Y+020684X0200Y    R180 S0      
317GND              VIA   -    MD0100PA00X+159505Y+020684X0200Y    R180 S0      
317GND              VIA   -    M      A01X+159112Y+020168X0200Y    R090 S2      
017GND              VIA   -    M      A18X+159112Y+020168X0260Y    R090 S2      
017GND                    -    MD0100PA00X+159112Y+020168                       
317GND              VIA   -    MD0100PA00X+158886Y+020339X0200Y    R180 S0      
317GND              VIA   -    MD0100PA00X+158636Y+020339X0200Y    R180 S0      
317GND              VIA   -    MD0100PA00X+158119Y+020086X0200Y         S0      
317GND              VIA   -    MD0100PA00X+158119Y+021286X0200Y         S0      
317GND              VIA   -    MD0100PA00X+159150Y+019518X0200Y    R180 S0      
317GND              VIA   -    MD0100PA00X+159112Y+019888X0200Y    R090 S0      
317GND              VIA   -    MD0100PA00X+158900Y+019518X0200Y    R180 S0      
317GND              VIA   -    M      A01X+159430Y+019518X0200Y    R180 S2      
017GND              VIA   -    M      A18X+159430Y+019518X0260Y    R180 S2      
017GND                    -    MD0100PA00X+159430Y+019518                       
317GND              VIA   -    MD0100PA00X+158650Y+019518X0200Y    R180 S0      
317GND              VIA   -    MD0100PA00X+158116Y+017266X0200Y         S0      
327GND              R651  -2          A01X+157852Y+017266X0198Y0197     S1      
317GND              VIA   -    MD0100PA00X+158116Y+018066X0200Y         S0      
327GND              R652  -2          A01X+157852Y+018066X0198Y0197     S1      
317GND              VIA   -    MD0100PA00X+158538Y+013458X0200Y         S0      
327GND              U397  -3          A01X+158226Y+013674X0240Y0240     S1      
317GND              VIA   -    MD0100PA00X+158323Y+013330X0200Y         S0      
327GND              PC973 -2          A01X+158323Y+013090X0198Y0197R090 S1      
317GND              VIA   -    MD0100PA00X+159123Y+013330X0200Y         S0      
327GND              PC971 -2          A01X+159123Y+013090X0198Y0197R090 S1      
317GND              VIA   -    MD0100PA00X+158364Y+011078X0200Y         S0      
327GND              PU133 -3   M      A01X+158497Y+011368X0100Y0280     S1      
317GND              VIA   -    MD0100PA00X+158099Y+011339X0200Y         S0      
317GND              VIA   -    MD0100PA00X+158920Y+010225X0200Y    R180 S0      
327GND              PR7127-2   M      A01X+158920Y+010475X0198Y0197R270 S1      
317GND              VIA   -    MD0100PA00X+158520Y+010225X0200Y    R180 S0      
327GND              PR7129-2   M      A01X+158520Y+010475X0198Y0197R270 S1      
317GND              VIA   -    MD0100PA00X+161050Y+021354X0200Y    R090 S0      
317GND              VIA   -    MD0100PA00X+160276Y+015085X0200Y         S0      
327GND              U376  -S          A01X+159881Y+015330X0400Y0560     S1      
317GND              VIA   -    MD0100PA00X+160197Y+013776X0200Y         S0      
317GND              VIA   -    MD0100PA00X+159987Y+014123X0200Y         S0      
327GND              R5711 -2          A01X+159840Y+013884X0198Y0197     S1      
317GND              VIA   -    MD0100PA00X+159796Y+014601X0200Y         S0      
327GND              C3674 -2          A01X+159546Y+014601X0198Y0197R090 S1      
317GND              VIA   -    MD0100PA00X+160677Y+013776X0200Y         S0      
317GND              VIA   -    MD0100PA00X+160677Y+013067X0200Y         S0      
317GND              VIA   -    MD0100PA00X+160927Y+013067X0200Y         S0      
317GND              VIA   -    MD0100PA00X+160927Y+012358X0200Y         S0      
317GND              VIA   -    MD0100PA00X+160677Y+012358X0200Y         S0      
317GND              VIA   -    MD0100PA00X+160197Y+013067X0200Y         S0      
317GND              VIA   -    MD0100PA00X+160197Y+012358X0200Y         S0      
317GND              VIA   -    MD0100PA00X+159823Y+010650X0200Y         S0      
327GND              C2777 -2   M      A01X+160082Y+010650X0198Y0197R180 S1      
317GND              VIA   -    MD0100PA00X+159922Y+010917X0200Y         S0      
317GND              VIA   -    MD0100PA00X+159622Y+010917X0200Y         S0      
317GND              VIA   -    MD0100PA00X+160677Y+011650X0200Y         S0      
317GND              VIA   -    MD0100PA00X+160927Y+011650X0200Y         S0      
317GND              VIA   -    MD0100PA00X+160197Y+011650X0200Y         S0      
317GND              VIA   -    MD0100PA00X+160927Y+010941X0200Y         S0      
317GND              VIA   -    MD0100PA00X+161162Y+005360X0200Y    R270 S0      
317GND              VIA   -    MD0100PA00X+160430Y+004477X0200Y    R270 S0      
317GND              VIA   -    MD0100PA00X+158184Y+046754X0200Y         S0      
317GND              VIA   -    MD0100PA00X+158664Y+046754X0200Y         S0      
317GND              VIA   -    MD0100PA00X+158184Y+043167X0200Y         S0      
317GND              VIA   -    MD0100PA00X+158664Y+043167X0200Y         S0      
317GND              VIA   -    MD0100PA00X+158664Y+043876X0200Y         S0      
317GND              VIA   -    MD0100PA00X+158184Y+043876X0200Y         S0      
317GND              VIA   -    MD0100PA00X+163162Y+005360X0200Y    R270 S0      
317GND              VIA   -    MD0100PA00X+162594Y+044987X0200Y         S0      
327GND              R395  -2          A01X+162354Y+044987X0198Y0197     S1      
317GND              VIA   -    MD0100PA00X+162502Y+043503X0200Y         S0      
327GND              R391  -2          A18X+162234Y+043503X0198Y0197R180 S2      
317GND              VIA   -    MD0100PA00X+162626Y+042702X0200Y         S0      
327GND              R387  -2          A18X+162238Y+042702X0198Y0197R180 S2      
317GND              VIA   -    MD0100PA00X+162595Y+043103X0200Y         S0      
327GND              R389  -2          A18X+162234Y+043103X0198Y0197R180 S2      
317GND              VIA   -    MD0100PA00X+161397Y+013776X0200Y         S0      
317GND              VIA   -    MD0100PA00X+162344Y+013776X0200Y    R180 S0      
317GND              VIA   -    MD0100PA00X+161397Y+012358X0200Y         S0      
317GND              VIA   -    MD0100PA00X+161397Y+013067X0200Y         S0      
317GND              VIA   -    MD0100PA00X+162345Y+013067X0200Y    R180 S0      
317GND              VIA   -    MD0100PA00X+162240Y+012458X0200Y    R180 S0      
317GND              VIA   -    MD0100PA00X+161397Y+010941X0200Y         S0      
317GND              VIA   -    MD0100PA00X+161397Y+010232X0200Y         S0      
317GND              VIA   -    MD0100PA00X+161397Y+011650X0200Y         S0      
317GND              VIA   -    MD0100PA00X+162222Y+011650X0200Y    R180 S0      
317GND              VIA   -    MD0100PA00X+162222Y+010941X0200Y    R180 S0      
317GND              VIA   -    MD0100PA00X+162197Y+010232X0200Y    R180 S0      
317GND              VIA   -    MD0100PA00X+162243Y+008558X0200Y         S0      
317GND              VIA   -    MD0100PA00X+162499Y+009285X0200Y         S0      
317GND              VIA   -    MD0100PA00X+162243Y+007778X0200Y         S0      
317GND              VIA   -    MD0100PA00X+162243Y+007518X0200Y         S0      
317GND              VIA   -    MD0100PA00X+162243Y+008038X0200Y         S0      
317GND              VIA   -    MD0100PA00X+162243Y+008298X0200Y         S0      
317GND              VIA   -    M      A01X+159953Y+041272X0200Y    R180 S2      
017GND              VIA   -    M      A18X+159953Y+041272X0260Y    R180 S2      
017GND                    -    MD0100PA00X+159953Y+041272                       
327GND              R377  -2          A01X+160195Y+041272X0198Y0197R180 S1      
317GND              VIA   -    M      A01X+159953Y+040472X0200Y    R180 S2      
017GND              VIA   -    M      A18X+159953Y+040472X0260Y    R180 S2      
017GND                    -    MD0100PA00X+159953Y+040472                       
327GND              R376  -2          A01X+160195Y+040472X0198Y0197R180 S1      
317GND              VIA   -    MD0100PA00X+159953Y+040072X0200Y    R180 S0      
327GND              R378  -2          A01X+160195Y+040072X0198Y0197R180 S1      
317GND              VIA   -    MD0100PA00X+159953Y+040872X0200Y    R180 S0      
327GND              R375  -2          A01X+160195Y+040872X0198Y0197R180 S1      
317GND              VIA   -    MD0100PA00X+159953Y+039272X0200Y    R180 S0      
327GND              R385  -2          A01X+160195Y+039272X0198Y0197R180 S1      
317GND              VIA   -    MD0100PA00X+159671Y+038300X0200Y         S0      
317GND              VIA   -    MD0100PA00X+159913Y+037559X0200Y         S0      
317GND              VIA   -    MD0100PA00X+159822Y+035100X0200Y         S0      
317GND              VIA   -    MD0100PA00X+160366Y+034260X0200Y         S0      
327GND              U421  -4          A01X+159956Y+034372X0240Y0460R270 S1      
317GND              VIA   -    MD0100PA00X+160824Y+032900X0200Y         S0      
317GND              VIA   -    MD0100PA00X+159701Y+029042X0200Y    R180 S0      
317GND              VIA   -    MD0100PA00X+159743Y+025320X0200Y         S0      
327GND              Q210  -1          A01X+159445Y+025320X0240Y0240R270 S1      
317GND              VIA   -    MD0100PA00X+160395Y+023869X0200Y    R090 S0      
327GND              PR282 -2          A01X+160395Y+023611X0198Y0197R090 S1      
317GND              VIA   -    MD0100PA00X+161218Y+023871X0200Y    R090 S0      
317GND              VIA   -    MD0100PA00X+159751Y+023612X0200Y    R090 S0      
327GND              PC588 -2          A01X+160008Y+023612X0198Y0197R090 S1      
317GND              VIA   -    MD0100PA00X+160472Y+024729X0200Y         S0      
327GND              Q210  -4          A01X+160153Y+024729X0240Y0240R270 S1      
317GND              VIA   -    M      A01X+163627Y+040331X0200Y         S2      
017GND              VIA   -    M      A18X+163627Y+040331X0260Y         S2      
017GND                    -    MD0100PA00X+163627Y+040331                       
317GND              VIA   -    MD0100PA00X+163627Y+041039X0200Y         S0      
317GND              VIA   -    MD0100PA00X+163647Y+034560X0200Y         S0      
317GND              VIA   -    MD0100PA00X+163070Y+035066X0200Y         S0      
317GND              VIA   -    MD0100PA00X+163599Y+033562X0200Y         S0      
317GND              VIA   -    MD0100PA00X+163223Y+033040X0200Y    R180 S0      
317GND              VIA   -    MD0100PA00X+163426Y+029380X0200Y         S0      
317GND              VIA   -    MD0100PA00X+163676Y+029380X0200Y         S0      
317GND              VIA   -    MD0100PA00X+164228Y+028819X0200Y         S0      
317GND              VIA   -    MD0100PA00X+164478Y+028569X0200Y         S0      
317GND              VIA   -    MD0100PA00X+164228Y+028569X0200Y         S0      
317GND              VIA   -    MD0100PA00X+164478Y+028819X0200Y         S0      
317GND              VIA   -    MD0100PA00X+164482Y+024889X0200Y    R180 S0      
317GND              VIA   -    MD0100PA00X+164117Y+022896X0200Y    R090 S0      
317GND              VIA   -    MD0100PA00X+164488Y+022614X0200Y         S0      
317GND              VIA   -    MD0100PA00X+164117Y+022646X0200Y    R090 S0      
317GND              VIA   -    M      A01X+164117Y+022366X0200Y    R090 S2      
017GND              VIA   -    M      A18X+164117Y+022366X0260Y    R090 S2      
017GND                    -    MD0100PA00X+164117Y+022366                       
317GND              VIA   -    MD0100PA00X+163072Y+022873X0200Y    R090 S0      
317GND              VIA   -    MD0100PA00X+163072Y+023123X0200Y    R090 S0      
317GND              VIA   -    MD0100PA00X+163072Y+022623X0200Y    R090 S0      
317GND              VIA   -    MD0100PA00X+163072Y+022373X0200Y    R090 S0      
317GND              VIA   -    MD0100PA00X+164117Y+023146X0200Y    R090 S0      
317GND              VIA   -    MD0100PA00X+164008Y+013776X0200Y    R180 S0      
317GND              VIA   -    MD0100PA00X+162867Y+013776X0200Y         S0      
317GND              VIA   -    MD0100PA00X+164008Y+012358X0200Y    R180 S0      
317GND              VIA   -    MD0100PA00X+164008Y+013067X0200Y    R180 S0      
317GND              VIA   -    MD0100PA00X+163208Y+012358X0200Y         S0      
317GND              VIA   -    MD0100PA00X+163208Y+013067X0200Y         S0      
317GND              VIA   -    MD0100PA00X+164008Y+010232X0200Y    R180 S0      
317GND              VIA   -    MD0100PA00X+164008Y+010941X0200Y    R180 S0      
317GND              VIA   -    MD0100PA00X+164008Y+011650X0200Y    R180 S0      
317GND              VIA   -    MD0100PA00X+163208Y+010941X0200Y         S0      
317GND              VIA   -    MD0100PA00X+163208Y+011650X0200Y         S0      
317GND              VIA   -    MD0100PA00X+163195Y+010304X0200Y         S0      
317GND              VIA   -    MD0100PA00X+165990Y+013669X0200Y         S0      
317GND              VIA   -    MD0100PA00X+164949Y+012957X0200Y         S0      
317GND              VIA   -    MD0100PA00X+164949Y+012462X0200Y         S0      
317GND              VIA   -    MD0100PA00X+165448Y+012957X0200Y         S0      
317GND              VIA   -    MD0100PA00X+165448Y+012462X0200Y         S0      
317GND              VIA   -    MD0100PA00X+165990Y+013173X0200Y         S0      
317GND              VIA   -    MD0100PA00X+165990Y+012251X0200Y         S0      
317GND              VIA   -    MD0100PA00X+165664Y+010378X0200Y    R270 S0      
327GND              R452  -1          A01X+165664Y+010135X0198Y0197R270 S1      
317GND              VIA   -    MD0100PA00X+164949Y+011540X0200Y         S0      
317GND              VIA   -    MD0100PA00X+164949Y+011044X0200Y         S0      
317GND              VIA   -    MD0100PA00X+165448Y+011540X0200Y         S0      
317GND              VIA   -    MD0100PA00X+165448Y+011044X0200Y         S0      
317GND              VIA   -    MD0100PA00X+165990Y+011756X0200Y         S0      
317GND              VIA   -    MD0100PA00X+164909Y+010170X0200Y    R090 S0      
317GND              VIA   -    MD0100PA00X+164536Y+009402X0200Y         S0      
317GND              VIA   -    MD0100PA00X+165336Y+009402X0200Y         S0      
317GND              VIA   -    MD0100PA00X+165737Y+009402X0200Y         S0      
317GND              VIA   -    MD0100PA00X+164936Y+009402X0200Y         S0      
317GND              VIA   -    MD0100PA00X+164973Y+004477X0200Y    R270 S0      
317GND              VIA   -    MD0100PA00X+164973Y+002477X0200Y    R270 S0      
317GND              VIA   -    MD0100PA00X+165042Y+000537X0200Y    R270 S0      
317GND              VIA   -    MD0100PA00X+163766Y+046549X0200Y         S0      
317GND              VIA   -    MD0100PA00X+163286Y+046549X0200Y         S0      
317GND              VIA   -    MD0100PA00X+163749Y+046226X0200Y         S0      
327GND              C961  -2          A18X+164136Y+046348X0198Y0197     S2      
317GND              VIA   -    MD0100PA00X+163766Y+045132X0200Y         S0      
317GND              VIA   -    MD0100PA00X+163766Y+045841X0200Y         S0      
317GND              VIA   -    MD0100PA00X+163720Y+043010X0200Y    R270 S0      
317GND              VIA   -    MD0100PA00X+163720Y+043260X0200Y    R270 S0      
317GND              VIA   -    MD0100PA00X+163720Y+043510X0200Y    R270 S0      
317GND              VIA   -    MD0100PA00X+163720Y+043760X0200Y    R270 S0      
317GND              VIA   -    MD0100PA00X+163720Y+044010X0200Y    R270 S0      
317GND              VIA   -    MD0100PA00X+165564Y+045202X0200Y    R180 S0      
317GND              VIA   -    MD0100PA00X+165543Y+043996X0200Y    R180 S0      
317GND              VIA   -    MD0100PA00X+165539Y+043707X0200Y    R180 S0      
317GND              VIA   -    MD0100PA00X+165558Y+043357X0200Y    R180 S0      
317GND              VIA   -    MD0100PA00X+165556Y+043076X0200Y    R180 S0      
317GND              VIA   -    MD0100PA00X+165534Y+038150X0200Y         S0      
327GND              R379  -2          A18X+165534Y+038450X0198Y0197R180 S2      
317GND              VIA   -    MD0100PA00X+164568Y+039050X0200Y         S0      
327GND              R380  -2          A18X+164568Y+038800X0198Y0197     S2      
317GND              VIA   -    M      A01X+165980Y+029076X0200Y         S2      
017GND              VIA   -    M      A18X+165980Y+029076X0260Y         S2      
017GND                    -    MD0100PA00X+165980Y+029076                       
317GND              VIA   -    MD0100PA00X+165180Y+029076X0200Y         S0      
327GND              PC890 -2          A01X+165180Y+028806X0198Y0197R090 S1      
317GND              VIA   -    MD0100PA00X+165580Y+029076X0200Y         S0      
327GND              PR7093-2          A01X+165580Y+028806X0198Y0197R090 S1      
317GND              VIA   -    MD0100PA00X+164758Y+028819X0200Y         S0      
317GND              VIA   -    MD0100PA00X+164758Y+028569X0200Y         S0      
317GND              VIA   -    MD0100PA00X+165275Y+025654X0200Y         S0      
327GND              PC891 -2          A01X+165275Y+025954X0198Y0197R270 S1      
317GND              VIA   -    MD0100PA00X+166075Y+025654X0200Y         S0      
317GND              VIA   -    MD0100PA00X+164982Y+024889X0200Y    R180 S0      
317GND              VIA   -    MD0100PA00X+164732Y+024889X0200Y    R180 S0      
317GND              VIA   -    MD0100PA00X+164914Y+023179X0200Y    R090 S0      
317GND              VIA   -    MD0100PA00X+164762Y+023661X0200Y    R180 S0      
317GND              VIA   -    MD0100PA00X+165012Y+023661X0200Y    R180 S0      
317GND              VIA   -    MD0100PA00X+164512Y+023661X0200Y    R180 S0      
317GND              VIA   -    MD0100PA00X+165284Y+022471X0200Y    R090 S0      
317GND              VIA   -    MD0100PA00X+165284Y+022221X0200Y    R090 S0      
317GND              VIA   -    MD0100PA00X+164914Y+022929X0200Y    R090 S0      
317GND              VIA   -    M      A01X+164768Y+022614X0200Y         S2      
017GND              VIA   -    M      A18X+164768Y+022614X0260Y         S2      
017GND                    -    MD0100PA00X+164768Y+022614                       
317GND              VIA   -    MD0100PA00X+165954Y+020676X0200Y         S0      
317GND              VIA   -    M      A01X+165092Y+018873X0200Y         S2      
017GND              VIA   -    M      A18X+165092Y+018873X0260Y         S2      
017GND                    -    MD0100PA00X+165092Y+018873                       
327GND              C404  -2          A01X+165392Y+018740X0198Y0197R090 S1      
317GND              VIA   -    MD0100PA00X+165756Y+018462X0200Y         S0      
327GND              U77   -10         A01X+166042Y+018383X0090Y0240R090 S1      
317GND              VIA   -    MD0100PA00X+165106Y+019194X0200Y         S0      
327GND              C336  -2          A01X+165384Y+019194X0198Y0197R180 S1      
317GND              VIA   -    MD0100PA00X+164741Y+015154X0200Y         S0      
327GND              R6125 -2          A01X+165018Y+015154X0198Y0197R180 S1      
317GND              VIA   -    M      A01X+166588Y+028131X0200Y         S2      
017GND              VIA   -    M      A18X+166588Y+028131X0260Y         S2      
017GND                    -    MD0100PA00X+166588Y+028131                       
317GND              VIA   -    MD0100PA00X+166178Y+027921X0200Y         S0      
317GND              VIA   -    MD0100PA00X+166823Y+018512X0200Y         S0      
317GND              VIA   -    MD0100PA00X+166359Y+018516X0200Y         S0      
317GND              VIA   -    MD0100PA00X+167199Y+019242X0200Y         S0      
317GND              VIA   -    MD0100PA00X+166827Y+018053X0200Y         S0      
317GND              VIA   -    MD0100PA00X+166359Y+018057X0200Y         S0      
327GND              U77   -TH  M      A01X+166593Y+018285X0670Y0670R180 S1      
317GND              VIA   -    MD0100PA00X+166189Y+015237X0200Y         S0      
327GND              Q231  -1          A01X+165890Y+015237X0240Y0240R270 S1      
317GND              VIA   -    MD0100PA00X+166489Y+013669X0200Y         S0      
317GND              VIA   -    MD0100PA00X+166299Y+014646X0200Y         S0      
327GND              Q231  -4          A01X+166599Y+014646X0240Y0240R270 S1      
317GND              VIA   -    MD0100PA00X+166489Y+013173X0200Y         S0      
317GND              VIA   -    MD0100PA00X+166489Y+012251X0200Y         S0      
317GND              VIA   -    MD0100PA00X+166781Y+010362X0200Y    R090 S0      
327GND              U406  -S          A01X+166781Y+010792X0400Y0560R180 S1      
317GND              VIA   -    MD0100PA00X+166489Y+011756X0200Y         S0      
317GND              VIA   -    MD0100PA00X+167582Y+011726X0200Y         S0      
327GND              R6212 -1          A01X+167624Y+011449X0198Y0197R180 S1      
317GND              VIA   -    MD0100PA00X+167721Y+009195X0200Y    R180 S0      
327GND              C2733 -1          A01X+167466Y+009195X0198Y0197R270 S1      
317GND              VIA   -    MD0100PA00X+166244Y+008014X0200Y         S0      
317GND              VIA   -    MD0100PA00X+166244Y+007614X0200Y         S0      
317GND              VIA   -    MD0100PA00X+166244Y+008414X0200Y         S0      
317GND              VIA   -    MD0100PA00X+166932Y+000300X0200Y    R270 S0      
317GND              VIA   -    MD0100PA00X+165574Y+046025X0200Y         S0      
317GND              VIA   -    MD0100PA00X+165578Y+046549X0200Y         S0      
317GND              VIA   -    MD0100PA00X+164546Y+046603X0200Y    R180 S0      
317GND              VIA   -    MD0100PA00X+165351Y+047014X0200Y         S0      
327GND              R381  -2          A18X+165351Y+046737X0198Y0197R180 S2      
317GND              VIA   -    MD0100PA00X+165570Y+045474X0200Y    R180 S0      
317GND              VIA   -    MD0100PA00X+165568Y+044318X0200Y    R180 S0      
317GND              VIA   -    MD0100PA00X+169348Y+019888X0200Y    R090 S0      
317GND              VIA   -    MD0100PA00X+168887Y+019518X0200Y    R180 S0      
317GND              VIA   -    MD0100PA00X+169137Y+019518X0200Y    R180 S0      
317GND              VIA   -    MD0100PA00X+168352Y+018066X0200Y         S0      
327GND              R664  -2          A01X+168088Y+018066X0198Y0197     S1      
317GND              VIA   -    MD0100PA00X+168352Y+017266X0200Y         S0      
327GND              R663  -2          A01X+168088Y+017266X0198Y0197     S1      
317GND              VIA   -    MD0100PA00X+168774Y+013458X0200Y         S0      
327GND              U396  -3          A01X+168463Y+013674X0240Y0240     S1      
317GND              VIA   -    MD0100PA00X+169359Y+013330X0200Y         S0      
317GND              VIA   -    MD0100PA00X+168617Y+013090X0200Y         S0      
327GND              PC977 -2          A01X+168359Y+013090X0198Y0197R090 S1      
317GND              VIA   -    MD0100PA00X+169157Y+010225X0200Y    R180 S0      
327GND              PR7128-2   M      A01X+169157Y+010475X0198Y0197R270 S1      
317GND              VIA   -    MD0100PA00X+168757Y+010225X0200Y    R180 S0      
327GND              PR7130-2   M      A01X+168757Y+010475X0198Y0197R270 S1      
317GND              VIA   -    MD0100PA00X+168600Y+011078X0200Y         S0      
327GND              PU134 -3   M      A01X+168733Y+011368X0100Y0280     S1      
317GND              VIA   -    MD0100PA00X+168335Y+011339X0200Y         S0      
317GND              VIA   -    M      A01X+169557Y+010225X0200Y    R180 S2      
017GND              VIA   -    M      A18X+169557Y+010225X0260Y    R180 S2      
017GND                    -    MD0100PA00X+169557Y+010225                       
317GND              VIA   -    MD0100PA00X+168002Y+005551X0200Y         S0      
327GND              C2740 -1          A01X+168002Y+005801X0198Y0197R180 S1      
317GND              VIA   -    MD0100PA00X+168518Y+006092X0200Y         S0      
327GND              U140  -4          A01X+168488Y+006472X0240Y0460R180 S1      
317GND              VIA   -    MD0100PA00X+168932Y+000300X0200Y    R270 S0      
317GND              VIA   -    MD0100PA00X+166358Y+046549X0200Y    R180 S0      
317GND              VIA   -    MD0100PA00X+167372Y+044579X0200Y         S0      
327GND              C958  -2          A18X+167372Y+044863X0198Y0197R090 S2      
317GND              VIA   -    MD0100PA00X+166977Y+044591X0200Y         S0      
327GND              C960  -2          A18X+166977Y+044863X0198Y0197R090 S2      
317GND              VIA   -    MD0100PA00X+166358Y+045841X0200Y    R180 S0      
317GND              VIA   -    MD0100PA00X+166376Y+040331X0200Y    R180 S0      
317GND              VIA   -    MD0100PA00X+166376Y+041039X0200Y    R180 S0      
317GND              VIA   -    MD0100PA00X+167320Y+033202X0200Y    R270 S0      
327GND              C962  -2          A01X+167580Y+033202X0198Y0197R090 S1      
317GND              VIA   -    MD0100PA00X+167423Y+032414X0200Y    R090 S0      
327GND              Q8    -1          A01X+167109Y+032185X0170Y0240R270 S1      
317GND              VIA   -    MD0100PA00X+166787Y+029364X0200Y    R090 S0      
317GND              VIA   -    MD0100PA00X+167037Y+029364X0200Y    R090 S0      
317GND              VIA   -    MD0100PA00X+166787Y+028834X0200Y    R090 S0      
317GND              VIA   -    MD0100PA00X+166787Y+029084X0200Y    R090 S0      
317GND              VIA   -    MD0100PA00X+167037Y+028834X0200Y    R090 S0      
317GND              VIA   -    MD0100PA00X+167037Y+029084X0200Y    R090 S0      
317GND              VIA   -    MD0100PA00X+169387Y+019518X0200Y    R180 S0      
317GND              VIA   -    M      A01X+169667Y+019518X0200Y    R180 S2      
017GND              VIA   -    M      A18X+169667Y+019518X0260Y    R180 S2      
017GND                    -    MD0100PA00X+169667Y+019518                       
317GND              VIA   -    MD0100PA00X+170512Y+015085X0200Y         S0      
327GND              U378  -S          A01X+170117Y+015330X0400Y0560     S1      
317GND              VIA   -    MD0100PA00X+170433Y+013776X0200Y         S0      
317GND              VIA   -    MD0100PA00X+170913Y+013776X0200Y         S0      
317GND              VIA   -    MD0100PA00X+170223Y+014123X0200Y         S0      
327GND              R5708 -2          A01X+170076Y+013884X0198Y0197     S1      
317GND              VIA   -    MD0100PA00X+170032Y+014601X0200Y         S0      
327GND              C3673 -2          A01X+169782Y+014601X0198Y0197R090 S1      
317GND              VIA   -    MD0100PA00X+170433Y+013067X0200Y         S0      
317GND              VIA   -    MD0100PA00X+170433Y+012358X0200Y         S0      
317GND              VIA   -    MD0100PA00X+170913Y+013067X0200Y         S0      
317GND              VIA   -    MD0100PA00X+170913Y+012358X0200Y         S0      
317GND              VIA   -    MD0100PA00X+170433Y+011650X0200Y         S0      
317GND              VIA   -    MD0100PA00X+170913Y+011650X0200Y         S0      
317GND              VIA   -    MD0100PA00X+170059Y+010650X0200Y         S0      
327GND              C2778 -2   M      A01X+170318Y+010650X0198Y0197R180 S1      
317GND              VIA   -    MD0100PA00X+170158Y+010917X0200Y         S0      
317GND              VIA   -    MD0100PA00X+169858Y+010917X0200Y         S0      
317GND              VIA   -    MD0100PA00X+170666Y+004477X0200Y    R270 S0      
317GND              VIA   -    MD0100PA00X+170666Y+002477X0200Y    R270 S0      
317GND              VIA   -    MD0100PA00X+170530Y+000447X0200Y    R270 S0      
317GND              VIA   -    MD0100PA00X+168976Y+047148X0200Y    R270 S0      
317GND              VIA   -    MD0100PA00X+168976Y+046653X0200Y    R270 S0      
317GND              VIA   -    MD0100PA00X+167793Y+041884X0200Y         S0      
317GND              VIA   -    MD0100PA00X+168052Y+040192X0200Y         S0      
327GND              R374  -2          A18X+167812Y+040192X0198Y0197R180 S2      
317GND              VIA   -    MD0100PA00X+168052Y+040592X0200Y         S0      
327GND              R373  -2          A18X+167812Y+040592X0198Y0197R180 S2      
317GND              VIA   -    MD0100PA00X+168052Y+040992X0200Y         S0      
317GND              VIA   -    MD0100PA00X+168052Y+038991X0200Y         S0      
327GND              R371  -2          A18X+167812Y+038991X0198Y0197R180 S2      
317GND              VIA   -    MD0100PA00X+168052Y+039392X0200Y         S0      
317GND              VIA   -    MD0100PA00X+168052Y+038591X0200Y         S0      
327GND              R370  -2          A18X+167812Y+038591X0198Y0197R180 S2      
317GND              VIA   -    MD0100PA00X+169174Y+035351X0200Y         S0      
327GND              C963  -2          A01X+169174Y+035085X0198Y0197     S1      
317GND              VIA   -    MD0100PA00X+167807Y+034232X0200Y         S0      
327GND              U45   -3          A01X+167454Y+034232X0160Y0360R270 S1      
317GND              VIA   -    MD0100PA00X+168716Y+033632X0200Y         S0      
327GND              U46   -3          A01X+169153Y+033632X0220Y0530R090 S1      
317GND              VIA   -    MD0100PA00X+169112Y+032165X0200Y    R180 S0      
327GND              U47   -3          A01X+169469Y+032165X0400Y0500     S1      
317GND              VIA   -    MD0100PA00X+168127Y+031673X0200Y    R090 S0      
327GND              Q8    -4          A01X+167857Y+031673X0170Y0240R270 S1      
317GND              VIA   -    MD0100PA00X+168531Y+025237X0200Y         S0      
327GND              PR7098-2          A01X+168809Y+025237X0198Y0197R180 S1      
317GND              VIA   -    MD0100PA00X+168356Y+021686X0200Y         S0      
327GND              PC420 -2          A01X+168098Y+021686X0198Y0197     S1      
317GND              VIA   -    MD0100PA00X+168356Y+022186X0200Y         S0      
327GND              C2874 -2   M      A01X+168098Y+022186X0198Y0197     S1      
317GND              VIA   -    MD0100PA00X+168873Y+020339X0200Y    R180 S0      
317GND              VIA   -    M      A01X+169348Y+020168X0200Y    R090 S2      
017GND              VIA   -    M      A18X+169348Y+020168X0260Y    R090 S2      
017GND                    -    MD0100PA00X+169348Y+020168                       
317GND              VIA   -    MD0100PA00X+169123Y+020339X0200Y    R180 S0      
317GND              VIA   -    MD0100PA00X+168356Y+021286X0200Y         S0      
317GND              VIA   -    MD0100PA00X+168356Y+020086X0200Y         S0      
317GND              VIA   -    MD0100PA00X+171273Y+034053X0200Y    R180 S0      
317GND              VIA   -    MD0100PA00X+171570Y+032869X0200Y    R180 S0      
317GND              VIA   -    MD0100PA00X+171455Y+023871X0200Y    R090 S0      
327GND              PC590 -2          A01X+171455Y+023613X0198Y0197R090 S1      
317GND              VIA   -    MD0100PA00X+171287Y+021354X0200Y    R090 S0      
317GND              VIA   -    MD0100PA00X+171633Y+013776X0200Y         S0      
317GND              VIA   -    MD0100PA00X+172581Y+013776X0200Y    R180 S0      
317GND              VIA   -    MD0100PA00X+171163Y+013067X0200Y         S0      
317GND              VIA   -    MD0100PA00X+171163Y+012358X0200Y         S0      
317GND              VIA   -    MD0100PA00X+171633Y+012358X0200Y         S0      
317GND              VIA   -    MD0100PA00X+171633Y+013067X0200Y         S0      
317GND              VIA   -    MD0100PA00X+172581Y+013067X0200Y    R180 S0      
317GND              VIA   -    MD0100PA00X+172476Y+012458X0200Y    R180 S0      
317GND              VIA   -    MD0100PA00X+172459Y+011650X0200Y    R180 S0      
317GND              VIA   -    MD0100PA00X+172459Y+010941X0200Y    R180 S0      
317GND              VIA   -    MD0100PA00X+172433Y+010232X0200Y    R180 S0      
317GND              VIA   -    MD0100PA00X+171163Y+010941X0200Y         S0      
317GND              VIA   -    MD0100PA00X+171163Y+011650X0200Y         S0      
317GND              VIA   -    MD0100PA00X+171633Y+010232X0200Y         S0      
317GND              VIA   -    MD0100PA00X+171633Y+010941X0200Y         S0      
317GND              VIA   -    MD0100PA00X+171633Y+011650X0200Y         S0      
317GND              VIA   -    MD0100PA00X+172480Y+008558X0200Y         S0      
317GND              VIA   -    MD0100PA00X+172480Y+007518X0200Y         S0      
317GND              VIA   -    MD0100PA00X+172480Y+008038X0200Y         S0      
317GND              VIA   -    MD0100PA00X+172480Y+007778X0200Y         S0      
317GND              VIA   -    MD0100PA00X+172480Y+008298X0200Y         S0      
317GND              VIA   -    MD0100PA00X+171398Y+005360X0200Y    R270 S0      
317GND              VIA   -    MD0100PA00X+169475Y+047148X0200Y    R090 S0      
317GND              VIA   -    MD0100PA00X+169475Y+046653X0200Y    R090 S0      
317GND              VIA   -    MD0100PA00X+169514Y+030384X0200Y         S0      
327GND              C957  -2          A01X+169514Y+030665X0198Y0197R180 S1      
317GND              VIA   -    MD0100PA00X+170150Y+028974X0200Y         S0      
317GND              VIA   -    MD0100PA00X+169980Y+025320X0200Y         S0      
327GND              Q211  -1          A01X+169681Y+025320X0240Y0240R270 S1      
317GND              VIA   -    MD0100PA00X+170631Y+023869X0200Y    R090 S0      
327GND              PR285 -2          A01X+170631Y+023611X0198Y0197R090 S1      
317GND              VIA   -    MD0100PA00X+169691Y+023859X0200Y    R090 S0      
327GND              C2899 -2          A01X+169691Y+023601X0198Y0197R090 S1      
317GND              VIA   -    MD0100PA00X+169988Y+023612X0200Y    R090 S0      
327GND              PC433 -2          A01X+170244Y+023612X0198Y0197R090 S1      
317GND              VIA   -    MD0100PA00X+170709Y+024729X0200Y         S0      
327GND              Q211  -4          A01X+170390Y+024729X0240Y0240R270 S1      
317GND              VIA   -    MD0100PA00X+169491Y+020684X0200Y    R180 S0      
317GND              VIA   -    MD0100PA00X+169741Y+020684X0200Y    R180 S0      
317GND              VIA   -    MD0100PA00X+172930Y+044252X0200Y    R270 S0      
317GND              VIA   -    MD0100PA00X+173307Y+039687X0200Y    R270 S0      
317GND              VIA   -    MD0100PA00X+172848Y+039687X0200Y    R270 S0      
317GND              VIA   -    MD0100PA00X+173249Y+040287X0200Y    R270 S0      
327GND              U86   -10         A01X+173174Y+040004X0090Y0240     S1      
317GND              VIA   -    MD0100PA00X+173581Y+040903X0200Y    R270 S0      
327GND              C623  -2          A01X+173581Y+040653X0198Y0197     S1      
317GND              VIA   -    M      A01X+173985Y+040902X0200Y    R270 S2      
017GND              VIA   -    M      A18X+173985Y+040902X0260Y    R270 S2      
017GND                    -    MD0100PA00X+173985Y+040902                       
327GND              C616  -2          A01X+173985Y+040662X0198Y0197R090 S1      
317GND              VIA   -    MD0100PA00X+172843Y+039218X0200Y    R270 S0      
317GND              VIA   -    MD0100PA00X+173303Y+039223X0200Y    R270 S0      
327GND              U86   -TH  M      A01X+173076Y+039452X0670Y0670R090 S1      
317GND              VIA   -    MD0100PA00X+173483Y+037650X0200Y    R180 S0      
317GND              VIA   -    MD0100PA00X+173662Y+029380X0200Y         S0      
317GND              VIA   -    MD0100PA00X+173912Y+029380X0200Y         S0      
317GND              VIA   -    M      A01X+174354Y+022366X0200Y    R090 S2      
017GND              VIA   -    M      A18X+174354Y+022366X0260Y    R090 S2      
017GND                    -    MD0100PA00X+174354Y+022366                       
317GND              VIA   -    MD0100PA00X+173308Y+022873X0200Y    R090 S0      
317GND              VIA   -    MD0100PA00X+173308Y+023123X0200Y    R090 S0      
317GND              VIA   -    MD0100PA00X+173308Y+022623X0200Y    R090 S0      
317GND              VIA   -    MD0100PA00X+173308Y+022373X0200Y    R090 S0      
317GND              VIA   -    MD0100PA00X+173065Y+013776X0200Y         S0      
317GND              VIA   -    MD0100PA00X+173444Y+012358X0200Y         S0      
317GND              VIA   -    MD0100PA00X+173444Y+013067X0200Y         S0      
317GND              VIA   -    MD0100PA00X+173444Y+010941X0200Y         S0      
317GND              VIA   -    MD0100PA00X+173444Y+011650X0200Y         S0      
317GND              VIA   -    MD0100PA00X+173431Y+010304X0200Y         S0      
317GND              VIA   -    MD0100PA00X+172735Y+009285X0200Y         S0      
317GND              VIA   -    MD0100PA00X+173398Y+005360X0200Y    R270 S0      
317GND              VIA   -    MD0100PA00X+171631Y+045833X0200Y    R090 S0      
327GND              PC912 -2          A01X+171871Y+045833X0198Y0197R180 S1      
317GND              VIA   -    MD0100PA00X+171871Y+044749X0200Y    R090 S0      
327GND              PC917 -2          A01X+171871Y+045033X0198Y0197R180 S1      
317GND              VIA   -    MD0100PA00X+172396Y+037094X0200Y    R270 S0      
327GND              R762  -2          A01X+171775Y+037957X0198Y0197R270 S1      
317GND              VIA   -    MD0100PA00X+172575Y+037717X0200Y    R270 S0      
317GND              VIA   -    M      A01X+175004Y+022614X0200Y         S2      
017GND              VIA   -    M      A18X+175004Y+022614X0260Y         S2      
017GND                    -    MD0100PA00X+175004Y+022614                       
317GND              VIA   -    M      A01X+175328Y+018873X0200Y         S2      
017GND              VIA   -    M      A18X+175328Y+018873X0260Y         S2      
017GND                    -    MD0100PA00X+175328Y+018873                       
327GND              C407  -2          A01X+175628Y+018740X0198Y0197R090 S1      
317GND              VIA   -    MD0100PA00X+175342Y+019194X0200Y         S0      
327GND              C339  -2          A01X+175620Y+019194X0198Y0197R180 S1      
317GND              VIA   -    MD0100PA00X+174244Y+013776X0200Y    R180 S0      
317GND              VIA   -    MD0100PA00X+175685Y+012957X0200Y         S0      
317GND              VIA   -    MD0100PA00X+175685Y+012462X0200Y         S0      
317GND              VIA   -    MD0100PA00X+175186Y+012462X0200Y         S0      
317GND              VIA   -    MD0100PA00X+175186Y+012957X0200Y         S0      
317GND              VIA   -    MD0100PA00X+174244Y+012358X0200Y    R180 S0      
317GND              VIA   -    MD0100PA00X+174244Y+013067X0200Y    R180 S0      
317GND              VIA   -    MD0100PA00X+175685Y+011044X0200Y         S0      
317GND              VIA   -    MD0100PA00X+175685Y+011540X0200Y         S0      
317GND              VIA   -    MD0100PA00X+175186Y+011540X0200Y         S0      
317GND              VIA   -    MD0100PA00X+175186Y+011044X0200Y         S0      
317GND              VIA   -    MD0100PA00X+174244Y+010941X0200Y    R180 S0      
317GND              VIA   -    MD0100PA00X+174244Y+011650X0200Y    R180 S0      
317GND              VIA   -    MD0100PA00X+174244Y+010232X0200Y    R180 S0      
317GND              VIA   -    MD0100PA00X+175173Y+009402X0200Y         S0      
317GND              VIA   -    MD0100PA00X+174773Y+009402X0200Y         S0      
317GND              VIA   -    MD0100PA00X+175146Y+010170X0200Y    R090 S0      
317GND              VIA   -    MD0100PA00X+175573Y+009402X0200Y         S0      
317GND              VIA   -    MD0100PA00X+175209Y+004477X0200Y    R270 S0      
317GND              VIA   -    MD0100PA00X+175209Y+002477X0200Y    R270 S0      
317GND              VIA   -    MD0100PA00X+175278Y+000537X0200Y    R270 S0      
317GND              VIA   -    MD0100PA00X+174054Y+046529X0200Y    R270 S0      
317GND              VIA   -    MD0100PA00X+174054Y+046809X0200Y    R270 S0      
317GND              VIA   -    MD0100PA00X+173770Y+047219X0200Y         S0      
317GND              VIA   -    MD0100PA00X+173621Y+045009X0200Y    R090 S0      
317GND              VIA   -    MD0100PA00X+173882Y+045274X0200Y    R090 S0      
327GND              PU122 -3   M      A01X+173592Y+045408X0100Y0280R090 S1      
317GND              VIA   -    MD0100PA00X+173918Y+044632X0200Y    R270 S0      
317GND              VIA   -    MD0100PA00X+173918Y+044912X0200Y    R270 S0      
317GND              VIA   -    MD0100PA00X+172930Y+043972X0200Y    R270 S0      
317GND              VIA   -    MD0100PA00X+176226Y+011756X0200Y         S0      
317GND              VIA   -    MD0100PA00X+175974Y+009402X0200Y         S0      
317GND              VIA   -    MD0100PA00X+176480Y+008014X0200Y         S0      
317GND              VIA   -    MD0100PA00X+176480Y+007614X0200Y         S0      
317GND              VIA   -    MD0100PA00X+176480Y+008414X0200Y         S0      
317GND              VIA   -    MD0100PA00X+176556Y+000300X0200Y    R270 S0      
317GND              VIA   -    MD0100PA00X+174736Y+046231X0200Y    R270 S0      
327GND              PC916 -2   M      A01X+174486Y+046231X0198Y0197     S1      
317GND              VIA   -    MD0100PA00X+174736Y+045831X0200Y    R270 S0      
327GND              PR7105-2   M      A01X+174486Y+045831X0198Y0197     S1      
317GND              VIA   -    MD0100PA00X+174736Y+045431X0200Y    R270 S0      
327GND              PR7106-2   M      A01X+174486Y+045431X0198Y0197     S1      
317GND              VIA   -    MD0100PA00X+174718Y+044632X0200Y    R270 S0      
317GND              VIA   -    MD0100PA00X+174718Y+044912X0200Y    R270 S0      
317GND              VIA   -    MD0100PA00X+175684Y+045564X0200Y    R270 S0      
317GND              VIA   -    MD0100PA00X+175684Y+045284X0200Y    R270 S0      
317GND              VIA   -    MD0100PA00X+175684Y+045004X0200Y    R270 S0      
317GND              VIA   -    MD0100PA00X+174825Y+039525X0200Y    R270 S0      
317GND              VIA   -    MD0100PA00X+174756Y+038516X0200Y    R180 S0      
317GND              VIA   -    MD0100PA00X+175650Y+037098X0200Y    R270 S0      
317GND              VIA   -    MD0100PA00X+174452Y+037001X0200Y         S0      
317GND              VIA   -    MD0100PA00X+175416Y+029076X0200Y         S0      
327GND              PC893 -2          A01X+175416Y+028806X0198Y0197R090 S1      
317GND              VIA   -    MD0100PA00X+175816Y+029076X0200Y         S0      
317GND              VIA   -    MD0100PA00X+174714Y+028569X0200Y         S0      
317GND              VIA   -    MD0100PA00X+174464Y+028569X0200Y         S0      
317GND              VIA   -    MD0100PA00X+174994Y+028569X0200Y         S0      
317GND              VIA   -    MD0100PA00X+174464Y+028819X0200Y         S0      
317GND              VIA   -    MD0100PA00X+174714Y+028819X0200Y         S0      
317GND              VIA   -    MD0100PA00X+174994Y+028819X0200Y         S0      
317GND              VIA   -    MD0100PA00X+175511Y+025654X0200Y         S0      
327GND              PC896 -2          A01X+175511Y+025954X0198Y0197R270 S1      
317GND              VIA   -    MD0100PA00X+175219Y+024889X0200Y    R180 S0      
317GND              VIA   -    MD0100PA00X+174969Y+024889X0200Y    R180 S0      
317GND              VIA   -    MD0100PA00X+174719Y+024889X0200Y    R180 S0      
317GND              VIA   -    MD0100PA00X+174748Y+023661X0200Y    R180 S0      
317GND              VIA   -    MD0100PA00X+175150Y+023179X0200Y    R090 S0      
317GND              VIA   -    MD0100PA00X+174998Y+023661X0200Y    R180 S0      
317GND              VIA   -    MD0100PA00X+175248Y+023661X0200Y    R180 S0      
317GND              VIA   -    MD0100PA00X+175520Y+022221X0200Y    R090 S0      
317GND              VIA   -    MD0100PA00X+175150Y+022929X0200Y    R090 S0      
317GND              VIA   -    MD0100PA00X+174354Y+023146X0200Y    R090 S0      
317GND              VIA   -    MD0100PA00X+174354Y+022896X0200Y    R090 S0      
317GND              VIA   -    MD0100PA00X+175520Y+022471X0200Y    R090 S0      
317GND              VIA   -    MD0100PA00X+174724Y+022614X0200Y         S0      
317GND              VIA   -    MD0100PA00X+174354Y+022646X0200Y    R090 S0      
317GND              VIA   -    M      A01X+176515Y+041361X0200Y         S2      
017GND              VIA   -    M      A18X+176515Y+041361X0260Y         S2      
017GND                    -    MD0100PA00X+176515Y+041361                       
317GND              VIA   -    MD0100PA00X+176370Y+040195X0200Y         S0      
317GND              VIA   -    M      A01X+176763Y+040710X0200Y    R270 S2      
017GND              VIA   -    M      A18X+176763Y+040710X0260Y    R270 S2      
017GND                    -    MD0100PA00X+176763Y+040710                       
317GND              VIA   -    MD0100PA00X+176763Y+040990X0200Y    R270 S0      
317GND              VIA   -    MD0100PA00X+177328Y+040264X0200Y         S0      
317GND              VIA   -    MD0100PA00X+177078Y+040264X0200Y         S0      
317GND              VIA   -    MD0100PA00X+176620Y+039895X0200Y         S0      
317GND              VIA   -    MD0100PA00X+176550Y+037090X0200Y         S0      
327GND              C2860 -2          A01X+176550Y+037348X0198Y0197R270 S1      
317GND              VIA   -    MD0100PA00X+176050Y+037107X0200Y    R270 S0      
327GND              PC336 -2          A01X+176050Y+037348X0198Y0197R270 S1      
317GND              VIA   -    M      A01X+176216Y+029076X0200Y         S2      
017GND              VIA   -    M      A18X+176216Y+029076X0260Y         S2      
017GND                    -    MD0100PA00X+176216Y+029076                       
317GND              VIA   -    MD0100PA00X+177274Y+028834X0200Y    R090 S0      
317GND              VIA   -    MD0100PA00X+177274Y+029084X0200Y    R090 S0      
317GND              VIA   -    MD0100PA00X+177024Y+028834X0200Y    R090 S0      
317GND              VIA   -    MD0100PA00X+177024Y+029084X0200Y    R090 S0      
317GND              VIA   -    MD0100PA00X+177024Y+029364X0200Y    R090 S0      
317GND              VIA   -    MD0100PA00X+177274Y+029364X0200Y    R090 S0      
317GND              VIA   -    M      A01X+176825Y+028131X0200Y         S2      
017GND              VIA   -    M      A18X+176825Y+028131X0260Y         S2      
017GND                    -    MD0100PA00X+176825Y+028131                       
317GND              VIA   -    MD0100PA00X+176414Y+027921X0200Y         S0      
317GND              VIA   -    MD0100PA00X+176311Y+025654X0200Y         S0      
327GND              PC897 -2          A01X+176311Y+025954X0198Y0197R270 S1      
317GND              VIA   -    MD0100PA00X+176190Y+020676X0200Y         S0      
317GND              VIA   -    MD0100PA00X+176595Y+018516X0200Y         S0      
317GND              VIA   -    MD0100PA00X+177059Y+018512X0200Y         S0      
317GND              VIA   -    MD0100PA00X+175992Y+018462X0200Y         S0      
327GND              U78   -10         A01X+176278Y+018383X0090Y0240R090 S1      
317GND              VIA   -    MD0100PA00X+177436Y+019242X0200Y         S0      
317GND              VIA   -    MD0100PA00X+177063Y+018053X0200Y         S0      
317GND              VIA   -    MD0100PA00X+176595Y+018057X0200Y         S0      
327GND              U78   -TH  M      A01X+176829Y+018285X0670Y0670R180 S1      
317GND              VIA   -    MD0100PA00X+176725Y+013669X0200Y         S0      
317GND              VIA   -    MD0100PA00X+176226Y+013669X0200Y         S0      
317GND              VIA   -    MD0100PA00X+176725Y+013173X0200Y         S0      
317GND              VIA   -    MD0100PA00X+176725Y+012251X0200Y         S0      
317GND              VIA   -    MD0100PA00X+176226Y+013173X0200Y         S0      
317GND              VIA   -    MD0100PA00X+176226Y+012251X0200Y         S0      
317GND              VIA   -    MD0100PA00X+175901Y+010378X0200Y    R270 S0      
327GND              R455  -1          A01X+175901Y+010135X0198Y0197R270 S1      
317GND              VIA   -    MD0100PA00X+177017Y+010362X0200Y    R090 S0      
327GND              U407  -S          A01X+177017Y+010792X0400Y0560R180 S1      
317GND              VIA   -    MD0100PA00X+176725Y+011756X0200Y         S0      
317GND              VIA   -    MD0100PA00X+178311Y+042674X0200Y    R180 S0      
327GND              PC827 -2   M      A01X+178311Y+042926X0198Y0197R270 S1      
317GND              VIA   -    MD0100PA00X+178315Y+042039X0200Y    R180 S0      
317GND              VIA   -    MD0100PA00X+178565Y+042039X0200Y    R180 S0      
317GND              VIA   -    MD0100PA00X+178065Y+042039X0200Y    R180 S0      
317GND              VIA   -    MD0100PA00X+178311Y+042424X0200Y    R180 S0      
317GND              VIA   -    MD0100PA00X+178053Y+040824X0200Y    R180 S0      
317GND              VIA   -    MD0100PA00X+178553Y+040824X0200Y    R180 S0      
317GND              VIA   -    MD0100PA00X+178303Y+040824X0200Y    R180 S0      
317GND              VIA   -    MD0100PA00X+177810Y+039666X0200Y    R090 S0      
317GND              VIA   -    MD0100PA00X+177810Y+040166X0200Y    R090 S0      
317GND              VIA   -    MD0100PA00X+177810Y+039916X0200Y    R090 S0      
317GND              VIA   -    MD0100PA00X+179014Y+039666X0200Y    R090 S0      
317GND              VIA   -    MD0100PA00X+179014Y+040166X0200Y    R090 S0      
317GND              VIA   -    MD0100PA00X+179014Y+039916X0200Y    R090 S0      
317GND              VIA   -    MD0100PA00X+179053Y+030375X0200Y    R180 S0      
317GND              VIA   -    MD0100PA00X+178592Y+022186X0200Y         S0      
327GND              C2876 -2   M      A01X+178334Y+022186X0198Y0197     S1      
317GND              VIA   -    MD0100PA00X+178592Y+021686X0200Y         S0      
327GND              PC589 -2          A01X+178334Y+021686X0198Y0197     S1      
317GND              VIA   -    MD0100PA00X+178592Y+021286X0200Y         S0      
317GND              VIA   -    MD0100PA00X+178592Y+020086X0200Y         S0      
317GND              VIA   -    MD0100PA00X+178589Y+018066X0200Y         S0      
327GND              R675  -2          A01X+178324Y+018066X0198Y0197     S1      
317GND              VIA   -    MD0100PA00X+178589Y+017266X0200Y         S0      
327GND              R673  -2          A01X+178324Y+017266X0198Y0197     S1      
317GND              VIA   -    MD0100PA00X+177818Y+011726X0200Y         S0      
327GND              R6213 -1          A01X+177860Y+011449X0198Y0197R180 S1      
317GND              VIA   -    MD0100PA00X+177958Y+009195X0200Y    R180 S0      
327GND              C2735 -1          A01X+177702Y+009195X0198Y0197R270 S1      
317GND              VIA   -    MD0100PA00X+178238Y+005551X0200Y         S0      
327GND              C2742 -1          A01X+178238Y+005801X0198Y0197R180 S1      
317GND              VIA   -    MD0100PA00X+178888Y+005987X0200Y         S0      
327GND              U141  -4          A01X+178725Y+006472X0240Y0460R180 S1      
317GND              VIA   -    MD0100PA00X+176510Y+046641X0200Y    R090 S0      
327GND              PC495 -2          A01X+176250Y+046641X0198Y0197     S1      
317GND              VIA   -    MD0100PA00X+176684Y+045564X0200Y    R270 S0      
317GND              VIA   -    MD0100PA00X+176684Y+045284X0200Y    R270 S0      
317GND              VIA   -    MD0100PA00X+176684Y+045004X0200Y    R270 S0      
317GND              VIA   -    M      A01X+176509Y+042394X0200Y         S2      
017GND              VIA   -    M      A18X+176509Y+042394X0260Y         S2      
017GND                    -    MD0100PA00X+176509Y+042394                       
317GND              VIA   -    MD0100PA00X+176789Y+042394X0200Y         S0      
317GND              VIA   -    MD0100PA00X+177039Y+042394X0200Y         S0      
317GND              VIA   -    MD0100PA00X+177289Y+042394X0200Y         S0      
317GND              VIA   -    MD0100PA00X+177295Y+041361X0200Y         S0      
317GND              VIA   -    MD0100PA00X+177045Y+041361X0200Y         S0      
317GND              VIA   -    MD0100PA00X+176795Y+041361X0200Y         S0      
317GND              VIA   -    MD0100PA00X+183009Y+033321X0200Y    R270 S0      
317GND              VIA   -    MD0100PA00X+183773Y+032473X0200Y    R270 S0      
317GND              VIA   -    MD0100PA00X+183790Y+030477X0200Y    R270 S0      
317GND              VIA   -    MD0100PA00X+183790Y+028477X0200Y    R270 S0      
317GND              VIA   -    MD0100PA00X+183790Y+026477X0200Y    R270 S0      
317GND              VIA   -    MD0100PA00X+183790Y+024477X0200Y    R270 S0      
317GND              VIA   -    MD0100PA00X+183790Y+022477X0200Y    R270 S0      
317GND              VIA   -    MD0100PA00X+183790Y+020477X0200Y    R270 S0      
317GND              VIA   -    MD0100PA00X+183790Y+018477X0200Y    R270 S0      
317GND              VIA   -    MD0100PA00X+183790Y+016477X0200Y    R270 S0      
317GND              VIA   -    MD0100PA00X+183790Y+014477X0200Y    R270 S0      
317GND              VIA   -    MD0100PA00X+183790Y+012477X0200Y    R270 S0      
317GND              VIA   -    MD0100PA00X+183790Y+010477X0200Y    R270 S0      
317GND              VIA   -    MD0100PA00X+183790Y+008477X0200Y    R270 S0      
317GND              VIA   -    MD0100PA00X+183790Y+006477X0200Y    R270 S0      
317GND              VIA   -    MD0100PA00X+183790Y+004477X0200Y    R270 S0      
317GND              VIA   -    MD0100PA00X+183790Y+002477X0200Y    R270 S0      
317GND              VIA   -    MD0100PA00X+183654Y+000447X0200Y    R270 S0      
317GND              VIA   -    MD0100PA00X+182556Y+000300X0200Y    R270 S0      
317GND              VIA   -    MD0100PA00X+182298Y+046605X0200Y    R270 S0      
317GND              VIA   -    M      A01X+181744Y+044710X0200Y    R180 S2      
017GND              VIA   -    M      A18X+181744Y+044710X0260Y    R180 S2      
017GND                    -    MD0100PA00X+181744Y+044710                       
327GND              PC835 -2   M      A01X+181501Y+044710X0198Y0197     S1      
317GND              VIA   -    MD0100PA00X+182298Y+044605X0200Y    R270 S0      
317GND              VIA   -    MD0100PA00X+182298Y+042605X0200Y    R270 S0      
317GND              VIA   -    MD0100PA00X+182298Y+040605X0200Y    R270 S0      
317GND              VIA   -    MD0100PA00X+182298Y+038605X0200Y    R270 S0      
317GND              VIA   -    MD0100PA00X+182298Y+036605X0200Y    R270 S0      
317GND              VIA   -    MD0100PA00X+182298Y+034605X0200Y    R270 S0      
317GND              VIA   -    MD0100PA00X+180357Y+043616X0200Y    R270 S0      
327GND              PU106 -3          A01X+180044Y+043616X0100Y0320R090 S1      
317GND              VIA   -    MD0100PA00X+180498Y+043398X0200Y    R270 S0      
327GND              PU106 -2          A01X+180044Y+043420X0100Y0320R090 S1      
317GND              VIA   -    MD0100PA00X+180499Y+029759X0200Y    R180 S0      
317GND              VIA   -    MD0100PA00X+179157Y+007454X0200Y         S0      
317GND              VIA   -    MD0100PA00X+179001Y+046861X0200Y         S0      
327GND              Q219  -4          A01X+178710Y+046861X0240Y0240R270 S1      
317GND              VIA   -    MD0100PA00X+178671Y+045504X0200Y    R270 S0      
327GND              PC451 -1          A01X+006620Y+047799X0400Y0500     S1      
327GND              PC450 -2          A01X+006338Y+048339X0198Y0197     S1      
327GND              PC475 -1          A01X+143746Y+047799X0400Y0500     S1      
327GND              PC462 -2          A01X+143464Y+048339X0198Y0197     S1      
327GND              PC466 -2          A01X+127850Y+048503X0198Y0197R090 S1      
327GND              PC449 -1          A01X+098038Y+047799X0400Y0500     S1      
327GND              PC474 -2          A01X+097755Y+048339X0198Y0197     S1      
327GND              PC488 -2          A01X+082141Y+048003X0198Y0197R090 S1      
327GND              PC448 -2          A01X+082541Y+048382X0198Y0197R180 S1      
327GND              PC489 -2          A01X+081602Y+048302X0400Y0500R270 S1      
327GND              PC463 -1          A01X+052329Y+047799X0400Y0500     S1      
327GND              PC484 -2          A01X+052046Y+048339X0198Y0197     S1      
327GND              PC464 -2          A01X+036433Y+048503X0198Y0197R090 S1      
327GND              PC490 -2          A01X+173559Y+048503X0198Y0197R090 S1      
327GND              PC660 -2          A01X+006622Y+047063X0198Y0197R090 S1      
327GND              PU80  -3          A01X+006119Y+045156X0100Y0280     S1      
327GND              PC658 -2          A01X+005494Y+045176X0198Y0197R270 S1      
327GND              PR6916-2   M      A01X+005776Y+043992X0198Y0197R270 S1      
327GND              PR6915-2   M      A01X+006176Y+043992X0198Y0197R270 S1      
327GND              PC664 -2   M      A01X+006576Y+043992X0198Y0197R270 S1      
327GND              Q212  -4          A01X+004269Y+045438X0240Y0240R180 S1      
327GND              Q212  -1          A01X+004860Y+046146X0240Y0240R180 S1      
327GND              PC665 -2          A01X+005822Y+047063X0198Y0197R090 S1      
327GND              PR7113-2   M      A01X+077739Y+010475X0198Y0197R270 S1      
327GND              PR7114-2   M      A01X+077339Y+010475X0198Y0197R270 S1      
317GND              VIA   -    MD0100PA00X+078741Y+010917X0200Y         S0      
317GND              VIA   -    MD0100PA00X+076918Y+011339X0200Y         S0      
327GND              PC937 -2          A01X+076942Y+013090X0198Y0197R090 S1      
317GND              VIA   -    MD0100PA00X+077196Y+013090X0200Y         S0      
327GND              PC932 -2          A01X+077942Y+013090X0198Y0197R090 S1      
317GND              VIA   -    MD0100PA00X+077942Y+013330X0200Y         S0      
317GND              VIA   -    MD0100PA00X+077339Y+010225X0200Y    R180 S0      
317GND              VIA   -    MD0100PA00X+077739Y+010225X0200Y    R180 S0      
327GND              PC936 -2   M      A01X+078139Y+010475X0198Y0197R270 S1      
317GND              VIA   -    M      A01X+078139Y+010225X0200Y    R180 S2      
017GND              VIA   -    M      A18X+078139Y+010225X0260Y    R180 S2      
017GND                    -    MD0100PA00X+078139Y+010225                       
327GND              PU126 -3   M      A01X+077316Y+011368X0100Y0280     S1      
317GND              VIA   -    MD0100PA00X+077182Y+011078X0200Y         S0      
317GND              VIA   -    MD0100PA00X+078441Y+010917X0200Y         S0      
327GND              R6296 -1          A01X+082231Y+083004X0198Y0197R180 S1      
317GND              VIA   -    MD0100PA00X+096637Y+114517X0200Y         S0      
317GND              VIA   -    MD0100PA00X+096887Y+114517X0200Y         S0      
327GND              PC21  -2          A01X+002942Y+067576X0400Y0500     S1      
327GND              PC20  -2          A01X+002942Y+066729X0400Y0500     S1      
327GND              PC614 -2          A01X+005419Y+063939X0198Y0197R090 S1      
327GND              R905  -1          A01X+005769Y+063939X0198Y0197R270 S1      
327GND              C839  -1          A01X+006119Y+063939X0198Y0197R270 S1      
327GND              PR6875-2          A01X+005019Y+063939X0198Y0197R090 S1      
327GND              PC615 -2          A01X+004619Y+063939X0198Y0197R090 S1      
327GND              PC610 -1          A01X+003429Y+060731X0280Y0320R270 S1      
327GND              PR6871-2          A01X+003399Y+061374X0198Y0197R270 S1      
327GND              PC600 -2          A01X+003796Y+057519X0400Y0500     S1      
327GND              PD78  -A          A01X+003209Y+058611X0670Y0990R090 S1      
327GND              PC601 -2          A01X+003796Y+055919X0400Y0500     S1      
327GND              PC602 -2          A01X+003796Y+056719X0400Y0500     S1      
327GND              PD52  -A          A01X+008337Y+048035X0670Y0990R180 S1      
327GND              PC453 -2          A01X+007256Y+048431X0400Y0500R090 S1      
327GND              PC452 -2          A01X+006634Y+048709X0198Y0197R270 S1      
327GND              PD76  -A          A01X+007569Y+063596X0850Y0890R270 S1      
327GND              PC352 -2          A01X+005357Y+052927X0198Y0197     S1      
327GND              PC308 -2          A01X+005651Y+053383X0198Y0197R270 S1      
327GND              PC311 -2          A01X+006273Y+053106X0400Y0500R090 S1      
327GND              PD6   -A          A01X+007354Y+052609X0670Y0990R180 S1      
327GND              PC353 -1          A01X+005639Y+052397X0400Y0500     S1      
327GND              PD24  -A          A01X+006170Y+051102X0850Y0890R180 S1      
327GND              PU4   -7          A01X+007639Y+067871X0110Y0320     S1      
327GND              PU4   -8          A01X+007442Y+067871X0110Y0320     S1      
327GND              PU4   -TH         A01X+007737Y+067477X0280Y0520R090 S1      
327GND              R502  -2          A01X+007491Y+068444X0198Y0197R270 S1      
327GND              PC16  -2          A01X+009052Y+066410X0400Y0500R180 S1      
327GND              PC17  -2          A01X+007811Y+065942X0198Y0197R270 S1      
327GND              PR58  -2          A01X+008769Y+068211X0198Y0197     S1      
327GND              R16   -2          A01X+015039Y+059559X0198Y0197R180 S1      
327GND              R15   -2          A01X+015039Y+059159X0198Y0197R180 S1      
327GND              R17   -2          A01X+015039Y+059959X0198Y0197R180 S1      
327GND              C846  -2          A01X+015288Y+058606X0400Y0500R270 S1      
327GND              C845  -2          A01X+014588Y+058606X0400Y0500R270 S1      
327GND              C851  -2          A18X+018162Y+057539X0120Y0150R180 S2      
327GND              C847  -2          A18X+018162Y+056219X0120Y0150R180 S2      
327GND              C848  -2          A18X+018162Y+056539X0120Y0150R180 S2      
327GND              C849  -2          A18X+018162Y+056859X0120Y0150R180 S2      
327GND              C850  -2          A18X+018162Y+057199X0120Y0150R180 S2      
327GND              C854  -2          A18X+018318Y+055040X0198Y0197R180 S2      
327GND              C852  -2          A18X+018318Y+055440X0198Y0197R180 S2      
327GND              J20   -A1         A01X+019938Y+057545X0140Y0480R270 S1      
327GND              J20   -A2         A01X+019938Y+057309X0140Y0480R270 S1      
327GND              J20   -A3         A01X+019938Y+057073X0140Y0480R270 S1      
327GND              J20   -A4         A01X+019938Y+056837X0140Y0480R270 S1      
327GND              J20   -A5         A01X+019938Y+056600X0140Y0480R270 S1      
327GND              J20   -A6         A01X+019938Y+056364X0140Y0480R270 S1      
327GND              J21   -A1         A01X+027030Y+043006X0140Y0480R090 S1      
327GND              J21   -A2         A01X+027030Y+043242X0140Y0480R090 S1      
327GND              J21   -A3         A01X+027030Y+043478X0140Y0480R090 S1      
327GND              J21   -A4         A01X+027030Y+043715X0140Y0480R090 S1      
327GND              J21   -A5         A01X+027030Y+043951X0140Y0480R090 S1      
327GND              J21   -A6         A01X+027030Y+044187X0140Y0480R090 S1      
327GND              PC461 -1          A01X+036550Y+049422X0400Y0500R180 S1      
327GND              PC460 -2          A01X+036832Y+048882X0198Y0197R180 S1      
327GND              PD54  -A          A01X+034833Y+049186X0670Y0990     S1      
327GND              PC465 -2          A01X+035893Y+048802X0400Y0500R270 S1      
327GND              PC25  -2          A01X+046449Y+067304X0630Y1380R270 S1      
327GND              PC24  -2          A01X+040547Y+067304X0630Y1380R090 S1      
327GND              PC27  -2          A01X+044523Y+065454X0400Y0500R180 S1      
327GND              PC29  -2          A01X+044523Y+064773X0400Y0500R180 S1      
327GND              PC28  -2          A01X+042173Y+065454X0400Y0500     S1      
327GND              PC26  -2          A01X+042173Y+064773X0400Y0500     S1      
327GND              PC40  -2          A01X+042146Y+062890X0198Y0197R090 S1      
327GND              PC32  -2          A18X+045910Y+053799X0400Y0500R270 S2      
327GND              PC35  -2          A18X+044761Y+053808X0400Y0500R270 S2      
327GND              PC34  -2          A18X+043580Y+053809X0400Y0500R270 S2      
327GND              PC33  -2          A18X+042375Y+053808X0400Y0500R270 S2      
327GND              PC36  -2          A01X+046884Y+054002X0198Y0197R270 S1      
327GND              PC38  -2          A01X+044770Y+053243X0630Y1190     S1      
327GND              PC37  -2          A01X+042404Y+053243X0630Y1190     S1      
327GND              PC298 -2          A01X+044286Y+050900X0198Y0197R180 S1      
327GND              PC299 -1          A01X+044009Y+051554X0400Y0500R180 S1      
327GND              PD3   -A          A01X+041939Y+051199X0670Y0990     S1      
327GND              PC301 -2          A01X+043176Y+050765X0400Y0500R270 S1      
327GND              PC300 -2          A01X+043816Y+050618X0198Y0197R090 S1      
327GND              PC630 -1          A01X+049138Y+060731X0280Y0320R270 S1      
327GND              PR6894-2          A01X+049108Y+061374X0198Y0197R270 S1      
327GND              PC625 -2          A01X+049504Y+057519X0400Y0500     S1      
327GND              PD82  -A          A01X+048917Y+058611X0670Y0990R090 S1      
327GND              PC623 -2          A01X+049504Y+055919X0400Y0500     S1      
327GND              PC624 -2          A01X+049504Y+056719X0400Y0500     S1      
327GND              R1125 -1          A18X+050331Y+070476X0198Y0197R180 S2      
327GND              C2655 -2          A18X+050266Y+069324X0280Y0320R090 S2      
327GND              C2656 -2          A18X+050407Y+069740X0198Y0197     S2      
327GND              R948  -1          A01X+051478Y+063939X0198Y0197R270 S1      
327GND              PC634 -2          A01X+051128Y+063939X0198Y0197R090 S1      
327GND              C841  -1          A01X+051828Y+063939X0198Y0197R270 S1      
327GND              PR6899-2          A01X+050728Y+063939X0198Y0197R090 S1      
327GND              PC635 -2          A01X+050328Y+063939X0198Y0197R090 S1      
327GND              PD81  -A          A01X+053278Y+063596X0850Y0890R270 S1      
327GND              PC332 -2          A01X+051360Y+053383X0198Y0197R270 S1      
327GND              PC333 -2          A01X+051982Y+053106X0400Y0500R090 S1      
327GND              PC328 -2          A01X+051065Y+052927X0198Y0197     S1      
327GND              PD14  -A          A01X+053063Y+052609X0670Y0990R180 S1      
327GND              PC329 -1          A01X+051348Y+052397X0400Y0500     S1      
327GND              PD4   -A          A01X+051879Y+051102X0850Y0890R180 S1      
327GND              PD56  -A          A01X+054046Y+048035X0670Y0990R180 S1      
327GND              PC477 -2          A01X+052965Y+048431X0400Y0500R090 S1      
327GND              PC476 -2          A01X+052343Y+048709X0198Y0197R270 S1      
327GND              R1123 -1          A18X+053302Y+071832X0198Y0197R090 S2      
327GND              C2654 -2          A18X+052610Y+071358X0198Y0197R180 S2      
327GND              C2653 -2          A18X+052721Y+071790X0280Y0320R270 S2      
327GND              R118  -2          A01X+060748Y+059559X0198Y0197R180 S1      
327GND              R117  -2          A01X+060748Y+059159X0198Y0197R180 S1      
327GND              R119  -2          A01X+060748Y+059959X0198Y0197R180 S1      
327GND              C875  -2          A01X+060997Y+058606X0400Y0500R270 S1      
327GND              C876  -2          A01X+060297Y+058606X0400Y0500R270 S1      
327GND              C879  -2          A18X+063870Y+057539X0120Y0150R180 S2      
327GND              C877  -2          A18X+063870Y+056219X0120Y0150R180 S2      
327GND              C878  -2          A18X+063870Y+056539X0120Y0150R180 S2      
327GND              C880  -2          A18X+063870Y+056859X0120Y0150R180 S2      
327GND              C881  -2          A18X+063870Y+057199X0120Y0150R180 S2      
327GND              C885  -2          A18X+064026Y+055040X0198Y0197R180 S2      
327GND              C884  -2          A18X+064026Y+055440X0198Y0197R180 S2      
327GND              J22   -A1         A01X+065647Y+057545X0140Y0480R270 S1      
327GND              J22   -A2         A01X+065647Y+057309X0140Y0480R270 S1      
327GND              J22   -A3         A01X+065647Y+057073X0140Y0480R270 S1      
327GND              J22   -A4         A01X+065647Y+056837X0140Y0480R270 S1      
327GND              J22   -A5         A01X+065647Y+056600X0140Y0480R270 S1      
327GND              J22   -A6         A01X+065647Y+056364X0140Y0480R270 S1      
327GND              J23   -A1         A01X+072739Y+043006X0140Y0480R090 S1      
327GND              J23   -A2         A01X+072739Y+043242X0140Y0480R090 S1      
327GND              J23   -A3         A01X+072739Y+043478X0140Y0480R090 S1      
327GND              J23   -A4         A01X+072739Y+043715X0140Y0480R090 S1      
327GND              J23   -A5         A01X+072739Y+043951X0140Y0480R090 S1      
327GND              J23   -A6         A01X+072739Y+044187X0140Y0480R090 S1      
327GND              PC485 -1          A01X+082259Y+048922X0400Y0500R180 S1      
327GND              PD58  -A          A01X+080542Y+048686X0670Y0990     S1      
327GND              C2804 -2          A18X+089838Y+059072X0198Y0197R090 S2      
327GND              C2788 -2          A18X+090715Y+059067X0198Y0197R090 S2      
327GND              C2801 -2          A18X+089417Y+059065X0198Y0197R090 S2      
327GND              C2790 -2          A18X+091142Y+057839X0198Y0197     S2      
327GND              C2787 -2          A18X+091137Y+058286X0198Y0197     S2      
327GND              C2786 -2          A18X+091142Y+058662X0198Y0197     S2      
327GND              C2802 -2          A18X+089078Y+057729X0198Y0197R180 S2      
327GND              C2800 -2          A18X+089083Y+058577X0198Y0197R180 S2      
327GND              C2795 -2          A18X+090439Y+056778X0198Y0197R270 S2      
327GND              C2794 -2          A18X+090852Y+056778X0198Y0197R270 S2      
327GND              C2806 -2          A18X+089882Y+056778X0198Y0197R270 S2      
327GND              U117  -B10        A01X+090786Y+056699X0110Y0180R180 S1      
327GND              U117  -B12        A01X+091229Y+056945X0110Y0180R090 S1      
327GND              PC802 -2          A01X+095213Y+057519X0400Y0500     S1      
327GND              PD94  -A          A01X+094626Y+058611X0670Y0990R090 S1      
327GND              PC801 -2          A01X+095213Y+055919X0400Y0500     S1      
327GND              PC800 -2          A01X+095213Y+056719X0400Y0500     S1      
327GND              PC810 -1          A01X+094846Y+060731X0280Y0320R270 S1      
327GND              PR7029-2          A01X+094816Y+061374X0198Y0197R270 S1      
327GND              R954  -1          A01X+097186Y+063939X0198Y0197R270 S1      
327GND              PC813 -2          A01X+096836Y+063939X0198Y0197R090 S1      
327GND              C843  -1          A01X+097536Y+063939X0198Y0197R270 S1      
327GND              PR7032-2          A01X+096436Y+063939X0198Y0197R090 S1      
327GND              PC814 -2          A01X+096036Y+063939X0198Y0197R090 S1      
327GND              PD93  -A          A01X+098986Y+063596X0850Y0890R270 S1      
327GND              PC309 -2          A01X+097069Y+053383X0198Y0197R270 S1      
327GND              PC342 -2          A01X+096774Y+052927X0198Y0197     S1      
327GND              PC310 -2          A01X+097691Y+053106X0400Y0500R090 S1      
327GND              PD7   -A          A01X+098772Y+052609X0670Y0990R180 S1      
327GND              PC343 -1          A01X+097057Y+052397X0400Y0500     S1      
327GND              PD92  -A          A01X+097587Y+051102X0850Y0890R180 S1      
327GND              PD53  -A          A01X+099755Y+048035X0670Y0990R180 S1      
327GND              PC455 -2          A01X+098674Y+048431X0400Y0500R090 S1      
327GND              PC454 -2          A01X+098052Y+048709X0198Y0197R270 S1      
327GND              R220  -2          A01X+106457Y+059559X0198Y0197R180 S1      
327GND              R219  -2          A01X+106457Y+059159X0198Y0197R180 S1      
327GND              R221  -2          A01X+106457Y+059959X0198Y0197R180 S1      
327GND              C906  -2          A01X+106706Y+058606X0400Y0500R270 S1      
327GND              C905  -2          A01X+106006Y+058606X0400Y0500R270 S1      
327GND              C909  -2          A18X+109579Y+057539X0120Y0150R180 S2      
327GND              C910  -2          A18X+109579Y+056859X0120Y0150R180 S2      
327GND              C908  -2          A18X+109579Y+056539X0120Y0150R180 S2      
327GND              C907  -2          A18X+109579Y+056219X0120Y0150R180 S2      
327GND              C911  -2          A18X+109579Y+057199X0120Y0150R180 S2      
327GND              C914  -2          A18X+109735Y+055040X0198Y0197R180 S2      
327GND              C912  -2          A18X+109735Y+055440X0198Y0197R180 S2      
327GND              J24   -A1         A01X+111355Y+057545X0140Y0480R270 S1      
327GND              J24   -A2         A01X+111355Y+057309X0140Y0480R270 S1      
327GND              J24   -A3         A01X+111355Y+057073X0140Y0480R270 S1      
327GND              J24   -A4         A01X+111355Y+056837X0140Y0480R270 S1      
327GND              J24   -A5         A01X+111355Y+056600X0140Y0480R270 S1      
327GND              J24   -A6         A01X+111355Y+056364X0140Y0480R270 S1      
327GND              J25   -A1         A01X+118448Y+043006X0140Y0480R090 S1      
327GND              J25   -A2         A01X+118448Y+043242X0140Y0480R090 S1      
327GND              J25   -A3         A01X+118448Y+043478X0140Y0480R090 S1      
327GND              J25   -A4         A01X+118448Y+043715X0140Y0480R090 S1      
327GND              J25   -A5         A01X+118448Y+043951X0140Y0480R090 S1      
327GND              J25   -A6         A01X+118448Y+044187X0140Y0480R090 S1      
327GND              PC487 -1          A01X+127967Y+049422X0400Y0500R180 S1      
327GND              PC486 -2          A01X+128250Y+048882X0198Y0197R180 S1      
327GND              PC467 -2          A01X+127311Y+048802X0400Y0500R270 S1      
327GND              PD55  -A          A01X+126250Y+049186X0670Y0990     S1      
327GND              PC822 -2          A01X+140922Y+057519X0400Y0500     S1      
327GND              PD15  -A          A01X+140335Y+058611X0670Y0990R090 S1      
327GND              PC335 -2          A01X+140922Y+055919X0400Y0500     S1      
327GND              PC823 -2          A01X+140922Y+056719X0400Y0500     S1      
327GND              PR7056-2          A01X+142145Y+063939X0198Y0197R090 S1      
327GND              PC833 -2          A01X+142545Y+063939X0198Y0197R090 S1      
327GND              C981  -1          A01X+143245Y+063939X0198Y0197R270 S1      
327GND              R960  -1          A01X+142895Y+063939X0198Y0197R270 S1      
327GND              PC834 -2          A01X+141745Y+063939X0198Y0197R090 S1      
327GND              PC830 -1          A01X+140555Y+060731X0280Y0320R270 S1      
327GND              PR7053-2          A01X+140525Y+061374X0198Y0197R270 S1      
327GND              PC334 -2          A01X+142777Y+053383X0198Y0197R270 S1      
327GND              PC304 -2          A01X+142483Y+052927X0198Y0197     S1      
327GND              PC819 -2          A01X+143399Y+053106X0400Y0500R090 S1      
327GND              PD98  -A          A01X+144480Y+052609X0670Y0990R180 S1      
327GND              PC305 -1          A01X+142765Y+052397X0400Y0500     S1      
327GND              PD9   -A          A01X+143296Y+051102X0850Y0890R180 S1      
327GND              PD57  -A          A01X+145463Y+048035X0670Y0990R180 S1      
327GND              PC478 -2          A01X+143760Y+048709X0198Y0197R270 S1      
327GND              PC479 -2          A01X+144382Y+048431X0400Y0500R090 S1      
327GND              PD5   -A          A01X+144695Y+063596X0850Y0890R270 S1      
327GND              R322  -2          A01X+152165Y+059559X0198Y0197R180 S1      
327GND              R321  -2          A01X+152165Y+059159X0198Y0197R180 S1      
327GND              R323  -2          A01X+152165Y+059959X0198Y0197R180 S1      
327GND              C936  -2          A01X+151714Y+058606X0400Y0500R270 S1      
327GND              C935  -2          A01X+152414Y+058606X0400Y0500R270 S1      
327GND              C939  -2          A18X+155288Y+057539X0120Y0150R180 S2      
327GND              C940  -2          A18X+155288Y+056859X0120Y0150R180 S2      
327GND              C938  -2          A18X+155288Y+056539X0120Y0150R180 S2      
327GND              C937  -2          A18X+155288Y+056219X0120Y0150R180 S2      
327GND              C941  -2          A18X+155288Y+057199X0120Y0150R180 S2      
327GND              C945  -2          A18X+155444Y+055040X0198Y0197R180 S2      
327GND              C942  -2          A18X+155444Y+055440X0198Y0197R180 S2      
327GND              J26   -A1         A01X+157064Y+057545X0140Y0480R270 S1      
327GND              J26   -A2         A01X+157064Y+057309X0140Y0480R270 S1      
327GND              J26   -A3         A01X+157064Y+057073X0140Y0480R270 S1      
327GND              J26   -A4         A01X+157064Y+056837X0140Y0480R270 S1      
327GND              J26   -A5         A01X+157064Y+056600X0140Y0480R270 S1      
327GND              J26   -A6         A01X+157064Y+056364X0140Y0480R270 S1      
327GND              J27   -A1         A01X+164156Y+043006X0140Y0480R090 S1      
327GND              J27   -A2         A01X+164156Y+043242X0140Y0480R090 S1      
327GND              J27   -A3         A01X+164156Y+043478X0140Y0480R090 S1      
327GND              J27   -A4         A01X+164156Y+043715X0140Y0480R090 S1      
327GND              J27   -A5         A01X+164156Y+043951X0140Y0480R090 S1      
327GND              J27   -A6         A01X+164156Y+044187X0140Y0480R090 S1      
327GND              PC473 -1          A01X+173676Y+049422X0400Y0500R180 S1      
327GND              PC472 -2          A01X+173958Y+048882X0198Y0197R180 S1      
327GND              PC491 -2          A01X+173019Y+048802X0400Y0500R270 S1      
327GND              PD59  -A          A01X+171959Y+049186X0670Y0990     S1      
327GND              PC595 -2          A01X+047177Y+048080X0400Y0500R180 S1      
327GND              PC593 -2          A01X+047097Y+046186X0198Y0197     S1      
327GND              PC793 -2          A01X+082276Y+046033X0400Y0500R180 S1      
327GND              PC789 -2          A01X+082196Y+044139X0198Y0197     S1      
317GND              VIA   -    MD0100PA00X+087014Y+066946X0200Y    R090 S0      
317GND              VIA   -    MD0100PA00X+083650Y+066784X0200Y         S0      
317GND              VIA   -    MD0100PA00X+083032Y+067416X0200Y         S0      
317GND              VIA   -    MD0100PA00X+074100Y+077110X0200Y         S0      
317GND              VIA   -    M      A01X+074407Y+074662X0200Y    R090 S2      
017GND              VIA   -    M      A18X+074407Y+074662X0260Y    R090 S2      
017GND                    -    MD0100PA00X+074407Y+074662                       
317GND              VIA   -    MD0100PA00X+072027Y+078248X0200Y    R090 S0      
327GND              C2096 -1          A01X+072027Y+077996X0198Y0197R180 S1      
317GND              VIA   -    M      A01X+071342Y+078603X0200Y    R090 S2      
017GND              VIA   -    M      A18X+071342Y+078603X0260Y    R090 S2      
017GND                    -    MD0100PA00X+071342Y+078603                       
317GND              VIA   -    MD0100PA00X+070268Y+078466X0200Y         S0      
327GND              R1033 -1          A18X+070008Y+078466X0198Y0197     S2      
317GND              VIA   -    MD0100PA00X+058462Y+078185X0200Y         S0      
317GND              VIA   -    MD0100PA00X+056919Y+078733X0200Y         S0      
317GND              VIA   -    MD0100PA00X+055829Y+078491X0200Y    R270 S0      
317GND              VIA   -    MD0100PA00X+056223Y+078491X0200Y    R270 S0      
317GND              VIA   -    MD0100PA00X+055824Y+079639X0200Y         S0      
317GND              VIA   -    MD0100PA00X+054260Y+078239X0200Y    R270 S0      
317GND              VIA   -    MD0100PA00X+055152Y+078489X0200Y    R270 S0      
317GND              VIA   -    MD0100PA00X+055436Y+078489X0200Y    R270 S0      
317GND              VIA   -    MD0100PA00X+054255Y+078491X0200Y    R270 S0      
317GND              VIA   -    MD0100PA00X+053245Y+078239X0200Y    R270 S0      
317GND              VIA   -    MD0100PA00X+053126Y+079493X0200Y         S0      
317GND              VIA   -    MD0100PA00X+053150Y+079233X0200Y         S0      
327GND              C2601 -2          A18X+053417Y+079265X0198Y0197     S2      
317GND              VIA   -    MD0100PA00X+053467Y+078504X0200Y    R270 S0      
317GND              VIA   -    MD0100PA00X+050906Y+078287X0200Y         S0      
317GND              VIA   -    MD0100PA00X+050813Y+078749X0200Y         S0      
317GND              VIA   -    MD0100PA00X+050932Y+079322X0200Y         S0      
327GND              C2591 -2          A18X+050932Y+079615X0198Y0197R180 S2      
317GND              VIA   -    MD0100PA00X+052232Y+079357X0200Y         S0      
317GND              VIA   -    MD0100PA00X+042921Y+078483X0200Y    R090 S0      
317GND              VIA   -    MD0100PA00X+037702Y+078254X0200Y    R090 S0      
317GND              VIA   -    MD0100PA00X+001796Y+078930X0200Y    R270 S0      
317GND              VIA   -    MD0100PA00X+182298Y+078605X0200Y    R270 S0      
317GND              VIA   -    MD0100PA00X+134714Y+078004X0200Y         S0      
317GND              VIA   -    MD0100PA00X+133500Y+072850X0200Y         S0      
327GND              R4762 -1          A01X+133258Y+072850X0198Y0197R180 S1      
317GND              VIA   -    MD0100PA00X+133500Y+072450X0200Y         S0      
327GND              R4761 -1          A01X+133258Y+072450X0198Y0197R180 S1      
317GND              VIA   -    MD0100PA00X+133500Y+068150X0200Y         S0      
327GND              R4781 -1          A01X+133258Y+068150X0198Y0197R180 S1      
317GND              VIA   -    MD0100PA00X+133500Y+067750X0200Y         S0      
327GND              R4780 -1          A01X+133258Y+067750X0198Y0197R180 S1      
317GND              VIA   -    MD0100PA00X+131900Y+067350X0200Y    R180 S0      
327GND              R4741 -2          A01X+132142Y+067350X0198Y0197R180 S1      
317GND              VIA   -    M      A01X+116076Y+066514X0200Y         S2      
017GND              VIA   -    M      A18X+116076Y+066514X0260Y         S2      
017GND                    -    MD0100PA00X+116076Y+066514                       
327GND              U32   -3          A01X+116076Y+066111X0400Y0500R180 S1      
317GND              VIA   -    MD0100PA00X+111284Y+066888X0200Y         S0      
327GND              C917  -2          A01X+111284Y+066628X0198Y0197R180 S1      
317GND              VIA   -    MD0100PA00X+097314Y+066762X0200Y         S0      
317GND              VIA   -    MD0100PA00X+096319Y+066762X0200Y         S0      
317GND              VIA   -    MD0100PA00X+001796Y+076930X0200Y    R270 S0      
317GND              VIA   -    MD0100PA00X+001796Y+074930X0200Y    R270 S0      
317GND              VIA   -    MD0100PA00X+001796Y+072930X0200Y    R270 S0      
317GND              VIA   -    MD0100PA00X+001796Y+070930X0200Y    R270 S0      
317GND              VIA   -    MD0100PA00X+001796Y+068930X0200Y    R270 S0      
317GND              VIA   -    MD0100PA00X+001796Y+066930X0200Y    R270 S0      
317GND              VIA   -    MD0100PA00X+001796Y+064930X0200Y    R270 S0      
317GND              VIA   -    MD0100PA00X+001796Y+062930X0200Y    R270 S0      
317GND              VIA   -    MD0100PA00X+001796Y+060930X0200Y    R270 S0      
317GND              VIA   -    MD0100PA00X+001796Y+058930X0200Y    R270 S0      
317GND              VIA   -    MD0100PA00X+001796Y+056930X0200Y    R270 S0      
317GND              VIA   -    MD0100PA00X+001796Y+054930X0200Y    R270 S0      
317GND              VIA   -    MD0100PA00X+001796Y+052930X0200Y    R270 S0      
317GND              VIA   -    MD0100PA00X+001796Y+050930X0200Y    R270 S0      
317GND              VIA   -    MD0100PA00X+001796Y+048930X0200Y    R270 S0      
317GND              VIA   -    MD0100PA00X+003041Y+067151X0200Y         S0      
317GND              VIA   -    MD0100PA00X+002785Y+067155X0200Y         S0      
317GND              VIA   -    MD0100PA00X+002582Y+068214X0200Y    R090 S0      
317GND              VIA   -    MD0100PA00X+002762Y+066309X0200Y    R090 S0      
317GND              VIA   -    MD0100PA00X+003037Y+066305X0200Y         S0      
317GND              VIA   -    MD0100PA00X+003669Y+064182X0200Y    R270 S0      
317GND              VIA   -    MD0100PA00X+002945Y+063356X0200Y         S0      
317GND              VIA   -    MD0100PA00X+003425Y+061109X0200Y         S0      
317GND              VIA   -    MD0100PA00X+003245Y+059122X0200Y         S0      
317GND              VIA   -    MD0100PA00X+002965Y+059122X0200Y         S0      
317GND              VIA   -    MD0100PA00X+003525Y+059122X0200Y         S0      
317GND              VIA   -    MD0100PA00X+003525Y+058122X0200Y         S0      
317GND              VIA   -    MD0100PA00X+002965Y+058122X0200Y         S0      
317GND              VIA   -    MD0100PA00X+003245Y+058122X0200Y         S0      
317GND              VIA   -    MD0100PA00X+002582Y+054073X0200Y    R180 S0      
327GND              PR193 -2          A01X+002840Y+054073X0198Y0197R180 S1      
317GND              VIA   -    MD0100PA00X+002582Y+055273X0200Y    R180 S0      
327GND              PC314 -2          A01X+002840Y+055273X0198Y0197R180 S1      
317GND              VIA   -    MD0100PA00X+002582Y+053673X0200Y    R180 S0      
327GND              PC360 -2          A01X+002840Y+053673X0198Y0197R180 S1      
317GND              VIA   -    MD0100PA00X+002582Y+053173X0200Y    R180 S0      
327GND              C2853 -2          A01X+002840Y+053173X0198Y0197R180 S1      
317GND              VIA   -    MD0100PA00X+003565Y+049998X0200Y    R180 S0      
327GND              PC458 -2          A01X+003823Y+049998X0198Y0197R180 S1      
317GND              VIA   -    MD0100PA00X+003565Y+048798X0200Y    R180 S0      
317GND              VIA   -    M      A01X+004219Y+064182X0200Y    R270 S2      
017GND              VIA   -    M      A18X+004219Y+064182X0260Y    R270 S2      
017GND                    -    MD0100PA00X+004219Y+064182                       
327GND              PC612 -2   M      A01X+004219Y+063939X0198Y0197R090 S1      
317GND              VIA   -    MD0100PA00X+003684Y+057119X0200Y         S0      
317GND              VIA   -    MD0100PA00X+003964Y+057119X0200Y         S0      
317GND              VIA   -    MD0100PA00X+003684Y+056319X0200Y         S0      
317GND              VIA   -    MD0100PA00X+003964Y+056319X0200Y         S0      
317GND              VIA   -    MD0100PA00X+004984Y+054683X0200Y    R180 S0      
317GND              VIA   -    MD0100PA00X+003684Y+055519X0200Y         S0      
317GND              VIA   -    MD0100PA00X+003964Y+055519X0200Y         S0      
317GND              VIA   -    MD0100PA00X+005531Y+068847X0200Y         S0      
327GND              PC22  -2          A01X+005260Y+068847X0198Y0197     S1      
317GND              VIA   -    MD0100PA00X+005313Y+062795X0200Y         S0      
327GND              PU71  -3          A01X+005313Y+062482X0100Y0320R180 S1      
317GND              VIA   -    MD0100PA00X+005532Y+062936X0200Y         S0      
327GND              PU71  -2          A01X+005510Y+062482X0100Y0320R180 S1      
317GND              VIA   -    M      A01X+006651Y+062824X0200Y    R270 S2      
017GND              VIA   -    M      A18X+006651Y+062824X0260Y    R270 S2      
017GND                    -    MD0100PA00X+006651Y+062824                       
327GND              PC598 -2   M      A01X+006399Y+062824X0198Y0197R090 S1      
317GND              VIA   -    MD0100PA00X+006279Y+060831X0200Y    R270 S0      
327GND              PC603 -2          A01X+006027Y+060831X0198Y0197     S1      
317GND              VIA   -    MD0100PA00X+006441Y+057298X0200Y    R090 S0      
327GND              C409  -2          A01X+006441Y+057576X0198Y0197R270 S1      
317GND              VIA   -    MD0100PA00X+006762Y+057284X0200Y    R090 S0      
317GND              VIA   -    MD0100PA00X+006820Y+052963X0200Y    R270 S0      
317GND              VIA   -    MD0100PA00X+006820Y+052463X0200Y    R270 S0      
317GND              VIA   -    MD0100PA00X+006820Y+052713X0200Y    R270 S0      
317GND              VIA   -    MD0100PA00X+006170Y+052745X0200Y    R180 S0      
317GND              VIA   -    MD0100PA00X+005654Y+052888X0200Y    R270 S0      
317GND              VIA   -    MD0100PA00X+005654Y+053138X0200Y    R270 S0      
317GND              VIA   -    MD0100PA00X+006023Y+052430X0200Y    R270 S0      
317GND              VIA   -    MD0100PA00X+006450Y+052745X0200Y    R180 S0      
317GND              VIA   -    MD0100PA00X+006820Y+052213X0200Y    R270 S0      
317GND              VIA   -    MD0100PA00X+006023Y+052180X0200Y    R270 S0      
317GND              VIA   -    MD0100PA00X+005925Y+051698X0200Y         S0      
317GND              VIA   -    MD0100PA00X+006425Y+051698X0200Y         S0      
317GND              VIA   -    MD0100PA00X+006175Y+051698X0200Y         S0      
317GND              VIA   -    MD0100PA00X+005955Y+050470X0200Y         S0      
317GND              VIA   -    MD0100PA00X+006205Y+050470X0200Y         S0      
317GND              VIA   -    MD0100PA00X+006455Y+050470X0200Y         S0      
317GND              VIA   -    MD0100PA00X+005967Y+050009X0200Y    R180 S0      
317GND              VIA   -    MD0100PA00X+007441Y+068191X0200Y         S0      
317GND              VIA   -    MD0100PA00X+008271Y+067471X0200Y    R090 S0      
317GND              VIA   -    MD0100PA00X+007231Y+068341X0200Y    R090 S0      
317GND              VIA   -    MD0100PA00X+007231Y+068021X0200Y    R090 S0      
317GND              VIA   -    M      A01X+007813Y+065690X0200Y    R090 S2      
017GND              VIA   -    M      A18X+007813Y+065690X0260Y    R090 S2      
017GND                    -    MD0100PA00X+007813Y+065690                       
317GND              VIA   -    MD0100PA00X+008174Y+063905X0200Y         S0      
317GND              VIA   -    MD0100PA00X+006967Y+063880X0200Y         S0      
317GND              VIA   -    MD0100PA00X+008174Y+063345X0200Y         S0      
317GND              VIA   -    MD0100PA00X+006967Y+063600X0200Y         S0      
317GND              VIA   -    MD0100PA00X+006967Y+063320X0200Y         S0      
317GND              VIA   -    MD0100PA00X+008174Y+063625X0200Y         S0      
317GND              VIA   -    MD0100PA00X+008368Y+060544X0200Y    R090 S0      
327GND              R685  -2          A01X+008368Y+060280X0198Y0197R090 S1      
317GND              VIA   -    MD0100PA00X+007568Y+060544X0200Y    R090 S0      
327GND              R686  -2          A01X+007568Y+060280X0198Y0197R090 S1      
317GND              VIA   -    MD0100PA00X+007582Y+059019X0200Y    R090 S0      
317GND              VIA   -    MD0100PA00X+007123Y+059014X0200Y    R090 S0      
317GND              VIA   -    MD0100PA00X+007173Y+057948X0200Y    R090 S0      
327GND              U79   -10         A01X+007252Y+058234X0090Y0240R180 S1      
317GND              VIA   -    MD0100PA00X+007118Y+058551X0200Y    R090 S0      
317GND              VIA   -    MD0100PA00X+007578Y+058551X0200Y    R090 S0      
327GND              U79   -TH  M      A01X+007350Y+058785X0670Y0670R270 S1      
317GND              VIA   -    MD0100PA00X+007074Y+051946X0200Y         S0      
317GND              VIA   -    MD0100PA00X+006824Y+051946X0200Y         S0      
317GND              VIA   -    MD0100PA00X+007324Y+051946X0200Y         S0      
317GND              VIA   -    MD0100PA00X+007574Y+051946X0200Y         S0      
317GND              VIA   -    MD0100PA00X+008771Y+068461X0200Y    R090 S0      
317GND              VIA   -    MD0100PA00X+008561Y+067471X0200Y    R090 S0      
317GND              VIA   -    MD0100PA00X+009213Y+066829X0200Y    R090 S0      
317GND              VIA   -    MD0100PA00X+008943Y+066829X0200Y    R090 S0      
317GND              VIA   -    MD0100PA00X+009346Y+064984X0200Y    R090 S0      
327GND              PC18  -2          A01X+009346Y+065225X0198Y0197R270 S1      
317GND              VIA   -    MD0100PA00X+011440Y+072797X0200Y         S0      
317GND              VIA   -    MD0100PA00X+011247Y+071632X0200Y         S0      
317GND              VIA   -    MD0100PA00X+011812Y+074756X0200Y         S0      
317GND              VIA   -    MD0100PA00X+014620Y+051986X0200Y    R270 S0      
317GND              VIA   -    MD0100PA00X+014079Y+051770X0200Y    R090 S0      
317GND              VIA   -    MD0100PA00X+013579Y+051770X0200Y    R270 S0      
317GND              VIA   -    MD0100PA00X+014079Y+051274X0200Y    R090 S0      
317GND              VIA   -    MD0100PA00X+013579Y+051274X0200Y    R270 S0      
317GND              VIA   -    MD0100PA00X+014620Y+049485X0200Y    R270 S0      
317GND              VIA   -    MD0100PA00X+014079Y+048774X0200Y    R090 S0      
317GND              VIA   -    MD0100PA00X+013579Y+048774X0200Y    R270 S0      
317GND              VIA   -    MD0100PA00X+014620Y+048990X0200Y    R270 S0      
317GND              VIA   -    MD0100PA00X+015119Y+051986X0200Y    R090 S0      
317GND              VIA   -    MD0100PA00X+015119Y+049485X0200Y    R090 S0      
317GND              VIA   -    MD0100PA00X+015119Y+048990X0200Y    R090 S0      
317GND              VIA   -    MD0100PA00X+014789Y+060759X0200Y         S0      
327GND              R26   -2          A01X+015039Y+060759X0198Y0197R180 S1      
317GND              VIA   -    M      A01X+014792Y+061560X0200Y         S2      
017GND              VIA   -    M      A18X+014792Y+061560X0260Y         S2      
017GND                    -    MD0100PA00X+014792Y+061560                       
327GND              R14   -2          A01X+015042Y+061160X0198Y0197R180 S1      
327GND              R13   -2   M      A01X+015042Y+061560X0198Y0197R180 S1      
317GND              VIA   -    MD0100PA00X+014790Y+059610X0200Y         S0      
317GND              VIA   -    MD0100PA00X+014561Y+059467X0200Y         S0      
317GND              VIA   -    MD0100PA00X+014709Y+059235X0200Y         S0      
317GND              VIA   -    MD0100PA00X+014716Y+058956X0200Y         S0      
317GND              VIA   -    MD0100PA00X+014789Y+059959X0200Y         S0      
317GND              VIA   -    MD0100PA00X+014567Y+059758X0200Y         S0      
317GND              VIA   -    MD0100PA00X+014070Y+053638X0200Y         S0      
327GND              C853  -2          A01X+014296Y+053878X0198Y0197R270 S1      
327GND              C855  -2          A01X+013897Y+053882X0198Y0197R270 S1      
317GND              VIA   -    MD0100PA00X+014079Y+052692X0200Y    R090 S0      
317GND              VIA   -    MD0100PA00X+014620Y+053403X0200Y    R270 S0      
317GND              VIA   -    MD0100PA00X+014620Y+053898X0200Y    R270 S0      
317GND              VIA   -    MD0100PA00X+014620Y+052481X0200Y    R270 S0      
317GND              VIA   -    MD0100PA00X+013579Y+053187X0200Y    R270 S0      
317GND              VIA   -    MD0100PA00X+014079Y+053187X0200Y    R090 S0      
317GND              VIA   -    MD0100PA00X+013579Y+052692X0200Y    R270 S0      
317GND              VIA   -    MD0100PA00X+015239Y+063495X0200Y         S0      
327GND              R22   -2          A01X+015042Y+063797X0198Y0197R180 S1      
327GND              R23   -2          A01X+015358Y+063142X0198Y0197     S1      
317GND              VIA   -    MD0100PA00X+015709Y+056200X0200Y         S0      
327GND              R30   -2          A01X+015430Y+056257X0198Y0197     S1      
317GND              VIA   -    MD0100PA00X+015738Y+055523X0200Y         S0      
327GND              R32   -2          A01X+015426Y+055856X0198Y0197     S1      
327GND              R34   -2   M      A01X+015426Y+055456X0198Y0197     S1      
317GND              VIA   -    MD0100PA00X+015119Y+052481X0200Y    R090 S0      
317GND              VIA   -    MD0100PA00X+015119Y+053403X0200Y    R090 S0      
317GND              VIA   -    MD0100PA00X+015119Y+053898X0200Y    R090 S0      
317GND              VIA   -    MD0100PA00X+017711Y+059511X0200Y         S0      
327GND              J20   -OB13       A01X+018127Y+059512X0140Y0480R270 S1      
317GND              VIA   -    MD0100PA00X+017665Y+060220X0200Y         S0      
327GND              J20   -OB10       A01X+018127Y+060220X0140Y0480R270 S1      
317GND              VIA   -    MD0100PA00X+017737Y+054711X0200Y         S0      
327GND              J20   -B13        A01X+018127Y+054711X0140Y0480R270 S1      
317GND              VIA   -    MD0100PA00X+017737Y+054002X0200Y         S0      
317GND              VIA   -    MD0100PA00X+017737Y+053293X0200Y         S0      
327GND              J20   -B19        A01X+018127Y+053293X0140Y0480R270 S1      
317GND              VIA   -    MD0100PA00X+017737Y+052585X0200Y         S0      
317GND              VIA   -    MD0100PA00X+017737Y+051876X0200Y         S0      
317GND              VIA   -    MD0100PA00X+017737Y+051167X0200Y         S0      
317GND              VIA   -    MD0100PA00X+017737Y+049589X0200Y         S0      
317GND              VIA   -    MD0100PA00X+017737Y+048880X0200Y         S0      
327GND              J20   -B32        A01X+018127Y+048880X0140Y0480R270 S1      
327GND              J20   -B49        A01X+018127Y+043167X0140Y0480R270 S1      
327GND              J20   -B46        A01X+018127Y+043876X0140Y0480R270 S1      
327GND              J20   -B55        A01X+018127Y+041750X0140Y0480R270 S1      
327GND              J20   -B52 M      A01X+018127Y+042459X0140Y0480R270 S1      
327GND              J20   -B64 M      A01X+018127Y+039624X0140Y0480R270 S1      
327GND              J20   -B61 M      A01X+018127Y+040333X0140Y0480R270 S1      
327GND              J20   -B67 M      A01X+018127Y+038915X0140Y0480R270 S1      
317GND              VIA   -    MD0100PA00X+019372Y+065694X0200Y         S0      
317GND              VIA   -    MD0100PA00X+019112Y+061440X0200Y    R180 S0      
327GND              R28   -2          A18X+019352Y+061440X0198Y0197     S2      
317GND              VIA   -    MD0100PA00X+019112Y+060640X0200Y    R180 S0      
327GND              R21   -2          A18X+019352Y+060640X0198Y0197     S2      
317GND              VIA   -    MD0100PA00X+019112Y+059440X0200Y    R180 S0      
327GND              R20   -2          A18X+019352Y+059440X0198Y0197     S2      
317GND              VIA   -    MD0100PA00X+019112Y+059840X0200Y    R180 S0      
327GND              R18   -2          A18X+019352Y+059840X0198Y0197     S2      
317GND              VIA   -    MD0100PA00X+019112Y+060240X0200Y    R180 S0      
327GND              R19   -2          A18X+019352Y+060240X0198Y0197     S2      
317GND              VIA   -    MD0100PA00X+018564Y+057410X0200Y         S0      
317GND              VIA   -    MD0100PA00X+018741Y+057233X0200Y         S0      
317GND              VIA   -    MD0100PA00X+018687Y+056068X0200Y         S0      
317GND              VIA   -    MD0100PA00X+018510Y+056244X0200Y         S0      
317GND              VIA   -    MD0100PA00X+018578Y+055012X0200Y         S0      
317GND              VIA   -    MD0100PA00X+018565Y+055287X0200Y         S0      
317GND              VIA   -    MD0100PA00X+018517Y+052585X0200Y    R180 S0      
327GND              J20   -B22 M      A01X+018127Y+052585X0140Y0480R270 S1      
317GND              VIA   -    MD0100PA00X+018517Y+051167X0200Y    R180 S0      
327GND              J20   -B28 M      A01X+018127Y+051167X0140Y0480R270 S1      
317GND              VIA   -    MD0100PA00X+018517Y+051876X0200Y    R180 S0      
327GND              J20   -B25 M      A01X+018127Y+051876X0140Y0480R270 S1      
317GND              VIA   -    MD0100PA00X+019408Y+051056X0200Y         S0      
317GND              VIA   -    MD0100PA00X+019083Y+051684X0200Y         S0      
317GND              VIA   -    MD0100PA00X+019548Y+049589X0200Y         S0      
317GND              VIA   -    MD0100PA00X+018738Y+049883X0200Y    R180 S0      
327GND              J20   -B29 M      A01X+018127Y+049589X0140Y0480R270 S1      
327GND              J20   -B35 M      A01X+018127Y+048171X0140Y0480R270 S1      
317GND              VIA   -    MD0100PA00X+019496Y+048771X0200Y         S0      
327GND              J20   -B41 M      A01X+018127Y+046754X0140Y0480R270 S1      
327GND              J20   -B38 M      A01X+018127Y+047463X0140Y0480R270 S1      
327GND              J20   -B43 M      A01X+018127Y+044585X0140Y0480R270 S1      
327GND              J20   -B58 M      A01X+018127Y+041041X0140Y0480R270 S1      
317GND              VIA   -    MD0100PA00X+020328Y+049589X0200Y    R180 S0      
327GND              J20   -A29 M      A01X+019938Y+049589X0140Y0480R270 S1      
317GND              VIA   -    MD0100PA00X+020808Y+049589X0200Y         S0      
327GND              J20   -A35 M      A01X+019938Y+048171X0140Y0480R270 S1      
317GND              VIA   -    MD0100PA00X+021058Y+048880X0200Y         S0      
317GND              VIA   -    MD0100PA00X+020808Y+048880X0200Y         S0      
317GND              VIA   -    MD0100PA00X+020328Y+048880X0200Y    R180 S0      
327GND              J20   -A32 M      A01X+019938Y+048880X0140Y0480R270 S1      
317GND              VIA   -    MD0100PA00X+021538Y+048880X0200Y         S0      
327GND              J20   -A38 M      A01X+019938Y+047463X0140Y0480R270 S1      
327GND              J20   -A41 M      A01X+019938Y+046754X0140Y0480R270 S1      
327GND              J20   -A43 M      A01X+019938Y+044585X0140Y0480R270 S1      
327GND              J20   -A49 M      A01X+019938Y+043167X0140Y0480R270 S1      
327GND              J20   -A46 M      A01X+019938Y+043876X0140Y0480R270 S1      
327GND              J20   -A55 M      A01X+019938Y+041750X0140Y0480R270 S1      
327GND              J20   -A52 M      A01X+019938Y+042459X0140Y0480R270 S1      
327GND              J20   -A64 M      A01X+019938Y+039624X0140Y0480R270 S1      
327GND              J20   -A61        A01X+019938Y+040333X0140Y0480R270 S1      
327GND              J20   -A58        A01X+019938Y+041041X0140Y0480R270 S1      
327GND              J20   -A67 M      A01X+019938Y+038915X0140Y0480R270 S1      
317GND              VIA   -    MD0100PA00X+020943Y+062530X0200Y         S0      
327GND              C858  -2          A18X+021615Y+062340X0198Y0197     S2      
317GND              VIA   -    MD0100PA00X+020328Y+059512X0200Y    R180 S0      
327GND              J20   -OA13       A01X+019938Y+059512X0140Y0480R270 S1      
317GND              VIA   -    MD0100PA00X+020328Y+060220X0200Y    R180 S0      
327GND              J20   -OA10       A01X+019938Y+060220X0140Y0480R270 S1      
317GND              VIA   -    MD0100PA00X+020374Y+057291X0200Y    R090 S0      
317GND              VIA   -    MD0100PA00X+020374Y+057541X0200Y    R090 S0      
317GND              VIA   -    MD0100PA00X+020374Y+057041X0200Y    R090 S0      
317GND              VIA   -    MD0100PA00X+020374Y+056541X0200Y    R090 S0      
317GND              VIA   -    MD0100PA00X+020374Y+056791X0200Y    R090 S0      
317GND              VIA   -    MD0100PA00X+021246Y+056050X0200Y         S0      
327GND              U8    -3          A18X+021246Y+055780X0240Y0240R180 S2      
317GND              VIA   -    MD0100PA00X+020328Y+055419X0200Y    R180 S0      
327GND              J20   -A10        A01X+019938Y+055419X0140Y0480R270 S1      
327GND              J20   -A13        A01X+019938Y+054711X0140Y0480R270 S1      
317GND              VIA   -    MD0100PA00X+020328Y+054711X0200Y    R180 S0      
327GND              R24   -2          A18X+020096Y+054497X0198Y0197R180 S2      
327GND              J20   -A16        A01X+019938Y+054002X0140Y0480R270 S1      
317GND              VIA   -    MD0100PA00X+020328Y+054002X0200Y    R180 S0      
317GND              VIA   -    MD0100PA00X+020328Y+053293X0200Y    R180 S0      
327GND              J20   -A19        A01X+019938Y+053293X0140Y0480R270 S1      
317GND              VIA   -    MD0100PA00X+020328Y+052585X0200Y    R180 S0      
327GND              J20   -A22        A01X+019938Y+052585X0140Y0480R270 S1      
317GND              VIA   -    MD0100PA00X+021538Y+053293X0200Y         S0      
317GND              VIA   -    MD0100PA00X+021538Y+052585X0200Y         S0      
317GND              VIA   -    MD0100PA00X+021058Y+052585X0200Y         S0      
317GND              VIA   -    MD0100PA00X+020808Y+052585X0200Y         S0      
317GND              VIA   -    MD0100PA00X+020808Y+054002X0200Y         S0      
317GND              VIA   -    MD0100PA00X+020808Y+053293X0200Y         S0      
317GND              VIA   -    MD0100PA00X+021058Y+053293X0200Y         S0      
317GND              VIA   -    MD0100PA00X+020328Y+051876X0200Y    R180 S0      
327GND              J20   -A25 M      A01X+019938Y+051876X0140Y0480R270 S1      
317GND              VIA   -    MD0100PA00X+020328Y+051167X0200Y    R180 S0      
327GND              J20   -A28 M      A01X+019938Y+051167X0140Y0480R270 S1      
317GND              VIA   -    MD0100PA00X+021538Y+051167X0200Y         S0      
317GND              VIA   -    MD0100PA00X+021058Y+051167X0200Y         S0      
317GND              VIA   -    MD0100PA00X+020808Y+051876X0200Y         S0      
317GND              VIA   -    MD0100PA00X+021058Y+051876X0200Y         S0      
317GND              VIA   -    MD0100PA00X+021538Y+051876X0200Y         S0      
317GND              VIA   -    MD0100PA00X+022265Y+060754X0200Y         S0      
327GND              U10   -3          A18X+022802Y+060777X0160Y0360R270 S2      
317GND              VIA   -    MD0100PA00X+022450Y+055500X0200Y         S0      
327GND              R38   -2          A01X+022702Y+055370X0198Y0197R180 S1      
317GND              VIA   -    MD0100PA00X+022392Y+054392X0200Y         S0      
327GND              C856  -2          A18X+022050Y+054392X0198Y0197R090 S2      
317GND              VIA   -    MD0100PA00X+024185Y+067846X0200Y         S0      
327GND              C859  -2          A01X+024185Y+067583X0198Y0197R180 S1      
317GND              VIA   -    MD0100PA00X+024658Y+066514X0200Y         S0      
327GND              U12   -3          A01X+024658Y+066111X0400Y0500R180 S1      
317GND              VIA   -    MD0100PA00X+024108Y+063824X0200Y         S0      
327GND              Q1    -4          A18X+023823Y+063824X0170Y0240R270 S2      
317GND              VIA   -    MD0100PA00X+024025Y+062833X0200Y         S0      
327GND              Q1    -1          A18X+023075Y+063312X0170Y0240R270 S2      
317GND              VIA   -    MD0100PA00X+024308Y+063649X0200Y         S0      
327GND              Q119  -1          A01X+024308Y+063379X0240Y0240     S1      
317GND              VIA   -    MD0100PA00X+024197Y+061606X0200Y         S0      
327GND              U11   -3          A18X+023745Y+061606X0220Y0530R090 S2      
317GND              VIA   -    MD0100PA00X+024733Y+059951X0200Y         S0      
327GND              C857  -2          A18X+024359Y+059951X0198Y0197R090 S2      
317GND              VIA   -    MD0100PA00X+026160Y+050963X0200Y         S0      
317GND              VIA   -    MD0100PA00X+025430Y+051671X0200Y         S0      
317GND              VIA   -    MD0100PA00X+025430Y+052380X0200Y         S0      
317GND              VIA   -    MD0100PA00X+026160Y+052380X0200Y         S0      
317GND              VIA   -    MD0100PA00X+025910Y+052380X0200Y         S0      
317GND              VIA   -    MD0100PA00X+025910Y+051671X0200Y         S0      
317GND              VIA   -    MD0100PA00X+026160Y+051671X0200Y         S0      
317GND              VIA   -    MD0100PA00X+025910Y+049384X0200Y         S0      
317GND              VIA   -    MD0100PA00X+025430Y+049384X0200Y         S0      
327GND              J21   -OA10       A01X+027030Y+040331X0140Y0480R090 S1      
317GND              VIA   -    MD0100PA00X+025887Y+068050X0200Y         S0      
317GND              VIA   -    MD0100PA00X+024898Y+063812X0200Y         S0      
327GND              Q119  -4          A01X+024898Y+064087X0240Y0240     S1      
317GND              VIA   -    MD0100PA00X+025430Y+061636X0200Y         S0      
317GND              VIA   -    MD0100PA00X+025910Y+061636X0200Y         S0      
317GND              VIA   -    MD0100PA00X+026160Y+060927X0200Y         S0      
317GND              VIA   -    MD0100PA00X+025910Y+060927X0200Y         S0      
317GND              VIA   -    MD0100PA00X+025430Y+060927X0200Y         S0      
317GND              VIA   -    MD0100PA00X+026160Y+060218X0200Y         S0      
317GND              VIA   -    MD0100PA00X+026160Y+059510X0200Y         S0      
317GND              VIA   -    MD0100PA00X+025910Y+059510X0200Y         S0      
317GND              VIA   -    MD0100PA00X+025430Y+059510X0200Y         S0      
317GND              VIA   -    MD0100PA00X+025430Y+060219X0200Y         S0      
317GND              VIA   -    MD0100PA00X+025910Y+060219X0200Y         S0      
317GND              VIA   -    MD0100PA00X+025430Y+058801X0200Y         S0      
317GND              VIA   -    MD0100PA00X+025430Y+058093X0200Y         S0      
317GND              VIA   -    MD0100PA00X+025910Y+058093X0200Y         S0      
317GND              VIA   -    MD0100PA00X+026160Y+058093X0200Y         S0      
317GND              VIA   -    MD0100PA00X+025910Y+057384X0200Y         S0      
317GND              VIA   -    MD0100PA00X+026160Y+057384X0200Y         S0      
317GND              VIA   -    MD0100PA00X+025430Y+057384X0200Y         S0      
317GND              VIA   -    MD0100PA00X+025910Y+058801X0200Y         S0      
317GND              VIA   -    MD0100PA00X+026160Y+058801X0200Y         S0      
317GND              VIA   -    MD0100PA00X+025910Y+056675X0200Y         S0      
317GND              VIA   -    MD0100PA00X+026160Y+056675X0200Y         S0      
317GND              VIA   -    MD0100PA00X+026160Y+055966X0200Y         S0      
317GND              VIA   -    MD0100PA00X+025430Y+056675X0200Y         S0      
317GND              VIA   -    MD0100PA00X+025430Y+053797X0200Y         S0      
317GND              VIA   -    MD0100PA00X+025430Y+053089X0200Y         S0      
317GND              VIA   -    MD0100PA00X+025910Y+053797X0200Y         S0      
317GND              VIA   -    MD0100PA00X+025910Y+053089X0200Y         S0      
317GND              VIA   -    MD0100PA00X+026160Y+053089X0200Y         S0      
327GND              J21   -OA13       A01X+027030Y+041039X0140Y0480R090 S1      
317GND              VIA   -    MD0100PA00X+027433Y+061636X0200Y    R180 S0      
317GND              VIA   -    MD0100PA00X+026640Y+061636X0200Y         S0      
327GND              J21   -A67 M      A01X+027030Y+061636X0140Y0480R090 S1      
317GND              VIA   -    MD0100PA00X+026640Y+060927X0200Y         S0      
327GND              J21   -A64        A01X+027030Y+060927X0140Y0480R090 S1      
317GND              VIA   -    MD0100PA00X+026640Y+059510X0200Y         S0      
327GND              J21   -A58        A01X+027030Y+059510X0140Y0480R090 S1      
317GND              VIA   -    MD0100PA00X+026640Y+060218X0200Y         S0      
327GND              J21   -A61        A01X+027030Y+060218X0140Y0480R090 S1      
317GND              VIA   -    MD0100PA00X+027423Y+057434X0200Y    R180 S0      
317GND              VIA   -    MD0100PA00X+026640Y+057384X0200Y         S0      
327GND              J21   -A49 M      A01X+027030Y+057384X0140Y0480R090 S1      
317GND              VIA   -    MD0100PA00X+026640Y+058801X0200Y         S0      
327GND              J21   -A55        A01X+027030Y+058801X0140Y0480R090 S1      
317GND              VIA   -    MD0100PA00X+026640Y+058093X0200Y         S0      
327GND              J21   -A52        A01X+027030Y+058092X0140Y0480R090 S1      
317GND              VIA   -    MD0100PA00X+027420Y+055966X0200Y    R180 S0      
317GND              VIA   -    MD0100PA00X+027459Y+056557X0200Y    R180 S0      
317GND              VIA   -    MD0100PA00X+026640Y+055966X0200Y         S0      
327GND              J21   -A43 M      A01X+027030Y+055966X0140Y0480R090 S1      
317GND              VIA   -    MD0100PA00X+026640Y+056675X0200Y         S0      
327GND              J21   -A46 M      A01X+027030Y+056675X0140Y0480R090 S1      
317GND              VIA   -    MD0100PA00X+027530Y+053568X0200Y    R180 S0      
317GND              VIA   -    MD0100PA00X+027546Y+052914X0200Y    R180 S0      
317GND              VIA   -    MD0100PA00X+026640Y+053797X0200Y         S0      
327GND              J21   -A41 M      A01X+027030Y+053797X0140Y0480R090 S1      
317GND              VIA   -    MD0100PA00X+026640Y+053089X0200Y         S0      
327GND              J21   -A38 M      A01X+027030Y+053089X0140Y0480R090 S1      
317GND              VIA   -    MD0100PA00X+027490Y+051461X0200Y    R180 S0      
317GND              VIA   -    MD0100PA00X+027482Y+052213X0200Y    R180 S0      
317GND              VIA   -    MD0100PA00X+027420Y+050963X0200Y    R180 S0      
317GND              VIA   -    MD0100PA00X+026640Y+050963X0200Y         S0      
327GND              J21   -A29 M      A01X+027030Y+050963X0140Y0480R090 S1      
317GND              VIA   -    MD0100PA00X+026640Y+051671X0200Y         S0      
327GND              J21   -A32 M      A01X+027030Y+051671X0140Y0480R090 S1      
327GND              J21   -A35 M      A01X+027030Y+052380X0140Y0480R090 S1      
317GND              VIA   -    MD0100PA00X+026640Y+052380X0200Y         S0      
317GND              VIA   -    MD0100PA00X+027416Y+049509X0200Y    R180 S0      
317GND              VIA   -    MD0100PA00X+026640Y+049384X0200Y         S0      
327GND              J21   -A28 M      A01X+027030Y+049384X0140Y0480R090 S1      
317GND              VIA   -    MD0100PA00X+027435Y+048944X0200Y    R180 S0      
327GND              J21   -A22 M      A01X+027030Y+047966X0140Y0480R090 S1      
327GND              J21   -A25 M      A01X+027030Y+048675X0140Y0480R090 S1      
327GND              J21   -A19 M      A01X+027030Y+047258X0140Y0480R090 S1      
327GND              J21   -A16 M      A01X+027030Y+046549X0140Y0480R090 S1      
327GND              J21   -A10        A01X+027030Y+045132X0140Y0480R090 S1      
327GND              J21   -A13        A01X+027030Y+045841X0140Y0480R090 S1      
327GND              J21   -OB13       A01X+028842Y+041039X0140Y0480R090 S1      
327GND              J21   -OB10       A01X+028842Y+040331X0140Y0480R090 S1      
317GND              VIA   -    MD0100PA00X+029232Y+060927X0200Y    R180 S0      
317GND              VIA   -    MD0100PA00X+029232Y+061636X0200Y    R180 S0      
327GND              J21   -B67        A01X+028842Y+061636X0140Y0480R090 S1      
317GND              VIA   -    MD0100PA00X+028458Y+060812X0200Y         S0      
327GND              J21   -B64 M      A01X+028842Y+060927X0140Y0480R090 S1      
317GND              VIA   -    MD0100PA00X+029232Y+060218X0200Y    R180 S0      
327GND              J21   -B61        A01X+028842Y+060218X0140Y0480R090 S1      
317GND              VIA   -    MD0100PA00X+029232Y+059510X0200Y    R180 S0      
327GND              J21   -B58        A01X+028842Y+059510X0140Y0480R090 S1      
317GND              VIA   -    MD0100PA00X+028452Y+057384X0200Y         S0      
317GND              VIA   -    MD0100PA00X+029232Y+058092X0200Y    R180 S0      
317GND              VIA   -    MD0100PA00X+029232Y+058801X0200Y    R180 S0      
327GND              J21   -B55        A01X+028842Y+058801X0140Y0480R090 S1      
317GND              VIA   -    MD0100PA00X+029232Y+057384X0200Y    R180 S0      
327GND              J21   -B49 M      A01X+028842Y+057384X0140Y0480R090 S1      
317GND              VIA   -    MD0100PA00X+028437Y+057998X0200Y         S0      
327GND              J21   -B52 M      A01X+028842Y+058092X0140Y0480R090 S1      
317GND              VIA   -    MD0100PA00X+029232Y+056675X0200Y    R180 S0      
317GND              VIA   -    MD0100PA00X+029232Y+055966X0200Y    R180 S0      
317GND              VIA   -    MD0100PA00X+028452Y+056675X0200Y         S0      
327GND              J21   -B46 M      A01X+028842Y+056675X0140Y0480R090 S1      
317GND              VIA   -    MD0100PA00X+028452Y+055966X0200Y         S0      
327GND              J21   -B43 M      A01X+028842Y+055966X0140Y0480R090 S1      
317GND              VIA   -    MD0100PA00X+028098Y+053797X0200Y         S0      
317GND              VIA   -    MD0100PA00X+028346Y+052548X0200Y         S0      
317GND              VIA   -    MD0100PA00X+028338Y+053276X0200Y         S0      
317GND              VIA   -    MD0100PA00X+029232Y+053089X0200Y    R180 S0      
327GND              J21   -B38 M      A01X+028842Y+053089X0140Y0480R090 S1      
317GND              VIA   -    MD0100PA00X+029232Y+053797X0200Y    R180 S0      
327GND              J21   -B41 M      A01X+028842Y+053797X0140Y0480R090 S1      
317GND              VIA   -    MD0100PA00X+028452Y+050963X0200Y         S0      
317GND              VIA   -    MD0100PA00X+028452Y+051671X0200Y         S0      
317GND              VIA   -    MD0100PA00X+029232Y+050963X0200Y    R180 S0      
327GND              J21   -B29 M      A01X+028842Y+050963X0140Y0480R090 S1      
317GND              VIA   -    MD0100PA00X+029232Y+051671X0200Y    R180 S0      
327GND              J21   -B32 M      A01X+028842Y+051671X0140Y0480R090 S1      
327GND              J21   -B35 M      A01X+028842Y+052380X0140Y0480R090 S1      
317GND              VIA   -    MD0100PA00X+029232Y+052380X0200Y    R180 S0      
317GND              VIA   -    MD0100PA00X+028452Y+049384X0200Y         S0      
317GND              VIA   -    MD0100PA00X+029232Y+049384X0200Y    R180 S0      
327GND              J21   -B28 M      A01X+028842Y+049384X0140Y0480R090 S1      
327GND              J21   -B22 M      A01X+028842Y+047966X0140Y0480R090 S1      
327GND              J21   -B25 M      A01X+028842Y+048675X0140Y0480R090 S1      
327GND              J21   -B16 M      A01X+028842Y+046549X0140Y0480R090 S1      
327GND              J21   -B19 M      A01X+028842Y+047258X0140Y0480R090 S1      
327GND              J21   -B13        A01X+028842Y+045841X0140Y0480R090 S1      
317GND              VIA   -    MD0100PA00X+032890Y+052273X0200Y    R270 S0      
317GND              VIA   -    MD0100PA00X+031850Y+051562X0200Y    R270 S0      
317GND              VIA   -    MD0100PA00X+032349Y+051066X0200Y    R090 S0      
317GND              VIA   -    MD0100PA00X+031850Y+051066X0200Y    R270 S0      
317GND              VIA   -    MD0100PA00X+032890Y+051777X0200Y    R270 S0      
317GND              VIA   -    MD0100PA00X+032349Y+051562X0200Y    R090 S0      
317GND              VIA   -    MD0100PA00X+032890Y+049277X0200Y    R270 S0      
317GND              VIA   -    MD0100PA00X+032890Y+048781X0200Y    R270 S0      
317GND              VIA   -    MD0100PA00X+032890Y+061529X0200Y    R270 S0      
317GND              VIA   -    MD0100PA00X+031850Y+060818X0200Y    R270 S0      
317GND              VIA   -    MD0100PA00X+032349Y+060818X0200Y    R090 S0      
317GND              VIA   -    MD0100PA00X+032890Y+061033X0200Y    R270 S0      
317GND              VIA   -    MD0100PA00X+032890Y+060112X0200Y    R270 S0      
317GND              VIA   -    MD0100PA00X+031850Y+060322X0200Y    R270 S0      
317GND              VIA   -    MD0100PA00X+032349Y+060322X0200Y    R090 S0      
317GND              VIA   -    MD0100PA00X+032349Y+059400X0200Y    R090 S0      
317GND              VIA   -    MD0100PA00X+032890Y+059616X0200Y    R270 S0      
317GND              VIA   -    MD0100PA00X+031850Y+059400X0200Y    R270 S0      
317GND              VIA   -    MD0100PA00X+032890Y+058694X0200Y    R270 S0      
317GND              VIA   -    MD0100PA00X+031850Y+058905X0200Y    R270 S0      
317GND              VIA   -    MD0100PA00X+032349Y+058905X0200Y    R090 S0      
317GND              VIA   -    MD0100PA00X+032890Y+058199X0200Y    R270 S0      
317GND              VIA   -    MD0100PA00X+032349Y+057983X0200Y    R090 S0      
317GND              VIA   -    MD0100PA00X+031850Y+057487X0200Y    R270 S0      
317GND              VIA   -    MD0100PA00X+032349Y+057487X0200Y    R090 S0      
317GND              VIA   -    MD0100PA00X+031850Y+057983X0200Y    R270 S0      
317GND              VIA   -    MD0100PA00X+032349Y+056070X0200Y    R090 S0      
317GND              VIA   -    MD0100PA00X+032349Y+056566X0200Y    R090 S0      
317GND              VIA   -    MD0100PA00X+032890Y+056781X0200Y    R270 S0      
317GND              VIA   -    MD0100PA00X+031850Y+056070X0200Y    R270 S0      
317GND              VIA   -    MD0100PA00X+031850Y+056566X0200Y    R270 S0      
317GND              VIA   -    MD0100PA00X+032890Y+057277X0200Y    R270 S0      
317GND              VIA   -    MD0100PA00X+032429Y+055678X0200Y    R180 S0      
327GND              C3999 -2          A01X+034228Y+056529X0198Y0197R090 S1      
327GND              U14   -S   M      A01X+032894Y+056004X0400Y0560R180 S1      
317GND              VIA   -    MD0100PA00X+031850Y+052979X0200Y    R270 S0      
317GND              VIA   -    MD0100PA00X+032349Y+052484X0200Y    R090 S0      
317GND              VIA   -    MD0100PA00X+032349Y+052979X0200Y    R090 S0      
317GND              VIA   -    MD0100PA00X+032890Y+053195X0200Y    R270 S0      
317GND              VIA   -    MD0100PA00X+032890Y+053690X0200Y    R270 S0      
317GND              VIA   -    MD0100PA00X+031850Y+052484X0200Y    R270 S0      
317GND              VIA   -    MD0100PA00X+033389Y+048781X0200Y    R090 S0      
317GND              VIA   -    MD0100PA00X+033389Y+061529X0200Y    R090 S0      
317GND              VIA   -    MD0100PA00X+033389Y+061033X0200Y    R090 S0      
317GND              VIA   -    MD0100PA00X+033389Y+060112X0200Y    R090 S0      
317GND              VIA   -    MD0100PA00X+033389Y+059616X0200Y    R090 S0      
317GND              VIA   -    MD0100PA00X+033389Y+058199X0200Y    R090 S0      
317GND              VIA   -    MD0100PA00X+033389Y+058694X0200Y    R090 S0      
317GND              VIA   -    MD0100PA00X+033389Y+056781X0200Y    R090 S0      
317GND              VIA   -    MD0100PA00X+033389Y+057277X0200Y    R090 S0      
317GND              VIA   -    MD0100PA00X+033836Y+055486X0200Y         S0      
317GND              VIA   -    MD0100PA00X+033389Y+053690X0200Y    R090 S0      
317GND              VIA   -    MD0100PA00X+033389Y+053195X0200Y    R090 S0      
317GND              VIA   -    MD0100PA00X+033389Y+051777X0200Y    R090 S0      
317GND              VIA   -    MD0100PA00X+033389Y+052273X0200Y    R090 S0      
317GND              VIA   -    MD0100PA00X+033389Y+049277X0200Y    R090 S0      
317GND              VIA   -    MD0100PA00X+035367Y+049612X0200Y    R090 S0      
317GND              VIA   -    MD0100PA00X+035678Y+049187X0200Y         S0      
317GND              VIA   -    MD0100PA00X+035928Y+049187X0200Y         S0      
317GND              VIA   -    MD0100PA00X+035367Y+049362X0200Y    R090 S0      
317GND              VIA   -    MD0100PA00X+035367Y+049112X0200Y    R090 S0      
317GND              VIA   -    MD0100PA00X+035367Y+048862X0200Y    R090 S0      
317GND              VIA   -    MD0100PA00X+037350Y+051795X0200Y         S0      
317GND              VIA   -    MD0100PA00X+036189Y+049626X0200Y    R090 S0      
317GND              VIA   -    MD0100PA00X+036189Y+049376X0200Y    R090 S0      
317GND              VIA   -    MD0100PA00X+036533Y+048757X0200Y    R090 S0      
317GND              VIA   -    MD0100PA00X+036533Y+049007X0200Y    R090 S0      
317GND              VIA   -    MD0100PA00X+039148Y+069068X0200Y         S0      
317GND              VIA   -    MD0100PA00X+038635Y+069356X0200Y         S0      
317GND              VIA   -    MD0100PA00X+038859Y+066423X0200Y         S0      
317GND              VIA   -    MD0100PA00X+039382Y+048738X0200Y    R090 S0      
327GND              C2879 -2          A01X+039124Y+048738X0198Y0197     S1      
317GND              VIA   -    MD0100PA00X+040310Y+067806X0200Y    R090 S0      
317GND              VIA   -    MD0100PA00X+040810Y+067806X0200Y    R090 S0      
317GND              VIA   -    MD0100PA00X+040560Y+067806X0200Y    R090 S0      
317GND              VIA   -    MD0100PA00X+040060Y+067806X0200Y    R090 S0      
317GND              VIA   -    MD0100PA00X+040060Y+066806X0200Y    R090 S0      
317GND              VIA   -    MD0100PA00X+040310Y+066806X0200Y    R090 S0      
317GND              VIA   -    MD0100PA00X+040810Y+066806X0200Y    R090 S0      
317GND              VIA   -    MD0100PA00X+040560Y+066806X0200Y    R090 S0      
317GND              VIA   -    MD0100PA00X+041060Y+067806X0200Y    R090 S0      
317GND              VIA   -    MD0100PA00X+041060Y+066806X0200Y    R090 S0      
317GND              VIA   -    MD0100PA00X+041823Y+065579X0200Y         S0      
317GND              VIA   -    MD0100PA00X+041767Y+063984X0200Y    R270 S0      
317GND              VIA   -    MD0100PA00X+041823Y+064898X0200Y         S0      
317GND              VIA   -    MD0100PA00X+041823Y+064648X0200Y         S0      
317GND              VIA   -    MD0100PA00X+042027Y+063984X0200Y    R270 S0      
317GND              VIA   -    MD0100PA00X+042327Y+063984X0200Y    R270 S0      
317GND              VIA   -    MD0100PA00X+041767Y+064264X0200Y    R270 S0      
317GND              VIA   -    MD0100PA00X+042027Y+064264X0200Y    R270 S0      
317GND              VIA   -    MD0100PA00X+042327Y+064264X0200Y    R270 S0      
317GND              VIA   -    MD0100PA00X+041823Y+065329X0200Y         S0      
317GND              VIA   -    MD0100PA00X+042327Y+063424X0200Y    R270 S0      
317GND              VIA   -    MD0100PA00X+042327Y+063704X0200Y    R270 S0      
317GND              VIA   -    MD0100PA00X+041767Y+063424X0200Y    R270 S0      
317GND              VIA   -    MD0100PA00X+041767Y+063704X0200Y    R270 S0      
317GND              VIA   -    MD0100PA00X+042027Y+063424X0200Y    R270 S0      
317GND              VIA   -    MD0100PA00X+042027Y+063704X0200Y    R270 S0      
317GND              VIA   -    MD0100PA00X+041767Y+063144X0200Y    R270 S0      
317GND              VIA   -    MD0100PA00X+042027Y+063144X0200Y    R270 S0      
317GND              VIA   -    MD0100PA00X+042327Y+063144X0200Y    R270 S0      
317GND              VIA   -    MD0100PA00X+041904Y+053889X0200Y    R270 S0      
317GND              VIA   -    MD0100PA00X+041904Y+053629X0200Y    R270 S0      
317GND              VIA   -    MD0100PA00X+041904Y+053099X0200Y    R270 S0      
317GND              VIA   -    MD0100PA00X+041904Y+052839X0200Y    R270 S0      
317GND              VIA   -    MD0100PA00X+041904Y+053369X0200Y    R270 S0      
317GND              VIA   -    MD0100PA00X+042473Y+051095X0200Y    R090 S0      
317GND              VIA   -    MD0100PA00X+041428Y+051322X0200Y    R090 S0      
317GND              VIA   -    MD0100PA00X+041428Y+051572X0200Y    R090 S0      
317GND              VIA   -    MD0100PA00X+041428Y+051072X0200Y    R090 S0      
317GND              VIA   -    MD0100PA00X+041428Y+050822X0200Y    R090 S0      
317GND              VIA   -    MD0100PA00X+042473Y+051595X0200Y    R090 S0      
317GND              VIA   -    MD0100PA00X+042473Y+051345X0200Y    R090 S0      
317GND              VIA   -    M      A01X+042473Y+050815X0200Y    R090 S2      
017GND              VIA   -    M      A18X+042473Y+050815X0260Y    R090 S2      
017GND                    -    MD0100PA00X+042473Y+050815                       
317GND              VIA   -    MD0100PA00X+044161Y+063101X0200Y    R270 S0      
317GND              VIA   -    MD0100PA00X+044183Y+062619X0200Y         S0      
327GND              PC42  -2          A01X+044974Y+062548X0198Y0197R270 S1      
327GND              PR62  -2   M      A01X+044574Y+062548X0198Y0197R270 S1      
317GND              VIA   -    MD0100PA00X+043637Y+062288X0200Y    R270 S0      
327GND              PC30  -2          A01X+043767Y+062046X0198Y0197     S1      
317GND              VIA   -    MD0100PA00X+043980Y+053918X0200Y    R180 S0      
317GND              VIA   -    MD0100PA00X+044270Y+053899X0200Y    R270 S0      
317GND              VIA   -    MD0100PA00X+043980Y+053668X0200Y    R180 S0      
317GND              VIA   -    MD0100PA00X+044270Y+053639X0200Y    R270 S0      
317GND              VIA   -    MD0100PA00X+043180Y+053918X0200Y         S0      
317GND              VIA   -    MD0100PA00X+042874Y+053889X0200Y    R270 S0      
317GND              VIA   -    MD0100PA00X+043180Y+053668X0200Y         S0      
317GND              VIA   -    MD0100PA00X+042874Y+053629X0200Y    R270 S0      
317GND              VIA   -    MD0100PA00X+044270Y+053109X0200Y    R270 S0      
317GND              VIA   -    MD0100PA00X+044270Y+052849X0200Y    R270 S0      
317GND              VIA   -    MD0100PA00X+042874Y+053099X0200Y    R270 S0      
317GND              VIA   -    MD0100PA00X+042874Y+052839X0200Y    R270 S0      
317GND              VIA   -    MD0100PA00X+044270Y+053379X0200Y    R270 S0      
317GND              VIA   -    MD0100PA00X+042874Y+053369X0200Y    R270 S0      
317GND              VIA   -    MD0100PA00X+043583Y+050958X0200Y         S0      
317GND              VIA   -    MD0100PA00X+043270Y+051628X0200Y    R090 S0      
317GND              VIA   -    MD0100PA00X+042769Y+050902X0200Y    R090 S0      
317GND              VIA   -    MD0100PA00X+043835Y+050868X0200Y    R090 S0      
317GND              VIA   -    M      A01X+043840Y+051149X0200Y         S2      
017GND              VIA   -    M      A18X+043840Y+051149X0260Y         S2      
017GND                    -    MD0100PA00X+043840Y+051149                       
317GND              VIA   -    MD0100PA00X+042769Y+050652X0200Y    R090 S0      
317GND              VIA   -    MD0100PA00X+044270Y+050643X0200Y    R090 S0      
317GND              VIA   -    MD0100PA00X+044784Y+071120X0200Y    R090 S0      
327GND              PC23  -2          A01X+044541Y+071120X0198Y0197     S1      
317GND              VIA   -    MD0100PA00X+044873Y+065579X0200Y    R180 S0      
317GND              VIA   -    MD0100PA00X+044873Y+064898X0200Y    R180 S0      
317GND              VIA   -    MD0100PA00X+044873Y+064648X0200Y    R180 S0      
317GND              VIA   -    MD0100PA00X+044873Y+065329X0200Y    R180 S0      
317GND              VIA   -    MD0100PA00X+044728Y+063388X0200Y         S0      
327GND              PR63  -1   M      A01X+044478Y+063388X0198Y0197R090 S1      
317GND              VIA   -    MD0100PA00X+045240Y+053889X0200Y    R270 S0      
317GND              VIA   -    MD0100PA00X+045510Y+053908X0200Y         S0      
317GND              VIA   -    MD0100PA00X+045240Y+053629X0200Y    R270 S0      
317GND              VIA   -    MD0100PA00X+045510Y+053658X0200Y         S0      
317GND              VIA   -    MD0100PA00X+045240Y+053099X0200Y    R270 S0      
317GND              VIA   -    MD0100PA00X+045240Y+052839X0200Y    R270 S0      
317GND              VIA   -    MD0100PA00X+045240Y+053369X0200Y    R270 S0      
317GND              VIA   -    MD0100PA00X+044309Y+049125X0200Y         S0      
317GND              VIA   -    MD0100PA00X+046435Y+066802X0200Y    R270 S0      
317GND              VIA   -    MD0100PA00X+046935Y+066802X0200Y    R270 S0      
317GND              VIA   -    MD0100PA00X+046685Y+066802X0200Y    R270 S0      
317GND              VIA   -    MD0100PA00X+045935Y+066802X0200Y    R270 S0      
317GND              VIA   -    MD0100PA00X+046185Y+066802X0200Y    R270 S0      
317GND              VIA   -    MD0100PA00X+046310Y+053908X0200Y    R180 S0      
317GND              VIA   -    MD0100PA00X+046885Y+053751X0200Y    R270 S0      
317GND              VIA   -    MD0100PA00X+046310Y+053658X0200Y    R180 S0      
317GND              VIA   -    MD0100PA00X+046856Y+051267X0200Y         S0      
327GND              C2852 -2          A01X+046598Y+051267X0198Y0197     S1      
317GND              VIA   -    MD0100PA00X+046856Y+050767X0200Y         S0      
317GND              VIA   -    MD0100PA00X+046856Y+050367X0200Y         S0      
327GND              PR190 -2          A01X+046598Y+050367X0198Y0197     S1      
317GND              VIA   -    M      A01X+046856Y+049167X0200Y         S2      
017GND              VIA   -    M      A18X+046856Y+049167X0260Y         S2      
017GND                    -    MD0100PA00X+046856Y+049167                       
317GND              VIA   -    MD0100PA00X+046435Y+067802X0200Y    R270 S0      
317GND              VIA   -    MD0100PA00X+046185Y+067802X0200Y    R270 S0      
317GND              VIA   -    MD0100PA00X+045935Y+067802X0200Y    R270 S0      
317GND              VIA   -    MD0100PA00X+046685Y+067802X0200Y    R270 S0      
317GND              VIA   -    MD0100PA00X+046935Y+067802X0200Y    R270 S0      
317GND              VIA   -    MD0100PA00X+048434Y+070548X0200Y    R270 S0      
317GND              VIA   -    MD0100PA00X+048434Y+070053X0200Y    R270 S0      
317GND              VIA   -    MD0100PA00X+048500Y+065977X0200Y         S0      
317GND              VIA   -    MD0100PA00X+049134Y+061109X0200Y         S0      
317GND              VIA   -    MD0100PA00X+048674Y+059122X0200Y         S0      
317GND              VIA   -    MD0100PA00X+048954Y+059122X0200Y         S0      
317GND              VIA   -    MD0100PA00X+048954Y+058122X0200Y         S0      
317GND              VIA   -    MD0100PA00X+048674Y+058122X0200Y         S0      
317GND              VIA   -    MD0100PA00X+048290Y+054073X0200Y    R180 S0      
317GND              VIA   -    MD0100PA00X+048290Y+055273X0200Y    R180 S0      
317GND              VIA   -    MD0100PA00X+048274Y+053722X0200Y    R180 S0      
327GND              PC325 -2          A01X+048548Y+053673X0198Y0197R180 S1      
317GND              VIA   -    MD0100PA00X+048290Y+053173X0200Y    R180 S0      
327GND              C2857 -2          A01X+048548Y+053173X0198Y0197R180 S1      
317GND              VIA   -    MD0100PA00X+049378Y+064182X0200Y    R270 S0      
327GND              PR6901-2   M      A01X+049378Y+063939X0198Y0197R090 S1      
317GND              VIA   -    M      A01X+049928Y+064182X0200Y    R270 S2      
017GND              VIA   -    M      A18X+049928Y+064182X0260Y    R270 S2      
017GND                    -    MD0100PA00X+049928Y+064182                       
327GND              PC632 -2   M      A01X+049928Y+063939X0198Y0197R090 S1      
317GND              VIA   -    MD0100PA00X+049234Y+059122X0200Y         S0      
317GND              VIA   -    MD0100PA00X+049234Y+058122X0200Y         S0      
317GND              VIA   -    MD0100PA00X+049673Y+057119X0200Y         S0      
317GND              VIA   -    MD0100PA00X+049393Y+057119X0200Y         S0      
317GND              VIA   -    MD0100PA00X+049673Y+056319X0200Y         S0      
317GND              VIA   -    MD0100PA00X+049393Y+056319X0200Y         S0      
317GND              VIA   -    MD0100PA00X+049673Y+055519X0200Y         S0      
317GND              VIA   -    MD0100PA00X+049393Y+055519X0200Y         S0      
317GND              VIA   -    M      A01X+050692Y+054683X0200Y    R180 S2      
017GND              VIA   -    M      A18X+050692Y+054683X0260Y    R180 S2      
017GND                    -    MD0100PA00X+050692Y+054683                       
317GND              VIA   -    MD0100PA00X+049274Y+049998X0200Y    R180 S0      
327GND              PC482 -2          A01X+049532Y+049998X0198Y0197R180 S1      
317GND              VIA   -    MD0100PA00X+049274Y+048798X0200Y    R180 S0      
317GND              VIA   -    MD0100PA00X+050072Y+076796X0200Y         S0      
317GND              VIA   -    MD0100PA00X+050567Y+076796X0200Y         S0      
317GND              VIA   -    MD0100PA00X+050755Y+073854X0200Y         S0      
317GND              VIA   -    MD0100PA00X+050070Y+070552X0200Y         S0      
317GND              VIA   -    MD0100PA00X+050331Y+071565X0200Y         S0      
327GND              C2660 -2          A18X+050331Y+071276X0198Y0197     S2      
317GND              VIA   -    MD0100PA00X+049901Y+069982X0200Y         S0      
317GND              VIA   -    MD0100PA00X+050162Y+069836X0200Y         S0      
317GND              VIA   -    MD0100PA00X+052241Y+069488X0200Y         S0      
317GND              VIA   -    MD0100PA00X+051800Y+069494X0200Y         S0      
317GND              VIA   -    MD0100PA00X+051199Y+068636X0200Y         S0      
317GND              VIA   -    MD0100PA00X+051881Y+066587X0200Y    R180 S0      
317GND              VIA   -    MD0100PA00X+051022Y+062795X0200Y         S0      
327GND              PU73  -3          A01X+051022Y+062482X0100Y0320R180 S1      
317GND              VIA   -    MD0100PA00X+051240Y+062936X0200Y         S0      
327GND              PU73  -2          A01X+051218Y+062482X0100Y0320R180 S1      
317GND              VIA   -    M      A01X+052360Y+062824X0200Y    R270 S2      
017GND              VIA   -    M      A18X+052360Y+062824X0260Y    R270 S2      
017GND                    -    MD0100PA00X+052360Y+062824                       
327GND              PC619 -2   M      A01X+052107Y+062824X0198Y0197R090 S1      
317GND              VIA   -    MD0100PA00X+051988Y+060831X0200Y    R270 S0      
327GND              PC620 -2          A01X+051735Y+060831X0198Y0197     S1      
317GND              VIA   -    MD0100PA00X+052149Y+057298X0200Y    R090 S0      
327GND              C888  -2          A01X+052149Y+057576X0198Y0197R270 S1      
317GND              VIA   -    MD0100PA00X+052158Y+052745X0200Y    R180 S0      
317GND              VIA   -    MD0100PA00X+051732Y+052430X0200Y    R270 S0      
317GND              VIA   -    MD0100PA00X+051878Y+052745X0200Y    R180 S0      
317GND              VIA   -    MD0100PA00X+051363Y+053138X0200Y    R270 S0      
317GND              VIA   -    M      A01X+051363Y+052858X0200Y    R270 S2      
017GND              VIA   -    M      A18X+051363Y+052858X0260Y    R270 S2      
017GND                    -    MD0100PA00X+051363Y+052858                       
317GND              VIA   -    MD0100PA00X+051884Y+051698X0200Y         S0      
317GND              VIA   -    MD0100PA00X+052134Y+051698X0200Y         S0      
317GND              VIA   -    MD0100PA00X+051634Y+051698X0200Y         S0      
317GND              VIA   -    MD0100PA00X+051732Y+052180X0200Y    R270 S0      
317GND              VIA   -    MD0100PA00X+051676Y+050009X0200Y    R180 S0      
317GND              VIA   -    MD0100PA00X+051914Y+050470X0200Y         S0      
317GND              VIA   -    MD0100PA00X+051664Y+050470X0200Y         S0      
317GND              VIA   -    MD0100PA00X+052164Y+050470X0200Y         S0      
317GND              VIA   -    MD0100PA00X+052191Y+073858X0200Y         S0      
317GND              VIA   -    MD0100PA00X+051695Y+073858X0200Y         S0      
317GND              VIA   -    MD0100PA00X+051250Y+073854X0200Y         S0      
317GND              VIA   -    MD0100PA00X+050824Y+072358X0200Y         S0      
327GND              R1122 -1          A18X+050979Y+072049X0198Y0197R090 S2      
317GND              VIA   -    MD0100PA00X+051853Y+070358X0200Y         S0      
317GND              VIA   -    MD0100PA00X+052471Y+057284X0200Y    R090 S0      
317GND              VIA   -    MD0100PA00X+053044Y+051954X0200Y         S0      
317GND              VIA   -    MD0100PA00X+052544Y+051954X0200Y         S0      
317GND              VIA   -    MD0100PA00X+052794Y+051954X0200Y         S0      
317GND              VIA   -    MD0100PA00X+052529Y+052993X0200Y    R270 S0      
317GND              VIA   -    MD0100PA00X+052529Y+052713X0200Y    R270 S0      
317GND              VIA   -    MD0100PA00X+052529Y+052463X0200Y    R270 S0      
317GND              VIA   -    MD0100PA00X+052529Y+052213X0200Y    R270 S0      
317GND              VIA   -    MD0100PA00X+053294Y+051954X0200Y         S0      
317GND              VIA   -    MD0100PA00X+053228Y+076274X0200Y         S0      
317GND              VIA   -    M      A01X+054228Y+076078X0200Y    R270 S2      
017GND              VIA   -    M      A18X+054228Y+076078X0260Y    R270 S2      
017GND                    -    MD0100PA00X+054228Y+076078                       
317GND              VIA   -    MD0100PA00X+053245Y+076747X0200Y         S0      
317GND              VIA   -    MD0100PA00X+052681Y+073910X0200Y         S0      
317GND              VIA   -    MD0100PA00X+053176Y+073910X0200Y         S0      
317GND              VIA   -    MD0100PA00X+053481Y+073410X0200Y         S0      
317GND              VIA   -    MD0100PA00X+053976Y+073410X0200Y         S0      
317GND              VIA   -    MD0100PA00X+052628Y+072134X0200Y         S0      
317GND              VIA   -    MD0100PA00X+053263Y+072078X0200Y         S0      
317GND              VIA   -    MD0100PA00X+052693Y+070382X0200Y         S0      
317GND              VIA   -    MD0100PA00X+053539Y+071262X0200Y         S0      
327GND              C2659 -2          A18X+053635Y+070871X0198Y0197R180 S2      
317GND              VIA   -    MD0100PA00X+052696Y+069496X0200Y         S0      
327GND              U114  -TH  M      A01X+052252Y+069941X1102Y1102     S1      
317GND              VIA   -    MD0100PA00X+053911Y+068146X0200Y         S0      
327GND              C2657 -2          A18X+054208Y+068146X0280Y0320R180 S2      
317GND              VIA   -    MD0100PA00X+053494Y+068449X0200Y         S0      
327GND              C2658 -2          A18X+053225Y+068422X0198Y0197R090 S2      
317GND              VIA   -    MD0100PA00X+053080Y+066139X0200Y    R180 S0      
317GND              VIA   -    MD0100PA00X+052494Y+066139X0200Y    R180 S0      
317GND              VIA   -    MD0100PA00X+053844Y+066405X0200Y    R180 S0      
317GND              VIA   -    MD0100PA00X+053349Y+066405X0200Y    R180 S0      
317GND              VIA   -    MD0100PA00X+052465Y+064360X0200Y         S0      
317GND              VIA   -    MD0100PA00X+052676Y+063880X0200Y         S0      
317GND              VIA   -    MD0100PA00X+053883Y+063905X0200Y         S0      
317GND              VIA   -    MD0100PA00X+053883Y+063625X0200Y         S0      
317GND              VIA   -    MD0100PA00X+052676Y+063320X0200Y         S0      
317GND              VIA   -    MD0100PA00X+052676Y+063600X0200Y         S0      
317GND              VIA   -    MD0100PA00X+053883Y+063345X0200Y         S0      
317GND              VIA   -    MD0100PA00X+053277Y+060544X0200Y    R090 S0      
327GND              R708  -2          A01X+053277Y+060280X0198Y0197R090 S1      
317GND              VIA   -    MD0100PA00X+052831Y+059014X0200Y    R090 S0      
317GND              VIA   -    MD0100PA00X+053291Y+059019X0200Y    R090 S0      
317GND              VIA   -    MD0100PA00X+052882Y+057948X0200Y    R090 S0      
327GND              U81   -10         A01X+052960Y+058234X0090Y0240R180 S1      
317GND              VIA   -    MD0100PA00X+052827Y+058551X0200Y    R090 S0      
317GND              VIA   -    MD0100PA00X+053286Y+058551X0200Y    R090 S0      
327GND              U81   -TH  M      A01X+053058Y+058785X0670Y0670R270 S1      
317GND              VIA   -    MD0100PA00X+055219Y+076658X0200Y         S0      
317GND              VIA   -    MD0100PA00X+055238Y+076289X0200Y         S0      
317GND              VIA   -    MD0100PA00X+055657Y+072099X0200Y         S0      
317GND              VIA   -    MD0100PA00X+055657Y+070499X0200Y         S0      
317GND              VIA   -    MD0100PA00X+055657Y+071603X0200Y         S0      
317GND              VIA   -    MD0100PA00X+055657Y+068899X0200Y         S0      
317GND              VIA   -    MD0100PA00X+055657Y+070003X0200Y         S0      
317GND              VIA   -    MD0100PA00X+055657Y+068403X0200Y         S0      
317GND              VIA   -    MD0100PA00X+055027Y+065868X0200Y         S0      
317GND              VIA   -    MD0100PA00X+054077Y+060544X0200Y    R090 S0      
327GND              R707  -2          A01X+054077Y+060280X0198Y0197R090 S1      
317GND              VIA   -    MD0100PA00X+056428Y+077670X0200Y         S0      
317GND              VIA   -    MD0100PA00X+057070Y+076705X0200Y         S0      
317GND              VIA   -    MD0100PA00X+055962Y+073961X0200Y         S0      
317GND              VIA   -    MD0100PA00X+056189Y+072814X0200Y         S0      
317GND              VIA   -    MD0100PA00X+055907Y+070803X0200Y         S0      
317GND              VIA   -    MD0100PA00X+055907Y+071299X0200Y         S0      
317GND              VIA   -    MD0100PA00X+055907Y+069203X0200Y         S0      
317GND              VIA   -    MD0100PA00X+055907Y+069699X0200Y         S0      
317GND              VIA   -    MD0100PA00X+057462Y+077272X0200Y         S0      
317GND              VIA   -    MD0100PA00X+057380Y+072830X0200Y         S0      
317GND              VIA   -    MD0100PA00X+060498Y+060759X0200Y         S0      
317GND              VIA   -    M      A01X+060501Y+061560X0200Y         S2      
017GND              VIA   -    M      A18X+060501Y+061560X0260Y         S2      
017GND                    -    MD0100PA00X+060501Y+061560                       
317GND              VIA   -    MD0100PA00X+060498Y+059610X0200Y         S0      
317GND              VIA   -    MD0100PA00X+060270Y+059467X0200Y         S0      
317GND              VIA   -    MD0100PA00X+060418Y+059235X0200Y         S0      
317GND              VIA   -    MD0100PA00X+060424Y+058956X0200Y         S0      
317GND              VIA   -    MD0100PA00X+060498Y+059959X0200Y         S0      
317GND              VIA   -    MD0100PA00X+060276Y+059758X0200Y         S0      
317GND              VIA   -    MD0100PA00X+059779Y+053638X0200Y         S0      
327GND              C889  -2          A01X+060005Y+053878X0198Y0197R270 S1      
327GND              C883  -2          A01X+059606Y+053882X0198Y0197R270 S1      
317GND              VIA   -    MD0100PA00X+059787Y+052692X0200Y    R090 S0      
317GND              VIA   -    MD0100PA00X+060328Y+053403X0200Y    R270 S0      
317GND              VIA   -    MD0100PA00X+060328Y+053898X0200Y    R270 S0      
317GND              VIA   -    MD0100PA00X+060328Y+052481X0200Y    R270 S0      
317GND              VIA   -    MD0100PA00X+059288Y+053187X0200Y    R270 S0      
317GND              VIA   -    MD0100PA00X+059787Y+053187X0200Y    R090 S0      
317GND              VIA   -    MD0100PA00X+059288Y+052692X0200Y    R270 S0      
317GND              VIA   -    MD0100PA00X+059288Y+051274X0200Y         S0      
317GND              VIA   -    MD0100PA00X+059787Y+051274X0200Y         S0      
317GND              VIA   -    MD0100PA00X+060328Y+051986X0200Y    R270 S0      
317GND              VIA   -    MD0100PA00X+059787Y+051770X0200Y    R090 S0      
317GND              VIA   -    MD0100PA00X+059288Y+051770X0200Y    R270 S0      
317GND              VIA   -    MD0100PA00X+060328Y+049485X0200Y    R270 S0      
317GND              VIA   -    MD0100PA00X+059787Y+048774X0200Y    R090 S0      
317GND              VIA   -    MD0100PA00X+059288Y+048774X0200Y    R270 S0      
317GND              VIA   -    MD0100PA00X+060328Y+048990X0200Y    R270 S0      
317GND              VIA   -    MD0100PA00X+060827Y+052481X0200Y    R090 S0      
317GND              VIA   -    MD0100PA00X+060827Y+053403X0200Y    R090 S0      
317GND              VIA   -    MD0100PA00X+060827Y+053898X0200Y    R090 S0      
317GND              VIA   -    MD0100PA00X+060827Y+051986X0200Y    R090 S0      
317GND              VIA   -    MD0100PA00X+060827Y+049485X0200Y    R090 S0      
317GND              VIA   -    MD0100PA00X+060827Y+048990X0200Y    R090 S0      
317GND              VIA   -    MD0100PA00X+060947Y+063495X0200Y         S0      
327GND              R124  -2          A01X+060751Y+063797X0198Y0197R180 S1      
327GND              R125  -2          A01X+061066Y+063142X0198Y0197     S1      
317GND              VIA   -    MD0100PA00X+061418Y+056200X0200Y         S0      
327GND              R132  -2          A01X+061138Y+056257X0198Y0197     S1      
317GND              VIA   -    MD0100PA00X+061446Y+055523X0200Y         S0      
327GND              R134  -2          A01X+061135Y+055856X0198Y0197     S1      
327GND              R136  -2   M      A01X+061135Y+055456X0198Y0197     S1      
317GND              VIA   -    MD0100PA00X+063420Y+059511X0200Y         S0      
327GND              J22   -OB13       A01X+063836Y+059512X0140Y0480R270 S1      
317GND              VIA   -    MD0100PA00X+063374Y+060220X0200Y         S0      
327GND              J22   -OB10       A01X+063836Y+060220X0140Y0480R270 S1      
317GND              VIA   -    MD0100PA00X+063446Y+054711X0200Y         S0      
327GND              J22   -B13        A01X+063836Y+054711X0140Y0480R270 S1      
317GND              VIA   -    MD0100PA00X+063446Y+054002X0200Y         S0      
317GND              VIA   -    MD0100PA00X+063446Y+053293X0200Y         S0      
327GND              J22   -B19        A01X+063836Y+053293X0140Y0480R270 S1      
317GND              VIA   -    MD0100PA00X+063446Y+052585X0200Y         S0      
317GND              VIA   -    MD0100PA00X+063446Y+051876X0200Y         S0      
317GND              VIA   -    MD0100PA00X+063446Y+051167X0200Y         S0      
317GND              VIA   -    MD0100PA00X+063446Y+049589X0200Y         S0      
317GND              VIA   -    MD0100PA00X+063446Y+048880X0200Y         S0      
327GND              J22   -B32        A01X+063836Y+048880X0140Y0480R270 S1      
327GND              J22   -B49        A01X+063836Y+043167X0140Y0480R270 S1      
327GND              J22   -B46        A01X+063836Y+043876X0140Y0480R270 S1      
327GND              J22   -B55        A01X+063836Y+041750X0140Y0480R270 S1      
317GND              VIA   -    MD0100PA00X+065096Y+067784X0200Y         S0      
327GND              U21   -3          A01X+065096Y+068201X0220Y0530R180 S1      
317GND              VIA   -    MD0100PA00X+064835Y+064547X0200Y         S0      
317GND              VIA   -    MD0100PA00X+064736Y+065316X0200Y         S0      
327GND              U20   -3          A01X+064393Y+065316X0160Y0360R270 S1      
317GND              VIA   -    MD0100PA00X+064821Y+061440X0200Y    R180 S0      
327GND              R130  -2          A18X+065061Y+061440X0198Y0197     S2      
317GND              VIA   -    MD0100PA00X+064821Y+060640X0200Y    R180 S0      
327GND              R123  -2          A18X+065061Y+060640X0198Y0197     S2      
317GND              VIA   -    MD0100PA00X+064821Y+059440X0200Y    R180 S0      
327GND              R122  -2          A18X+065061Y+059440X0198Y0197     S2      
317GND              VIA   -    MD0100PA00X+064821Y+059840X0200Y    R180 S0      
327GND              R120  -2          A18X+065061Y+059840X0198Y0197     S2      
317GND              VIA   -    MD0100PA00X+064821Y+060240X0200Y    R180 S0      
327GND              R121  -2          A18X+065061Y+060240X0198Y0197     S2      
317GND              VIA   -    MD0100PA00X+064273Y+057410X0200Y         S0      
317GND              VIA   -    MD0100PA00X+064395Y+056068X0200Y         S0      
317GND              VIA   -    MD0100PA00X+064218Y+056244X0200Y         S0      
317GND              VIA   -    MD0100PA00X+064449Y+057233X0200Y         S0      
317GND              VIA   -    MD0100PA00X+064274Y+055287X0200Y         S0      
317GND              VIA   -    MD0100PA00X+064286Y+055012X0200Y         S0      
317GND              VIA   -    MD0100PA00X+064226Y+052585X0200Y    R180 S0      
327GND              J22   -B22 M      A01X+063836Y+052585X0140Y0480R270 S1      
317GND              VIA   -    MD0100PA00X+064226Y+051167X0200Y    R180 S0      
327GND              J22   -B28 M      A01X+063836Y+051167X0140Y0480R270 S1      
317GND              VIA   -    MD0100PA00X+064226Y+051876X0200Y    R180 S0      
327GND              J22   -B25 M      A01X+063836Y+051876X0140Y0480R270 S1      
317GND              VIA   -    MD0100PA00X+065117Y+051056X0200Y         S0      
317GND              VIA   -    MD0100PA00X+064792Y+051684X0200Y         S0      
317GND              VIA   -    MD0100PA00X+065257Y+049589X0200Y         S0      
317GND              VIA   -    MD0100PA00X+064447Y+049883X0200Y    R180 S0      
327GND              J22   -B29 M      A01X+063836Y+049589X0140Y0480R270 S1      
327GND              J22   -B35 M      A01X+063836Y+048171X0140Y0480R270 S1      
317GND              VIA   -    MD0100PA00X+065204Y+048771X0200Y         S0      
327GND              J22   -B41 M      A01X+063836Y+046754X0140Y0480R270 S1      
327GND              J22   -B38 M      A01X+063836Y+047463X0140Y0480R270 S1      
327GND              J22   -B43 M      A01X+063836Y+044585X0140Y0480R270 S1      
327GND              J22   -B58 M      A01X+063836Y+041041X0140Y0480R270 S1      
327GND              J22   -B52 M      A01X+063836Y+042459X0140Y0480R270 S1      
327GND              J22   -B64 M      A01X+063836Y+039624X0140Y0480R270 S1      
327GND              J22   -B61 M      A01X+063836Y+040333X0140Y0480R270 S1      
327GND              J22   -B67 M      A01X+063836Y+038915X0140Y0480R270 S1      
327GND              J22   -A41 M      A01X+065647Y+046754X0140Y0480R270 S1      
327GND              J22   -A38 M      A01X+065647Y+047463X0140Y0480R270 S1      
327GND              J22   -A43 M      A01X+065647Y+044585X0140Y0480R270 S1      
327GND              J22   -A49 M      A01X+065647Y+043167X0140Y0480R270 S1      
327GND              J22   -A46 M      A01X+065647Y+043876X0140Y0480R270 S1      
327GND              J22   -A55 M      A01X+065647Y+041750X0140Y0480R270 S1      
327GND              J22   -A52 M      A01X+065647Y+042459X0140Y0480R270 S1      
327GND              J22   -A61        A01X+065647Y+040333X0140Y0480R270 S1      
327GND              J22   -A58        A01X+065647Y+041041X0140Y0480R270 S1      
327GND              J22   -A64 M      A01X+065647Y+039624X0140Y0480R270 S1      
327GND              J22   -A67 M      A01X+065647Y+038915X0140Y0480R270 S1      
317GND              VIA   -    MD0100PA00X+066177Y+070504X0200Y         S0      
327GND              Q3    -1          A01X+066177Y+070228X0170Y0240R180 S1      
317GND              VIA   -    MD0100PA00X+065616Y+069185X0200Y         S0      
327GND              Q3    -4          A01X+065665Y+069480X0170Y0240R180 S1      
317GND              VIA   -    MD0100PA00X+066178Y+066298X0200Y         S0      
327GND              C415  -2          A01X+066112Y+066040X0198Y0197     S1      
317GND              VIA   -    MD0100PA00X+065575Y+066888X0200Y         S0      
327GND              C886  -2          A01X+065575Y+066628X0198Y0197R180 S1      
317GND              VIA   -    MD0100PA00X+066037Y+059512X0200Y    R180 S0      
327GND              J22   -OA13       A01X+065647Y+059512X0140Y0480R270 S1      
317GND              VIA   -    MD0100PA00X+066037Y+060220X0200Y    R180 S0      
327GND              J22   -OA10       A01X+065647Y+060220X0140Y0480R270 S1      
317GND              VIA   -    MD0100PA00X+066083Y+057291X0200Y    R090 S0      
317GND              VIA   -    MD0100PA00X+066083Y+057541X0200Y    R090 S0      
317GND              VIA   -    MD0100PA00X+066955Y+056050X0200Y         S0      
327GND              U18   -3          A18X+066955Y+055780X0240Y0240R180 S2      
317GND              VIA   -    MD0100PA00X+066083Y+056541X0200Y    R090 S0      
317GND              VIA   -    MD0100PA00X+066083Y+056791X0200Y    R090 S0      
317GND              VIA   -    MD0100PA00X+066083Y+057041X0200Y    R090 S0      
327GND              J22   -A13        A01X+065647Y+054711X0140Y0480R270 S1      
317GND              VIA   -    MD0100PA00X+066037Y+054711X0200Y    R180 S0      
327GND              R126  -2          A18X+065805Y+054497X0198Y0197R180 S2      
317GND              VIA   -    MD0100PA00X+066037Y+055419X0200Y    R180 S0      
327GND              J22   -A10        A01X+065647Y+055419X0140Y0480R270 S1      
327GND              J22   -A16        A01X+065647Y+054002X0140Y0480R270 S1      
317GND              VIA   -    MD0100PA00X+066037Y+054002X0200Y    R180 S0      
317GND              VIA   -    MD0100PA00X+066037Y+053293X0200Y    R180 S0      
327GND              J22   -A19        A01X+065647Y+053293X0140Y0480R270 S1      
317GND              VIA   -    MD0100PA00X+066037Y+052585X0200Y    R180 S0      
327GND              J22   -A22        A01X+065647Y+052585X0140Y0480R270 S1      
317GND              VIA   -    MD0100PA00X+066767Y+052585X0200Y         S0      
317GND              VIA   -    MD0100PA00X+066517Y+052585X0200Y         S0      
317GND              VIA   -    MD0100PA00X+066517Y+054002X0200Y         S0      
317GND              VIA   -    MD0100PA00X+066517Y+053293X0200Y         S0      
317GND              VIA   -    MD0100PA00X+066767Y+053293X0200Y         S0      
317GND              VIA   -    MD0100PA00X+066037Y+051876X0200Y    R180 S0      
327GND              J22   -A25 M      A01X+065647Y+051876X0140Y0480R270 S1      
317GND              VIA   -    MD0100PA00X+066037Y+051167X0200Y    R180 S0      
327GND              J22   -A28 M      A01X+065647Y+051167X0140Y0480R270 S1      
317GND              VIA   -    MD0100PA00X+066767Y+051167X0200Y         S0      
317GND              VIA   -    MD0100PA00X+066517Y+051876X0200Y         S0      
317GND              VIA   -    MD0100PA00X+066767Y+051876X0200Y         S0      
317GND              VIA   -    MD0100PA00X+066037Y+049589X0200Y    R180 S0      
327GND              J22   -A29 M      A01X+065647Y+049589X0140Y0480R270 S1      
317GND              VIA   -    MD0100PA00X+066517Y+049589X0200Y         S0      
317GND              VIA   -    MD0100PA00X+066767Y+048880X0200Y         S0      
317GND              VIA   -    MD0100PA00X+066517Y+048880X0200Y         S0      
327GND              J22   -A35 M      A01X+065647Y+048171X0140Y0480R270 S1      
317GND              VIA   -    MD0100PA00X+066037Y+048880X0200Y    R180 S0      
327GND              J22   -A32 M      A01X+065647Y+048880X0140Y0480R270 S1      
317GND              VIA   -    MD0100PA00X+068101Y+054392X0200Y         S0      
327GND              C901  -2          A18X+067759Y+054392X0198Y0197R090 S2      
317GND              VIA   -    MD0100PA00X+068159Y+055500X0200Y         S0      
327GND              R140  -2          A01X+068411Y+055370X0198Y0197R180 S1      
317GND              VIA   -    MD0100PA00X+067247Y+053293X0200Y         S0      
317GND              VIA   -    MD0100PA00X+067247Y+052585X0200Y         S0      
317GND              VIA   -    MD0100PA00X+067247Y+051167X0200Y         S0      
317GND              VIA   -    MD0100PA00X+067247Y+051876X0200Y         S0      
317GND              VIA   -    MD0100PA00X+067247Y+048880X0200Y         S0      
317GND              VIA   -    MD0100PA00X+070268Y+077116X0200Y         S0      
327GND              R1034 -1          A18X+070008Y+077116X0198Y0197     S2      
317GND              VIA   -    MD0100PA00X+070269Y+075347X0200Y         S0      
327GND              R1036 -1          A18X+070009Y+075347X0198Y0197     S2      
317GND              VIA   -    MD0100PA00X+070269Y+076647X0200Y         S0      
327GND              R1035 -1          A18X+070009Y+076647X0198Y0197     S2      
317GND              VIA   -    MD0100PA00X+069894Y+067846X0200Y         S0      
327GND              C882  -2          A01X+069894Y+067583X0198Y0197R180 S1      
317GND              VIA   -    MD0100PA00X+070016Y+063684X0200Y         S0      
327GND              Q120  -1          A01X+070016Y+063379X0240Y0240     S1      
317GND              VIA   -    MD0100PA00X+070445Y+076061X0200Y    R090 S0      
327GND              U50   -10         A01X+070919Y+076214X0140Y0630R270 S1      
317GND              VIA   -    MD0100PA00X+070367Y+066514X0200Y         S0      
327GND              U22   -3          A01X+070367Y+066111X0400Y0500R180 S1      
317GND              VIA   -    MD0100PA00X+071666Y+064643X0200Y         S0      
317GND              VIA   -    MD0100PA00X+070607Y+063812X0200Y         S0      
327GND              Q120  -4          A01X+070607Y+064087X0240Y0240     S1      
317GND              VIA   -    MD0100PA00X+071139Y+061636X0200Y         S0      
317GND              VIA   -    MD0100PA00X+071619Y+061636X0200Y         S0      
317GND              VIA   -    MD0100PA00X+071869Y+060927X0200Y         S0      
317GND              VIA   -    MD0100PA00X+071619Y+060927X0200Y         S0      
317GND              VIA   -    MD0100PA00X+071139Y+060927X0200Y         S0      
317GND              VIA   -    MD0100PA00X+071619Y+059510X0200Y         S0      
317GND              VIA   -    MD0100PA00X+071139Y+059510X0200Y         S0      
317GND              VIA   -    MD0100PA00X+071869Y+059510X0200Y         S0      
317GND              VIA   -    MD0100PA00X+071869Y+060218X0200Y         S0      
317GND              VIA   -    MD0100PA00X+071139Y+060219X0200Y         S0      
317GND              VIA   -    MD0100PA00X+071619Y+060219X0200Y         S0      
317GND              VIA   -    MD0100PA00X+071139Y+058093X0200Y         S0      
317GND              VIA   -    MD0100PA00X+071619Y+058093X0200Y         S0      
317GND              VIA   -    MD0100PA00X+071869Y+058093X0200Y         S0      
317GND              VIA   -    MD0100PA00X+071619Y+058801X0200Y         S0      
317GND              VIA   -    MD0100PA00X+071869Y+058801X0200Y         S0      
317GND              VIA   -    MD0100PA00X+071139Y+058801X0200Y         S0      
317GND              VIA   -    MD0100PA00X+071619Y+057384X0200Y         S0      
317GND              VIA   -    MD0100PA00X+071869Y+057384X0200Y         S0      
317GND              VIA   -    MD0100PA00X+071139Y+057384X0200Y         S0      
317GND              VIA   -    MD0100PA00X+071619Y+056675X0200Y         S0      
317GND              VIA   -    MD0100PA00X+071869Y+056675X0200Y         S0      
317GND              VIA   -    MD0100PA00X+071869Y+055966X0200Y         S0      
317GND              VIA   -    MD0100PA00X+071139Y+056675X0200Y         S0      
317GND              VIA   -    MD0100PA00X+071139Y+053797X0200Y         S0      
317GND              VIA   -    MD0100PA00X+071139Y+053089X0200Y         S0      
317GND              VIA   -    MD0100PA00X+071619Y+053797X0200Y         S0      
317GND              VIA   -    MD0100PA00X+071619Y+053089X0200Y         S0      
317GND              VIA   -    MD0100PA00X+071869Y+053089X0200Y         S0      
317GND              VIA   -    MD0100PA00X+071869Y+051671X0200Y         S0      
317GND              VIA   -    MD0100PA00X+071139Y+051671X0200Y         S0      
317GND              VIA   -    MD0100PA00X+071139Y+052380X0200Y         S0      
317GND              VIA   -    MD0100PA00X+071869Y+052380X0200Y         S0      
317GND              VIA   -    MD0100PA00X+071619Y+052380X0200Y         S0      
317GND              VIA   -    MD0100PA00X+071619Y+051671X0200Y         S0      
317GND              VIA   -    MD0100PA00X+071619Y+049384X0200Y         S0      
317GND              VIA   -    MD0100PA00X+071139Y+049384X0200Y         S0      
317GND              VIA   -    MD0100PA00X+072349Y+060218X0200Y         S0      
327GND              J23   -A61        A01X+072739Y+060218X0140Y0480R090 S1      
317GND              VIA   -    MD0100PA00X+073132Y+057434X0200Y    R180 S0      
317GND              VIA   -    MD0100PA00X+072349Y+058093X0200Y         S0      
327GND              J23   -A52        A01X+072739Y+058092X0140Y0480R090 S1      
317GND              VIA   -    MD0100PA00X+072349Y+058801X0200Y         S0      
327GND              J23   -A55        A01X+072739Y+058801X0140Y0480R090 S1      
317GND              VIA   -    MD0100PA00X+072349Y+057384X0200Y         S0      
327GND              J23   -A49 M      A01X+072739Y+057384X0140Y0480R090 S1      
317GND              VIA   -    MD0100PA00X+073167Y+056557X0200Y    R180 S0      
317GND              VIA   -    MD0100PA00X+073129Y+055966X0200Y    R180 S0      
317GND              VIA   -    MD0100PA00X+072349Y+055966X0200Y         S0      
327GND              J23   -A43 M      A01X+072739Y+055966X0140Y0480R090 S1      
317GND              VIA   -    MD0100PA00X+072349Y+056675X0200Y         S0      
327GND              J23   -A46 M      A01X+072739Y+056675X0140Y0480R090 S1      
317GND              VIA   -    MD0100PA00X+073239Y+053568X0200Y    R180 S0      
317GND              VIA   -    MD0100PA00X+073255Y+052914X0200Y    R180 S0      
317GND              VIA   -    MD0100PA00X+072349Y+053797X0200Y         S0      
327GND              J23   -A41 M      A01X+072739Y+053797X0140Y0480R090 S1      
317GND              VIA   -    MD0100PA00X+072349Y+053089X0200Y         S0      
327GND              J23   -A38 M      A01X+072739Y+053089X0140Y0480R090 S1      
317GND              VIA   -    MD0100PA00X+073129Y+050963X0200Y    R180 S0      
317GND              VIA   -    MD0100PA00X+073191Y+052213X0200Y    R180 S0      
317GND              VIA   -    MD0100PA00X+073198Y+051461X0200Y    R180 S0      
317GND              VIA   -    MD0100PA00X+072349Y+050963X0200Y         S0      
327GND              J23   -A29 M      A01X+072739Y+050963X0140Y0480R090 S1      
317GND              VIA   -    MD0100PA00X+072349Y+051671X0200Y         S0      
327GND              J23   -A32 M      A01X+072739Y+051671X0140Y0480R090 S1      
327GND              J23   -A35 M      A01X+072739Y+052380X0140Y0480R090 S1      
317GND              VIA   -    MD0100PA00X+072349Y+052380X0200Y         S0      
317GND              VIA   -    MD0100PA00X+073125Y+049509X0200Y    R180 S0      
317GND              VIA   -    MD0100PA00X+072349Y+049384X0200Y         S0      
327GND              J23   -A28 M      A01X+072739Y+049384X0140Y0480R090 S1      
317GND              VIA   -    MD0100PA00X+073143Y+048944X0200Y    R180 S0      
327GND              J23   -A22 M      A01X+072739Y+047966X0140Y0480R090 S1      
327GND              J23   -A25 M      A01X+072739Y+048675X0140Y0480R090 S1      
327GND              J23   -A16 M      A01X+072739Y+046549X0140Y0480R090 S1      
327GND              J23   -A19 M      A01X+072739Y+047258X0140Y0480R090 S1      
327GND              J23   -A13        A01X+072739Y+045841X0140Y0480R090 S1      
327GND              J23   -A10        A01X+072739Y+045132X0140Y0480R090 S1      
327GND              J23   -OA13       A01X+072739Y+041039X0140Y0480R090 S1      
327GND              J23   -OA10       A01X+072739Y+040331X0140Y0480R090 S1      
317GND              VIA   -    MD0100PA00X+072122Y+074213X0200Y    R090 S0      
327GND              C2093 -1          A01X+072381Y+074213X0198Y0197R270 S1      
317GND              VIA   -    MD0100PA00X+073482Y+064643X0200Y         S0      
317GND              VIA   -    MD0100PA00X+073142Y+061636X0200Y    R180 S0      
317GND              VIA   -    MD0100PA00X+072349Y+061636X0200Y         S0      
327GND              J23   -A67 M      A01X+072739Y+061636X0140Y0480R090 S1      
317GND              VIA   -    MD0100PA00X+072349Y+060927X0200Y         S0      
327GND              J23   -A64        A01X+072739Y+060927X0140Y0480R090 S1      
317GND              VIA   -    MD0100PA00X+072349Y+059510X0200Y         S0      
327GND              J23   -A58        A01X+072739Y+059510X0140Y0480R090 S1      
317GND              VIA   -    MD0100PA00X+074046Y+053276X0200Y         S0      
317GND              VIA   -    MD0100PA00X+074054Y+052548X0200Y         S0      
317GND              VIA   -    MD0100PA00X+073806Y+053797X0200Y         S0      
317GND              VIA   -    MD0100PA00X+074940Y+053089X0200Y    R180 S0      
327GND              J23   -B38 M      A01X+074550Y+053089X0140Y0480R090 S1      
317GND              VIA   -    MD0100PA00X+074940Y+053797X0200Y    R180 S0      
327GND              J23   -B41 M      A01X+074550Y+053797X0140Y0480R090 S1      
317GND              VIA   -    MD0100PA00X+074160Y+051671X0200Y         S0      
317GND              VIA   -    MD0100PA00X+074160Y+050963X0200Y         S0      
317GND              VIA   -    MD0100PA00X+074940Y+050963X0200Y    R180 S0      
327GND              J23   -B29 M      A01X+074550Y+050963X0140Y0480R090 S1      
317GND              VIA   -    MD0100PA00X+074940Y+051671X0200Y    R180 S0      
327GND              J23   -B32 M      A01X+074550Y+051671X0140Y0480R090 S1      
327GND              J23   -B35 M      A01X+074550Y+052380X0140Y0480R090 S1      
317GND              VIA   -    MD0100PA00X+074940Y+052380X0200Y    R180 S0      
317GND              VIA   -    MD0100PA00X+074160Y+049384X0200Y         S0      
317GND              VIA   -    MD0100PA00X+074940Y+049384X0200Y    R180 S0      
327GND              J23   -B28 M      A01X+074550Y+049384X0140Y0480R090 S1      
327GND              J23   -B22 M      A01X+074550Y+047966X0140Y0480R090 S1      
327GND              J23   -B25 M      A01X+074550Y+048675X0140Y0480R090 S1      
327GND              J23   -B19 M      A01X+074550Y+047258X0140Y0480R090 S1      
327GND              J23   -B16 M      A01X+074550Y+046549X0140Y0480R090 S1      
327GND              J23   -B13 M      A01X+074550Y+045841X0140Y0480R090 S1      
327GND              J23   -OB13       A01X+074550Y+041039X0140Y0480R090 S1      
327GND              J23   -OB10       A01X+074550Y+040331X0140Y0480R090 S1      
317GND              VIA   -    MD0100PA00X+074167Y+060812X0200Y         S0      
317GND              VIA   -    MD0100PA00X+074940Y+061636X0200Y    R180 S0      
327GND              J23   -B67        A01X+074550Y+061636X0140Y0480R090 S1      
317GND              VIA   -    MD0100PA00X+074940Y+060927X0200Y    R180 S0      
327GND              J23   -B64 M      A01X+074550Y+060927X0140Y0480R090 S1      
317GND              VIA   -    MD0100PA00X+074940Y+059510X0200Y    R180 S0      
327GND              J23   -B58        A01X+074550Y+059510X0140Y0480R090 S1      
317GND              VIA   -    MD0100PA00X+074940Y+060218X0200Y    R180 S0      
327GND              J23   -B61        A01X+074550Y+060218X0140Y0480R090 S1      
317GND              VIA   -    MD0100PA00X+074160Y+057384X0200Y         S0      
317GND              VIA   -    MD0100PA00X+074145Y+057998X0200Y         S0      
317GND              VIA   -    MD0100PA00X+074940Y+058092X0200Y    R180 S0      
327GND              J23   -B52 M      A01X+074550Y+058092X0140Y0480R090 S1      
317GND              VIA   -    MD0100PA00X+074940Y+058801X0200Y    R180 S0      
327GND              J23   -B55        A01X+074550Y+058801X0140Y0480R090 S1      
317GND              VIA   -    MD0100PA00X+074940Y+057384X0200Y    R180 S0      
327GND              J23   -B49 M      A01X+074550Y+057384X0140Y0480R090 S1      
317GND              VIA   -    MD0100PA00X+074160Y+056675X0200Y         S0      
317GND              VIA   -    MD0100PA00X+074160Y+055966X0200Y         S0      
317GND              VIA   -    MD0100PA00X+074940Y+056675X0200Y    R180 S0      
327GND              J23   -B46 M      A01X+074550Y+056675X0140Y0480R090 S1      
317GND              VIA   -    MD0100PA00X+074940Y+055966X0200Y    R180 S0      
327GND              J23   -B43 M      A01X+074550Y+055966X0140Y0480R090 S1      
317GND              VIA   -    MD0100PA00X+077558Y+056566X0200Y    R270 S0      
317GND              VIA   -    MD0100PA00X+077558Y+056070X0200Y    R270 S0      
317GND              VIA   -    MD0100PA00X+078058Y+056566X0200Y    R090 S0      
317GND              VIA   -    MD0100PA00X+078058Y+056070X0200Y    R090 S0      
317GND              VIA   -    MD0100PA00X+077558Y+052979X0200Y    R270 S0      
317GND              VIA   -    MD0100PA00X+077558Y+052484X0200Y    R270 S0      
317GND              VIA   -    MD0100PA00X+078058Y+052979X0200Y    R090 S0      
317GND              VIA   -    MD0100PA00X+078058Y+052484X0200Y    R090 S0      
317GND              VIA   -    MD0100PA00X+077558Y+051066X0200Y    R270 S0      
317GND              VIA   -    MD0100PA00X+078058Y+051562X0200Y    R090 S0      
317GND              VIA   -    MD0100PA00X+077558Y+051562X0200Y    R270 S0      
317GND              VIA   -    MD0100PA00X+078058Y+051066X0200Y    R090 S0      
317GND              VIA   -    MD0100PA00X+078058Y+060818X0200Y    R090 S0      
317GND              VIA   -    MD0100PA00X+077558Y+060818X0200Y    R270 S0      
317GND              VIA   -    MD0100PA00X+078058Y+060322X0200Y    R090 S0      
317GND              VIA   -    MD0100PA00X+077558Y+060322X0200Y    R270 S0      
317GND              VIA   -    MD0100PA00X+077558Y+059400X0200Y    R270 S0      
317GND              VIA   -    MD0100PA00X+078058Y+059400X0200Y    R090 S0      
317GND              VIA   -    MD0100PA00X+078058Y+058905X0200Y    R090 S0      
317GND              VIA   -    MD0100PA00X+077558Y+058905X0200Y    R270 S0      
317GND              VIA   -    MD0100PA00X+078058Y+057487X0200Y    R090 S0      
317GND              VIA   -    MD0100PA00X+077558Y+057487X0200Y    R270 S0      
317GND              VIA   -    MD0100PA00X+078058Y+057983X0200Y    R090 S0      
317GND              VIA   -    MD0100PA00X+077558Y+057983X0200Y    R270 S0      
317GND              VIA   -    MD0100PA00X+078598Y+056781X0200Y    R270 S0      
317GND              VIA   -    MD0100PA00X+079098Y+057277X0200Y    R090 S0      
317GND              VIA   -    MD0100PA00X+078598Y+057277X0200Y    R270 S0      
317GND              VIA   -    MD0100PA00X+079098Y+053690X0200Y    R090 S0      
317GND              VIA   -    MD0100PA00X+079098Y+053195X0200Y    R090 S0      
317GND              VIA   -    MD0100PA00X+078598Y+053690X0200Y    R270 S0      
317GND              VIA   -    MD0100PA00X+078598Y+053195X0200Y    R270 S0      
317GND              VIA   -    MD0100PA00X+078598Y+052273X0200Y    R270 S0      
317GND              VIA   -    MD0100PA00X+078598Y+051777X0200Y    R270 S0      
317GND              VIA   -    MD0100PA00X+079098Y+052273X0200Y    R090 S0      
317GND              VIA   -    MD0100PA00X+079098Y+051777X0200Y    R090 S0      
317GND              VIA   -    MD0100PA00X+079098Y+049277X0200Y    R090 S0      
317GND              VIA   -    MD0100PA00X+078598Y+049277X0200Y    R270 S0      
317GND              VIA   -    MD0100PA00X+079098Y+048781X0200Y    R090 S0      
317GND              VIA   -    MD0100PA00X+078598Y+048781X0200Y    R270 S0      
317GND              VIA   -    MD0100PA00X+078598Y+061033X0200Y    R270 S0      
317GND              VIA   -    MD0100PA00X+078598Y+061529X0200Y    R270 S0      
317GND              VIA   -    MD0100PA00X+079098Y+061033X0200Y    R090 S0      
317GND              VIA   -    MD0100PA00X+079098Y+061529X0200Y    R090 S0      
317GND              VIA   -    MD0100PA00X+079098Y+059616X0200Y    R090 S0      
317GND              VIA   -    MD0100PA00X+078598Y+059616X0200Y    R270 S0      
317GND              VIA   -    MD0100PA00X+078598Y+060112X0200Y    R270 S0      
317GND              VIA   -    MD0100PA00X+079098Y+060112X0200Y    R090 S0      
317GND              VIA   -    MD0100PA00X+078598Y+058694X0200Y    R270 S0      
317GND              VIA   -    MD0100PA00X+078598Y+058199X0200Y    R270 S0      
317GND              VIA   -    MD0100PA00X+079098Y+058694X0200Y    R090 S0      
317GND              VIA   -    MD0100PA00X+079098Y+058199X0200Y    R090 S0      
317GND              VIA   -    MD0100PA00X+079098Y+056781X0200Y    R090 S0      
317GND              VIA   -    MD0100PA00X+078466Y+056484X0200Y    R180 S0      
327GND              C4001 -2          A01X+079937Y+056529X0198Y0197R090 S1      
327GND              U24   -S   M      A01X+078603Y+056004X0400Y0560R180 S1      
317GND              VIA   -    MD0100PA00X+081076Y+048862X0200Y    R090 S0      
317GND              VIA   -    MD0100PA00X+081076Y+049112X0200Y    R090 S0      
317GND              VIA   -    MD0100PA00X+081897Y+048876X0200Y    R090 S0      
317GND              VIA   -    MD0100PA00X+081897Y+049126X0200Y    R090 S0      
317GND              VIA   -    MD0100PA00X+084573Y+066126X0200Y         S0      
317GND              VIA   -    MD0100PA00X+083524Y+053317X0200Y         S0      
317GND              VIA   -    MD0100PA00X+085111Y+065664X0200Y         S0      
317GND              VIA   -    MD0100PA00X+085820Y+064633X0200Y         S0      
317GND              VIA   -    MD0100PA00X+085390Y+062770X0200Y         S0      
317GND              VIA   -    M      A01X+086709Y+058283X0200Y    R180 S2      
017GND              VIA   -    M      A18X+086709Y+058283X0260Y    R180 S2      
017GND                    -    MD0100PA00X+086709Y+058283                       
317GND              VIA   -    M      A01X+086709Y+057070X0200Y    R180 S2      
017GND              VIA   -    M      A18X+086709Y+057070X0260Y    R180 S2      
017GND                    -    MD0100PA00X+086709Y+057070                       
317GND              VIA   -    MD0100PA00X+086147Y+049130X0200Y    R270 S0      
317GND              VIA   -    MD0100PA00X+086709Y+057870X0200Y    R180 S0      
327GND              R4204 -1          A01X+086949Y+057870X0198Y0197     S1      
317GND              VIA   -    MD0100PA00X+086709Y+056670X0200Y    R180 S0      
327GND              R4206 -1          A01X+086949Y+056670X0198Y0197     S1      
317GND              VIA   -    MD0100PA00X+086709Y+056270X0200Y    R180 S0      
327GND              R4210 -1          A01X+086949Y+056270X0198Y0197     S1      
317GND              VIA   -    MD0100PA00X+086709Y+055870X0200Y    R180 S0      
327GND              C2807 -2          A01X+086949Y+055870X0198Y0197R180 S1      
327GND              Q215  -1          A01X+087291Y+048626X0240Y0240R270 S1      
317GND              VIA   -    MD0100PA00X+089445Y+060636X0200Y         S0      
327GND              C2803 -2          A18X+089445Y+060394X0198Y0197R270 S2      
317GND              VIA   -    MD0100PA00X+088795Y+060886X0200Y         S0      
327GND              C2799 -2          A18X+088795Y+060576X0280Y0320     S2      
317GND              VIA   -    MD0100PA00X+089593Y+061814X0200Y    R090 S0      
327GND              R4209 -1          A01X+089593Y+061574X0198Y0197R270 S1      
317GND              VIA   -    MD0100PA00X+089402Y+058825X0200Y    R090 S0      
317GND              VIA   -    MD0100PA00X+089096Y+058832X0200Y    R090 S0      
317GND              VIA   -    MD0100PA00X+089096Y+057979X0200Y    R090 S0      
317GND              VIA   -    MD0100PA00X+088295Y+055736X0200Y         S0      
327GND              C2797 -2          A18X+088295Y+056046X0280Y0320R180 S2      
317GND              VIA   -    MD0100PA00X+089202Y+057018X0200Y    R090 S0      
317GND              VIA   -    MD0100PA00X+089395Y+055036X0200Y         S0      
327GND              C2805 -2          A18X+089495Y+055396X0280Y0320R180 S2      
317GND              VIA   -    MD0100PA00X+089645Y+055086X0200Y         S0      
327GND              C2793 -2          A18X+090005Y+055186X0280Y0320R090 S2      
317GND              VIA   -    MD0100PA00X+088289Y+053612X0200Y         S0      
327GND              Q215  -4          A01X+088000Y+048035X0240Y0240R270 S1      
317GND              VIA   -    MD0100PA00X+090700Y+053071X0200Y         S0      
317GND              VIA   -    MD0100PA00X+089643Y+053409X0200Y    R270 S0      
327GND              R4201 -1          A01X+089643Y+053649X0198Y0197R090 S1      
317GND              VIA   -    MD0100PA00X+090343Y+053409X0200Y    R270 S0      
327GND              R4202 -1          A01X+090343Y+053649X0198Y0197R090 S1      
317GND              VIA   -    MD0100PA00X+090485Y+061904X0200Y         S0      
317GND              VIA   -    MD0100PA00X+089990Y+061904X0200Y         S0      
317GND              VIA   -    MD0100PA00X+091369Y+061912X0200Y         S0      
317GND              VIA   -    MD0100PA00X+090873Y+061912X0200Y         S0      
317GND              VIA   -    MD0100PA00X+090902Y+057439X0200Y    R180 S0      
317GND              VIA   -    MD0100PA00X+090700Y+058827X0200Y    R090 S0      
317GND              VIA   -    MD0100PA00X+090264Y+058830X0200Y    R090 S0      
317GND              VIA   -    MD0100PA00X+090902Y+058677X0200Y         S0      
317GND              VIA   -    MD0100PA00X+089823Y+058832X0200Y    R090 S0      
317GND              VIA   -    MD0100PA00X+090902Y+057839X0200Y    R180 S0      
317GND              VIA   -    MD0100PA00X+089882Y+057018X0200Y    R090 S0      
317GND              VIA   -    MD0100PA00X+090852Y+057018X0200Y    R090 S0      
317GND              VIA   -    MD0100PA00X+090439Y+057018X0200Y    R090 S0      
327GND              U117  -C1  M      A01X+089999Y+057929X2008Y2008R090 S1      
317GND              VIA   -    MD0100PA00X+091385Y+056149X0200Y    R090 S0      
327GND              U117  -A14 M      A01X+091278Y+056404X0070Y0220R180 S1      
317GND              VIA   -    MD0100PA00X+089816Y+055481X0200Y         S0      
317GND              VIA   -    MD0100PA00X+090936Y+055561X0200Y         S0      
317GND              VIA   -    MD0100PA00X+091058Y+055019X0200Y         S0      
317GND              VIA   -    MD0100PA00X+091163Y+054400X0200Y         S0      
317GND              VIA   -    MD0100PA00X+091595Y+056336X0200Y         S0      
327GND              C2789 -2          A18X+091595Y+056646X0280Y0320R180 S2      
317GND              VIA   -    MD0100PA00X+092096Y+055008X0200Y         S0      
317GND              VIA   -    MD0100PA00X+092460Y+053371X0200Y         S0      
317GND              VIA   -    MD0100PA00X+091519Y+066667X0200Y         S0      
317GND              VIA   -    MD0100PA00X+091571Y+061379X0200Y         S0      
327GND              C2785 -2          A18X+091495Y+060976X0280Y0320     S2      
317GND              VIA   -    MD0100PA00X+094382Y+059122X0200Y         S0      
317GND              VIA   -    MD0100PA00X+094382Y+058122X0200Y         S0      
317GND              VIA   -    MD0100PA00X+093163Y+056558X0200Y         S0      
327GND              R4205 -1          A01X+092923Y+056558X0198Y0197R180 S1      
317GND              VIA   -    MD0100PA00X+093163Y+056158X0200Y         S0      
327GND              R4208 -1          A01X+092923Y+056158X0198Y0197R180 S1      
317GND              VIA   -    MD0100PA00X+093999Y+055273X0200Y    R180 S0      
317GND              VIA   -    MD0100PA00X+093999Y+054073X0200Y    R180 S0      
317GND              VIA   -    MD0100PA00X+093999Y+053673X0200Y    R180 S0      
327GND              PC312 -2          A01X+094257Y+053673X0198Y0197R180 S1      
317GND              VIA   -    MD0100PA00X+093983Y+053110X0200Y    R180 S0      
327GND              C2854 -2          A01X+094257Y+053173X0198Y0197R180 S1      
317GND              VIA   -    MD0100PA00X+094843Y+061109X0200Y         S0      
317GND              VIA   -    MD0100PA00X+094662Y+059122X0200Y         S0      
317GND              VIA   -    MD0100PA00X+094942Y+059122X0200Y         S0      
317GND              VIA   -    MD0100PA00X+094942Y+058122X0200Y         S0      
317GND              VIA   -    MD0100PA00X+094662Y+058122X0200Y         S0      
317GND              VIA   -    MD0100PA00X+095102Y+056319X0200Y         S0      
317GND              VIA   -    MD0100PA00X+095382Y+056319X0200Y         S0      
317GND              VIA   -    MD0100PA00X+095102Y+057119X0200Y         S0      
317GND              VIA   -    MD0100PA00X+095382Y+057119X0200Y         S0      
317GND              VIA   -    MD0100PA00X+095102Y+055519X0200Y         S0      
317GND              VIA   -    MD0100PA00X+095382Y+055519X0200Y         S0      
317GND              VIA   -    MD0100PA00X+094982Y+049998X0200Y    R180 S0      
327GND              PC459 -2          A01X+095240Y+049998X0198Y0197R180 S1      
317GND              VIA   -    MD0100PA00X+094982Y+048798X0200Y    R180 S0      
317GND              VIA   -    MD0100PA00X+095086Y+064182X0200Y    R270 S0      
327GND              PR7033-2   M      A01X+095086Y+063939X0198Y0197R090 S1      
317GND              VIA   -    M      A01X+095636Y+064182X0200Y    R270 S2      
017GND              VIA   -    M      A18X+095636Y+064182X0260Y    R270 S2      
017GND                    -    MD0100PA00X+095636Y+064182                       
327GND              PC811 -2   M      A01X+095636Y+063939X0198Y0197R090 S1      
317GND              VIA   -    MD0100PA00X+096949Y+062936X0200Y         S0      
327GND              PU103 -2          A01X+096927Y+062482X0100Y0320R180 S1      
317GND              VIA   -    MD0100PA00X+096730Y+062795X0200Y         S0      
327GND              PU103 -3          A01X+096730Y+062482X0100Y0320R180 S1      
317GND              VIA   -    M      A01X+098068Y+062824X0200Y    R270 S2      
017GND              VIA   -    M      A18X+098068Y+062824X0260Y    R270 S2      
017GND                    -    MD0100PA00X+098068Y+062824                       
327GND              PC799 -2   M      A01X+097816Y+062824X0198Y0197R090 S1      
317GND              VIA   -    MD0100PA00X+097696Y+060831X0200Y    R270 S0      
327GND              PC803 -2          A01X+097444Y+060831X0198Y0197     S1      
317GND              VIA   -    MD0100PA00X+097858Y+057298X0200Y    R090 S0      
317GND              VIA   -    MD0100PA00X+096401Y+054683X0200Y    R180 S0      
317GND              VIA   -    M      A01X+097587Y+052745X0200Y    R180 S2      
017GND              VIA   -    M      A18X+097587Y+052745X0260Y    R180 S2      
017GND                    -    MD0100PA00X+097587Y+052745                       
317GND              VIA   -    MD0100PA00X+097071Y+052888X0200Y    R270 S0      
317GND              VIA   -    MD0100PA00X+097071Y+053138X0200Y    R270 S0      
317GND              VIA   -    MD0100PA00X+097441Y+052430X0200Y    R270 S0      
317GND              VIA   -    MD0100PA00X+097867Y+052745X0200Y    R180 S0      
317GND              VIA   -    MD0100PA00X+097592Y+051698X0200Y         S0      
317GND              VIA   -    MD0100PA00X+097441Y+052180X0200Y    R270 S0      
317GND              VIA   -    MD0100PA00X+097342Y+051698X0200Y         S0      
317GND              VIA   -    MD0100PA00X+097842Y+051698X0200Y         S0      
317GND              VIA   -    MD0100PA00X+097372Y+050470X0200Y         S0      
317GND              VIA   -    MD0100PA00X+097622Y+050470X0200Y         S0      
317GND              VIA   -    MD0100PA00X+097872Y+050470X0200Y         S0      
317GND              VIA   -    MD0100PA00X+097384Y+050009X0200Y    R180 S0      
317GND              VIA   -    MD0100PA00X+098384Y+063600X0200Y         S0      
317GND              VIA   -    MD0100PA00X+098384Y+063320X0200Y         S0      
317GND              VIA   -    MD0100PA00X+098986Y+060544X0200Y    R090 S0      
327GND              R730  -2          A01X+098986Y+060280X0198Y0197R090 S1      
317GND              VIA   -    MD0100PA00X+099000Y+059019X0200Y    R090 S0      
317GND              VIA   -    MD0100PA00X+098540Y+059014X0200Y    R090 S0      
317GND              VIA   -    MD0100PA00X+098995Y+058551X0200Y    R090 S0      
317GND              VIA   -    MD0100PA00X+098536Y+058551X0200Y    R090 S0      
327GND              U83   -TH  M      A01X+098767Y+058785X0670Y0670R270 S1      
317GND              VIA   -    MD0100PA00X+098590Y+057948X0200Y    R090 S0      
327GND              U83   -10         A01X+098669Y+058234X0090Y0240R180 S1      
317GND              VIA   -    MD0100PA00X+098180Y+057284X0200Y    R090 S0      
317GND              VIA   -    M      A01X+098238Y+052993X0200Y    R270 S2      
017GND              VIA   -    M      A18X+098238Y+052993X0260Y    R270 S2      
017GND                    -    MD0100PA00X+098238Y+052993                       
317GND              VIA   -    MD0100PA00X+098494Y+051953X0200Y         S0      
317GND              VIA   -    MD0100PA00X+098244Y+051953X0200Y         S0      
317GND              VIA   -    MD0100PA00X+098744Y+051953X0200Y         S0      
317GND              VIA   -    MD0100PA00X+098238Y+052463X0200Y    R270 S0      
317GND              VIA   -    MD0100PA00X+098238Y+052713X0200Y    R270 S0      
317GND              VIA   -    MD0100PA00X+098994Y+051953X0200Y         S0      
317GND              VIA   -    MD0100PA00X+098238Y+052213X0200Y    R270 S0      
317GND              VIA   -    MD0100PA00X+098384Y+063880X0200Y         S0      
317GND              VIA   -    MD0100PA00X+099591Y+063905X0200Y         S0      
317GND              VIA   -    MD0100PA00X+099591Y+063625X0200Y         S0      
317GND              VIA   -    MD0100PA00X+099591Y+063345X0200Y         S0      
317GND              VIA   -    MD0100PA00X+099786Y+060544X0200Y    R090 S0      
327GND              R729  -2          A01X+099786Y+060280X0198Y0197R090 S1      
317GND              VIA   -    MD0100PA00X+105496Y+048774X0200Y    R090 S0      
317GND              VIA   -    MD0100PA00X+104997Y+048774X0200Y    R270 S0      
317GND              VIA   -    M      A01X+106210Y+061560X0200Y         S2      
017GND              VIA   -    M      A18X+106210Y+061560X0260Y         S2      
017GND                    -    MD0100PA00X+106210Y+061560                       
317GND              VIA   -    MD0100PA00X+105978Y+059467X0200Y         S0      
317GND              VIA   -    MD0100PA00X+105984Y+059758X0200Y         S0      
317GND              VIA   -    MD0100PA00X+105488Y+053638X0200Y         S0      
327GND              C913  -2          A01X+105314Y+053882X0198Y0197R270 S1      
327GND              C915  -2          A01X+105713Y+053878X0198Y0197R270 S1      
317GND              VIA   -    MD0100PA00X+105496Y+052692X0200Y    R090 S0      
317GND              VIA   -    MD0100PA00X+104997Y+053187X0200Y    R270 S0      
317GND              VIA   -    MD0100PA00X+105496Y+053187X0200Y    R090 S0      
317GND              VIA   -    MD0100PA00X+104997Y+052692X0200Y    R270 S0      
317GND              VIA   -    MD0100PA00X+104997Y+051770X0200Y    R270 S0      
317GND              VIA   -    MD0100PA00X+105496Y+051274X0200Y    R090 S0      
317GND              VIA   -    MD0100PA00X+104997Y+051274X0200Y    R270 S0      
317GND              VIA   -    MD0100PA00X+105496Y+051770X0200Y    R090 S0      
317GND              VIA   -    MD0100PA00X+107155Y+055523X0200Y         S0      
327GND              R236  -2          A01X+106844Y+055856X0198Y0197     S1      
327GND              R238  -2   M      A01X+106844Y+055456X0198Y0197     S1      
317GND              VIA   -    MD0100PA00X+106536Y+053403X0200Y    R090 S0      
317GND              VIA   -    MD0100PA00X+106536Y+053898X0200Y    R090 S0      
317GND              VIA   -    MD0100PA00X+106037Y+053403X0200Y    R270 S0      
317GND              VIA   -    MD0100PA00X+106037Y+053898X0200Y    R270 S0      
317GND              VIA   -    MD0100PA00X+106037Y+052481X0200Y    R270 S0      
317GND              VIA   -    MD0100PA00X+106536Y+052481X0200Y    R090 S0      
317GND              VIA   -    MD0100PA00X+106536Y+051986X0200Y    R090 S0      
317GND              VIA   -    MD0100PA00X+106037Y+051986X0200Y    R270 S0      
317GND              VIA   -    MD0100PA00X+106536Y+049485X0200Y    R090 S0      
317GND              VIA   -    MD0100PA00X+106037Y+049485X0200Y    R270 S0      
317GND              VIA   -    MD0100PA00X+106037Y+048990X0200Y    R270 S0      
317GND              VIA   -    MD0100PA00X+106536Y+048990X0200Y    R090 S0      
317GND              VIA   -    MD0100PA00X+106656Y+063495X0200Y         S0      
327GND              R226  -2          A01X+106460Y+063797X0198Y0197R180 S1      
327GND              R227  -2          A01X+106775Y+063142X0198Y0197     S1      
317GND              VIA   -    MD0100PA00X+106207Y+060759X0200Y         S0      
327GND              R230  -2          A01X+106457Y+060759X0198Y0197R180 S1      
317GND              VIA   -    MD0100PA00X+106207Y+059610X0200Y         S0      
317GND              VIA   -    MD0100PA00X+106127Y+059235X0200Y         S0      
317GND              VIA   -    MD0100PA00X+106133Y+058956X0200Y         S0      
317GND              VIA   -    MD0100PA00X+106207Y+059959X0200Y         S0      
317GND              VIA   -    MD0100PA00X+107126Y+056200X0200Y         S0      
327GND              R234  -2          A01X+106847Y+056257X0198Y0197     S1      
317GND              VIA   -    MD0100PA00X+109129Y+059511X0200Y         S0      
327GND              J24   -OB13       A01X+109544Y+059512X0140Y0480R270 S1      
317GND              VIA   -    MD0100PA00X+109082Y+060220X0200Y         S0      
327GND              J24   -OB10       A01X+109544Y+060220X0140Y0480R270 S1      
317GND              VIA   -    MD0100PA00X+109154Y+054711X0200Y         S0      
327GND              J24   -B13        A01X+109544Y+054711X0140Y0480R270 S1      
317GND              VIA   -    MD0100PA00X+109154Y+054002X0200Y         S0      
317GND              VIA   -    MD0100PA00X+109154Y+053293X0200Y         S0      
327GND              J24   -B19        A01X+109544Y+053293X0140Y0480R270 S1      
317GND              VIA   -    MD0100PA00X+109154Y+052585X0200Y         S0      
317GND              VIA   -    MD0100PA00X+109154Y+051876X0200Y         S0      
317GND              VIA   -    MD0100PA00X+109154Y+051167X0200Y         S0      
317GND              VIA   -    MD0100PA00X+109154Y+049589X0200Y         S0      
317GND              VIA   -    MD0100PA00X+109154Y+048880X0200Y         S0      
327GND              J24   -B32        A01X+109544Y+048880X0140Y0480R270 S1      
327GND              J24   -B49        A01X+109544Y+043167X0140Y0480R270 S1      
327GND              J24   -B46        A01X+109544Y+043876X0140Y0480R270 S1      
327GND              J24   -B55        A01X+109544Y+041750X0140Y0480R270 S1      
317GND              VIA   -    M      A01X+110445Y+065316X0200Y         S2      
017GND              VIA   -    M      A18X+110445Y+065316X0260Y         S2      
017GND                    -    MD0100PA00X+110445Y+065316                       
327GND              U30   -3          A01X+110102Y+065316X0160Y0360R270 S1      
317GND              VIA   -    MD0100PA00X+110530Y+060640X0200Y    R180 S0      
327GND              R225  -2          A18X+110770Y+060640X0198Y0197     S2      
317GND              VIA   -    MD0100PA00X+110530Y+061440X0200Y    R180 S0      
327GND              R232  -2          A18X+110770Y+061440X0198Y0197     S2      
317GND              VIA   -    MD0100PA00X+110530Y+059440X0200Y    R180 S0      
327GND              R224  -2          A18X+110770Y+059440X0198Y0197     S2      
317GND              VIA   -    MD0100PA00X+110530Y+060240X0200Y    R180 S0      
327GND              R223  -2          A18X+110770Y+060240X0198Y0197     S2      
317GND              VIA   -    MD0100PA00X+110530Y+059840X0200Y    R180 S0      
327GND              R222  -2          A18X+110770Y+059840X0198Y0197     S2      
317GND              VIA   -    MD0100PA00X+109981Y+057410X0200Y         S0      
317GND              VIA   -    MD0100PA00X+110104Y+056068X0200Y         S0      
317GND              VIA   -    MD0100PA00X+109927Y+056244X0200Y         S0      
317GND              VIA   -    MD0100PA00X+110158Y+057233X0200Y         S0      
317GND              VIA   -    MD0100PA00X+109983Y+055287X0200Y         S0      
317GND              VIA   -    MD0100PA00X+109995Y+055012X0200Y         S0      
317GND              VIA   -    MD0100PA00X+109934Y+052585X0200Y    R180 S0      
327GND              J24   -B22 M      A01X+109544Y+052585X0140Y0480R270 S1      
317GND              VIA   -    MD0100PA00X+109934Y+051167X0200Y    R180 S0      
327GND              J24   -B28 M      A01X+109544Y+051167X0140Y0480R270 S1      
317GND              VIA   -    MD0100PA00X+109934Y+051876X0200Y    R180 S0      
327GND              J24   -B25 M      A01X+109544Y+051876X0140Y0480R270 S1      
317GND              VIA   -    MD0100PA00X+110825Y+051056X0200Y         S0      
317GND              VIA   -    MD0100PA00X+110500Y+051684X0200Y         S0      
317GND              VIA   -    MD0100PA00X+110155Y+049883X0200Y    R180 S0      
327GND              J24   -B29 M      A01X+109544Y+049589X0140Y0480R270 S1      
327GND              J24   -B35 M      A01X+109544Y+048171X0140Y0480R270 S1      
327GND              J24   -B41 M      A01X+109544Y+046754X0140Y0480R270 S1      
327GND              J24   -B38 M      A01X+109544Y+047463X0140Y0480R270 S1      
327GND              J24   -B43 M      A01X+109544Y+044585X0140Y0480R270 S1      
327GND              J24   -B58 M      A01X+109544Y+041041X0140Y0480R270 S1      
327GND              J24   -B52 M      A01X+109544Y+042459X0140Y0480R270 S1      
327GND              J24   -B64 M      A01X+109544Y+039624X0140Y0480R270 S1      
327GND              J24   -B61 M      A01X+109544Y+040333X0140Y0480R270 S1      
327GND              J24   -B67 M      A01X+109544Y+038915X0140Y0480R270 S1      
327GND              J24   -A49 M      A01X+111355Y+043167X0140Y0480R270 S1      
327GND              J24   -A46 M      A01X+111355Y+043876X0140Y0480R270 S1      
327GND              J24   -A55 M      A01X+111355Y+041750X0140Y0480R270 S1      
327GND              J24   -A52 M      A01X+111355Y+042459X0140Y0480R270 S1      
327GND              J24   -A64 M      A01X+111355Y+039624X0140Y0480R270 S1      
327GND              J24   -A61        A01X+111355Y+040333X0140Y0480R270 S1      
327GND              J24   -A58        A01X+111355Y+041041X0140Y0480R270 S1      
327GND              J24   -A67 M      A01X+111355Y+038915X0140Y0480R270 S1      
317GND              VIA   -    MD0100PA00X+111886Y+066298X0200Y         S0      
327GND              C933  -2          A01X+111820Y+066040X0198Y0197     S1      
317GND              VIA   -    MD0100PA00X+112102Y+060775X0200Y    R090 S0      
317GND              VIA   -    MD0100PA00X+112051Y+061733X0200Y    R090 S0      
317GND              VIA   -    MD0100PA00X+112119Y+061256X0200Y    R090 S0      
317GND              VIA   -    MD0100PA00X+112272Y+059886X0200Y    R090 S0      
317GND              VIA   -    MD0100PA00X+111745Y+059512X0200Y    R180 S0      
327GND              J24   -OA13       A01X+111355Y+059512X0140Y0480R270 S1      
317GND              VIA   -    MD0100PA00X+111745Y+060220X0200Y    R180 S0      
327GND              J24   -OA10       A01X+111355Y+060220X0140Y0480R270 S1      
317GND              VIA   -    MD0100PA00X+111791Y+057541X0200Y    R090 S0      
317GND              VIA   -    MD0100PA00X+111791Y+057291X0200Y    R090 S0      
317GND              VIA   -    MD0100PA00X+111791Y+057041X0200Y    R090 S0      
317GND              VIA   -    MD0100PA00X+111791Y+056791X0200Y    R090 S0      
317GND              VIA   -    MD0100PA00X+111791Y+056541X0200Y    R090 S0      
327GND              J24   -A13        A01X+111355Y+054711X0140Y0480R270 S1      
317GND              VIA   -    MD0100PA00X+111745Y+054711X0200Y    R180 S0      
327GND              R228  -2          A18X+111513Y+054497X0198Y0197R180 S2      
317GND              VIA   -    MD0100PA00X+111745Y+055419X0200Y    R180 S0      
327GND              J24   -A10        A01X+111355Y+055419X0140Y0480R270 S1      
327GND              J24   -A16        A01X+111355Y+054002X0140Y0480R270 S1      
317GND              VIA   -    MD0100PA00X+111745Y+054002X0200Y    R180 S0      
317GND              VIA   -    MD0100PA00X+111745Y+053293X0200Y    R180 S0      
327GND              J24   -A19        A01X+111355Y+053293X0140Y0480R270 S1      
317GND              VIA   -    MD0100PA00X+111745Y+052585X0200Y    R180 S0      
327GND              J24   -A22        A01X+111355Y+052585X0140Y0480R270 S1      
317GND              VIA   -    MD0100PA00X+112475Y+052585X0200Y         S0      
317GND              VIA   -    MD0100PA00X+112225Y+052585X0200Y         S0      
317GND              VIA   -    MD0100PA00X+112225Y+054002X0200Y         S0      
317GND              VIA   -    MD0100PA00X+112225Y+053293X0200Y         S0      
317GND              VIA   -    MD0100PA00X+112475Y+053293X0200Y         S0      
317GND              VIA   -    MD0100PA00X+111745Y+051876X0200Y    R180 S0      
327GND              J24   -A25 M      A01X+111355Y+051876X0140Y0480R270 S1      
317GND              VIA   -    MD0100PA00X+111745Y+051167X0200Y    R180 S0      
327GND              J24   -A28 M      A01X+111355Y+051167X0140Y0480R270 S1      
317GND              VIA   -    MD0100PA00X+112475Y+051167X0200Y         S0      
317GND              VIA   -    MD0100PA00X+112225Y+051876X0200Y         S0      
317GND              VIA   -    MD0100PA00X+112475Y+051876X0200Y         S0      
317GND              VIA   -    MD0100PA00X+110965Y+049589X0200Y         S0      
317GND              VIA   -    MD0100PA00X+111745Y+049589X0200Y    R180 S0      
327GND              J24   -A29 M      A01X+111355Y+049589X0140Y0480R270 S1      
317GND              VIA   -    MD0100PA00X+112225Y+049589X0200Y         S0      
317GND              VIA   -    MD0100PA00X+110913Y+048771X0200Y         S0      
327GND              J24   -A35 M      A01X+111355Y+048171X0140Y0480R270 S1      
317GND              VIA   -    MD0100PA00X+111745Y+048880X0200Y    R180 S0      
327GND              J24   -A32 M      A01X+111355Y+048880X0140Y0480R270 S1      
317GND              VIA   -    MD0100PA00X+112475Y+048880X0200Y         S0      
317GND              VIA   -    MD0100PA00X+112225Y+048880X0200Y         S0      
327GND              J24   -A38 M      A01X+111355Y+047463X0140Y0480R270 S1      
327GND              J24   -A41 M      A01X+111355Y+046754X0140Y0480R270 S1      
327GND              J24   -A43 M      A01X+111355Y+044585X0140Y0480R270 S1      
317GND              VIA   -    MD0100PA00X+112529Y+059290X0200Y    R180 S0      
317GND              VIA   -    MD0100PA00X+112663Y+056050X0200Y         S0      
327GND              U28   -3          A18X+112663Y+055780X0240Y0240R180 S2      
317GND              VIA   -    MD0100PA00X+113867Y+055500X0200Y         S0      
327GND              R242  -2          A01X+114120Y+055370X0198Y0197R180 S1      
317GND              VIA   -    MD0100PA00X+113810Y+054392X0200Y         S0      
327GND              C918  -2          A18X+113467Y+054392X0198Y0197R090 S2      
317GND              VIA   -    MD0100PA00X+113817Y+053476X0200Y    R090 S0      
317GND              VIA   -    MD0100PA00X+112955Y+052585X0200Y         S0      
317GND              VIA   -    MD0100PA00X+112955Y+053293X0200Y         S0      
317GND              VIA   -    MD0100PA00X+112955Y+051167X0200Y         S0      
317GND              VIA   -    MD0100PA00X+112955Y+051876X0200Y         S0      
317GND              VIA   -    MD0100PA00X+112955Y+048880X0200Y         S0      
317GND              VIA   -    M      A01X+115725Y+063684X0200Y         S2      
017GND              VIA   -    M      A18X+115725Y+063684X0260Y         S2      
017GND                    -    MD0100PA00X+115725Y+063684                       
317GND              VIA   -    MD0100PA00X+117328Y+061636X0200Y         S0      
317GND              VIA   -    MD0100PA00X+116848Y+059510X0200Y         S0      
317GND              VIA   -    MD0100PA00X+117328Y+059510X0200Y         S0      
317GND              VIA   -    MD0100PA00X+117328Y+060219X0200Y         S0      
317GND              VIA   -    MD0100PA00X+116848Y+060219X0200Y         S0      
317GND              VIA   -    MD0100PA00X+116848Y+057384X0200Y         S0      
317GND              VIA   -    MD0100PA00X+117328Y+057384X0200Y         S0      
317GND              VIA   -    MD0100PA00X+116848Y+058801X0200Y         S0      
317GND              VIA   -    MD0100PA00X+117328Y+058801X0200Y         S0      
317GND              VIA   -    MD0100PA00X+117328Y+058093X0200Y         S0      
317GND              VIA   -    MD0100PA00X+116848Y+058093X0200Y         S0      
317GND              VIA   -    MD0100PA00X+116848Y+056675X0200Y         S0      
317GND              VIA   -    MD0100PA00X+117328Y+056675X0200Y         S0      
317GND              VIA   -    MD0100PA00X+116127Y+055046X0200Y    R090 S0      
317GND              VIA   -    MD0100PA00X+116848Y+053089X0200Y         S0      
317GND              VIA   -    MD0100PA00X+117328Y+053089X0200Y         S0      
317GND              VIA   -    MD0100PA00X+116848Y+053797X0200Y         S0      
317GND              VIA   -    MD0100PA00X+117328Y+053797X0200Y         S0      
317GND              VIA   -    MD0100PA00X+117328Y+052380X0200Y         S0      
317GND              VIA   -    MD0100PA00X+117328Y+051671X0200Y         S0      
317GND              VIA   -    MD0100PA00X+116848Y+051671X0200Y         S0      
317GND              VIA   -    MD0100PA00X+116848Y+052380X0200Y         S0      
317GND              VIA   -    MD0100PA00X+117328Y+049384X0200Y         S0      
317GND              VIA   -    MD0100PA00X+116848Y+049384X0200Y         S0      
327GND              J25   -OA13       A01X+118448Y+041039X0140Y0480R090 S1      
327GND              J25   -OA10       A01X+118448Y+040331X0140Y0480R090 S1      
317GND              VIA   -    MD0100PA00X+116316Y+063812X0200Y         S0      
327GND              Q121  -4          A01X+116316Y+064087X0240Y0240     S1      
317GND              VIA   -    MD0100PA00X+116848Y+061636X0200Y         S0      
317GND              VIA   -    MD0100PA00X+116848Y+060927X0200Y         S0      
317GND              VIA   -    MD0100PA00X+117328Y+060927X0200Y         S0      
317GND              VIA   -    MD0100PA00X+118876Y+056557X0200Y    R180 S0      
317GND              VIA   -    MD0100PA00X+118838Y+055966X0200Y    R180 S0      
317GND              VIA   -    MD0100PA00X+117578Y+055966X0200Y         S0      
317GND              VIA   -    MD0100PA00X+117578Y+056675X0200Y         S0      
317GND              VIA   -    MD0100PA00X+118058Y+056675X0200Y         S0      
327GND              J25   -A46 M      A01X+118448Y+056675X0140Y0480R090 S1      
317GND              VIA   -    MD0100PA00X+118058Y+055966X0200Y         S0      
327GND              J25   -A43 M      A01X+118448Y+055966X0140Y0480R090 S1      
317GND              VIA   -    MD0100PA00X+118964Y+052914X0200Y    R180 S0      
317GND              VIA   -    MD0100PA00X+118948Y+053568X0200Y    R180 S0      
317GND              VIA   -    MD0100PA00X+118058Y+053089X0200Y         S0      
327GND              J25   -A38 M      A01X+118448Y+053089X0140Y0480R090 S1      
317GND              VIA   -    MD0100PA00X+117578Y+053089X0200Y         S0      
317GND              VIA   -    MD0100PA00X+118058Y+053797X0200Y         S0      
327GND              J25   -A41 M      A01X+118448Y+053797X0140Y0480R090 S1      
317GND              VIA   -    MD0100PA00X+118838Y+050963X0200Y    R180 S0      
317GND              VIA   -    MD0100PA00X+118899Y+052213X0200Y    R180 S0      
317GND              VIA   -    MD0100PA00X+118907Y+051461X0200Y    R180 S0      
317GND              VIA   -    MD0100PA00X+117578Y+052380X0200Y         S0      
317GND              VIA   -    MD0100PA00X+117578Y+051671X0200Y         S0      
317GND              VIA   -    MD0100PA00X+118058Y+050963X0200Y         S0      
327GND              J25   -A29 M      A01X+118448Y+050963X0140Y0480R090 S1      
317GND              VIA   -    MD0100PA00X+118058Y+051671X0200Y         S0      
327GND              J25   -A32 M      A01X+118448Y+051671X0140Y0480R090 S1      
327GND              J25   -A35 M      A01X+118448Y+052380X0140Y0480R090 S1      
317GND              VIA   -    MD0100PA00X+118058Y+052380X0200Y         S0      
317GND              VIA   -    MD0100PA00X+117578Y+050963X0200Y         S0      
317GND              VIA   -    MD0100PA00X+118834Y+049509X0200Y    R180 S0      
317GND              VIA   -    MD0100PA00X+118058Y+049384X0200Y         S0      
327GND              J25   -A28 M      A01X+118448Y+049384X0140Y0480R090 S1      
317GND              VIA   -    MD0100PA00X+118852Y+048944X0200Y    R180 S0      
327GND              J25   -A22 M      A01X+118448Y+047966X0140Y0480R090 S1      
327GND              J25   -A25 M      A01X+118448Y+048675X0140Y0480R090 S1      
327GND              J25   -A19 M      A01X+118448Y+047258X0140Y0480R090 S1      
327GND              J25   -A16 M      A01X+118448Y+046549X0140Y0480R090 S1      
327GND              J25   -A13        A01X+118448Y+045841X0140Y0480R090 S1      
327GND              J25   -A10        A01X+118448Y+045132X0140Y0480R090 S1      
317GND              VIA   -    MD0100PA00X+118850Y+061636X0200Y    R180 S0      
317GND              VIA   -    MD0100PA00X+118058Y+060927X0200Y         S0      
327GND              J25   -A64        A01X+118448Y+060927X0140Y0480R090 S1      
317GND              VIA   -    MD0100PA00X+118058Y+061636X0200Y         S0      
327GND              J25   -A67 M      A01X+118448Y+061636X0140Y0480R090 S1      
317GND              VIA   -    MD0100PA00X+117578Y+060927X0200Y         S0      
317GND              VIA   -    MD0100PA00X+118058Y+059510X0200Y         S0      
327GND              J25   -A58        A01X+118448Y+059510X0140Y0480R090 S1      
317GND              VIA   -    MD0100PA00X+117578Y+059510X0200Y         S0      
317GND              VIA   -    MD0100PA00X+118058Y+060218X0200Y         S0      
327GND              J25   -A61        A01X+118448Y+060218X0140Y0480R090 S1      
317GND              VIA   -    MD0100PA00X+117578Y+060218X0200Y         S0      
317GND              VIA   -    MD0100PA00X+118841Y+057434X0200Y    R180 S0      
317GND              VIA   -    MD0100PA00X+117578Y+057384X0200Y         S0      
317GND              VIA   -    MD0100PA00X+118058Y+057384X0200Y         S0      
327GND              J25   -A49 M      A01X+118448Y+057384X0140Y0480R090 S1      
317GND              VIA   -    MD0100PA00X+117578Y+058801X0200Y         S0      
317GND              VIA   -    MD0100PA00X+118058Y+058801X0200Y         S0      
327GND              J25   -A55        A01X+118448Y+058801X0140Y0480R090 S1      
317GND              VIA   -    MD0100PA00X+118058Y+058093X0200Y         S0      
327GND              J25   -A52        A01X+118448Y+058092X0140Y0480R090 S1      
317GND              VIA   -    MD0100PA00X+117578Y+058093X0200Y         S0      
317GND              VIA   -    MD0100PA00X+119755Y+053276X0200Y         S0      
317GND              VIA   -    MD0100PA00X+119763Y+052548X0200Y         S0      
317GND              VIA   -    MD0100PA00X+119515Y+053797X0200Y         S0      
317GND              VIA   -    MD0100PA00X+119869Y+051671X0200Y         S0      
317GND              VIA   -    MD0100PA00X+119869Y+050963X0200Y         S0      
317GND              VIA   -    MD0100PA00X+119869Y+049384X0200Y         S0      
317GND              VIA   -    MD0100PA00X+119875Y+060812X0200Y         S0      
317GND              VIA   -    MD0100PA00X+119869Y+057384X0200Y         S0      
317GND              VIA   -    MD0100PA00X+119854Y+057998X0200Y         S0      
317GND              VIA   -    MD0100PA00X+119869Y+056675X0200Y         S0      
317GND              VIA   -    MD0100PA00X+119869Y+055966X0200Y         S0      
317GND              VIA   -    MD0100PA00X+120649Y+060927X0200Y    R180 S0      
327GND              J25   -B64 M      A01X+120259Y+060927X0140Y0480R090 S1      
317GND              VIA   -    MD0100PA00X+120649Y+061636X0200Y    R180 S0      
327GND              J25   -B67        A01X+120259Y+061636X0140Y0480R090 S1      
317GND              VIA   -    MD0100PA00X+120649Y+059510X0200Y    R180 S0      
327GND              J25   -B58        A01X+120259Y+059510X0140Y0480R090 S1      
317GND              VIA   -    MD0100PA00X+120649Y+060218X0200Y    R180 S0      
327GND              J25   -B61        A01X+120259Y+060218X0140Y0480R090 S1      
317GND              VIA   -    MD0100PA00X+120649Y+057384X0200Y    R180 S0      
327GND              J25   -B49 M      A01X+120259Y+057384X0140Y0480R090 S1      
317GND              VIA   -    MD0100PA00X+120649Y+058801X0200Y    R180 S0      
327GND              J25   -B55        A01X+120259Y+058801X0140Y0480R090 S1      
317GND              VIA   -    MD0100PA00X+120649Y+058092X0200Y    R180 S0      
327GND              J25   -B52 M      A01X+120259Y+058092X0140Y0480R090 S1      
317GND              VIA   -    MD0100PA00X+120649Y+055966X0200Y    R180 S0      
327GND              J25   -B43 M      A01X+120259Y+055966X0140Y0480R090 S1      
317GND              VIA   -    MD0100PA00X+120649Y+056675X0200Y    R180 S0      
327GND              J25   -B46 M      A01X+120259Y+056675X0140Y0480R090 S1      
317GND              VIA   -    MD0100PA00X+120649Y+053089X0200Y    R180 S0      
327GND              J25   -B38 M      A01X+120259Y+053089X0140Y0480R090 S1      
317GND              VIA   -    MD0100PA00X+120649Y+053797X0200Y    R180 S0      
327GND              J25   -B41 M      A01X+120259Y+053797X0140Y0480R090 S1      
317GND              VIA   -    MD0100PA00X+120649Y+050963X0200Y    R180 S0      
327GND              J25   -B29 M      A01X+120259Y+050963X0140Y0480R090 S1      
317GND              VIA   -    MD0100PA00X+120649Y+051671X0200Y    R180 S0      
327GND              J25   -B32 M      A01X+120259Y+051671X0140Y0480R090 S1      
327GND              J25   -B35 M      A01X+120259Y+052380X0140Y0480R090 S1      
317GND              VIA   -    MD0100PA00X+120649Y+052380X0200Y    R180 S0      
317GND              VIA   -    MD0100PA00X+120649Y+049384X0200Y    R180 S0      
327GND              J25   -B28 M      A01X+120259Y+049384X0140Y0480R090 S1      
327GND              J25   -B22 M      A01X+120259Y+047966X0140Y0480R090 S1      
327GND              J25   -B25 M      A01X+120259Y+048675X0140Y0480R090 S1      
327GND              J25   -B19 M      A01X+120259Y+047258X0140Y0480R090 S1      
327GND              J25   -B16 M      A01X+120259Y+046549X0140Y0480R090 S1      
327GND              J25   -B13 M      A01X+120259Y+045841X0140Y0480R090 S1      
327GND              J25   -OB13       A01X+120259Y+041039X0140Y0480R090 S1      
327GND              J25   -OB10       A01X+120259Y+040331X0140Y0480R090 S1      
317GND              VIA   -    MD0100PA00X+123267Y+052979X0200Y    R270 S0      
317GND              VIA   -    MD0100PA00X+123267Y+052484X0200Y    R270 S0      
317GND              VIA   -    MD0100PA00X+123766Y+052979X0200Y    R090 S0      
317GND              VIA   -    MD0100PA00X+123766Y+052484X0200Y    R090 S0      
317GND              VIA   -    MD0100PA00X+123766Y+051066X0200Y    R090 S0      
317GND              VIA   -    MD0100PA00X+123267Y+051066X0200Y    R270 S0      
317GND              VIA   -    MD0100PA00X+123766Y+051562X0200Y    R090 S0      
317GND              VIA   -    MD0100PA00X+123267Y+051562X0200Y    R270 S0      
317GND              VIA   -    MD0100PA00X+123267Y+060818X0200Y    R270 S0      
317GND              VIA   -    MD0100PA00X+123766Y+060818X0200Y    R090 S0      
317GND              VIA   -    MD0100PA00X+123766Y+059400X0200Y    R090 S0      
317GND              VIA   -    MD0100PA00X+123267Y+059400X0200Y    R270 S0      
317GND              VIA   -    MD0100PA00X+123267Y+060322X0200Y    R270 S0      
317GND              VIA   -    MD0100PA00X+123766Y+060322X0200Y    R090 S0      
317GND              VIA   -    MD0100PA00X+123766Y+057983X0200Y    R090 S0      
317GND              VIA   -    MD0100PA00X+123267Y+057487X0200Y    R270 S0      
317GND              VIA   -    MD0100PA00X+123766Y+057487X0200Y    R090 S0      
317GND              VIA   -    MD0100PA00X+123267Y+058905X0200Y    R270 S0      
317GND              VIA   -    MD0100PA00X+123766Y+058905X0200Y    R090 S0      
317GND              VIA   -    MD0100PA00X+123267Y+057983X0200Y    R270 S0      
317GND              VIA   -    MD0100PA00X+123766Y+056070X0200Y    R090 S0      
317GND              VIA   -    MD0100PA00X+123766Y+056566X0200Y    R090 S0      
317GND              VIA   -    MD0100PA00X+123267Y+056070X0200Y    R270 S0      
317GND              VIA   -    MD0100PA00X+123267Y+056566X0200Y    R270 S0      
317GND              VIA   -    MD0100PA00X+124307Y+053195X0200Y    R270 S0      
317GND              VIA   -    MD0100PA00X+124307Y+053690X0200Y    R270 S0      
317GND              VIA   -    MD0100PA00X+124806Y+053690X0200Y    R090 S0      
317GND              VIA   -    MD0100PA00X+124806Y+053195X0200Y    R090 S0      
317GND              VIA   -    MD0100PA00X+124307Y+051777X0200Y    R270 S0      
317GND              VIA   -    MD0100PA00X+124806Y+052273X0200Y    R090 S0      
317GND              VIA   -    MD0100PA00X+124806Y+051777X0200Y    R090 S0      
317GND              VIA   -    MD0100PA00X+124307Y+052273X0200Y    R270 S0      
317GND              VIA   -    MD0100PA00X+124806Y+049277X0200Y    R090 S0      
317GND              VIA   -    MD0100PA00X+124307Y+049277X0200Y    R270 S0      
317GND              VIA   -    MD0100PA00X+124806Y+048781X0200Y    R090 S0      
317GND              VIA   -    MD0100PA00X+124307Y+048781X0200Y    R270 S0      
317GND              VIA   -    MD0100PA00X+124806Y+061033X0200Y         S0      
317GND              VIA   -    MD0100PA00X+124806Y+061529X0200Y         S0      
317GND              VIA   -    MD0100PA00X+124307Y+061529X0200Y    R270 S0      
317GND              VIA   -    MD0100PA00X+124307Y+061033X0200Y    R270 S0      
317GND              VIA   -    MD0100PA00X+124806Y+059616X0200Y         S0      
317GND              VIA   -    MD0100PA00X+124307Y+059616X0200Y    R270 S0      
317GND              VIA   -    MD0100PA00X+124806Y+060112X0200Y         S0      
317GND              VIA   -    MD0100PA00X+124307Y+060112X0200Y    R270 S0      
317GND              VIA   -    MD0100PA00X+124307Y+058199X0200Y    R270 S0      
317GND              VIA   -    MD0100PA00X+124307Y+058694X0200Y    R270 S0      
317GND              VIA   -    MD0100PA00X+124806Y+058694X0200Y         S0      
317GND              VIA   -    MD0100PA00X+124806Y+058199X0200Y         S0      
317GND              VIA   -    MD0100PA00X+124307Y+057277X0200Y    R270 S0      
317GND              VIA   -    MD0100PA00X+124806Y+057277X0200Y         S0      
317GND              VIA   -    MD0100PA00X+124307Y+056781X0200Y    R270 S0      
317GND              VIA   -    MD0100PA00X+124175Y+056484X0200Y    R180 S0      
327GND              C4003 -2          A01X+125646Y+056529X0198Y0197R090 S1      
327GND              U34   -S   M      A01X+124312Y+056004X0400Y0560R180 S1      
317GND              VIA   -    MD0100PA00X+124806Y+056781X0200Y         S0      
317GND              VIA   -    MD0100PA00X+127095Y+049187X0200Y         S0      
317GND              VIA   -    MD0100PA00X+126784Y+049362X0200Y    R090 S0      
317GND              VIA   -    MD0100PA00X+126784Y+049112X0200Y    R090 S0      
317GND              VIA   -    MD0100PA00X+126784Y+048862X0200Y    R090 S0      
317GND              VIA   -    MD0100PA00X+127606Y+049376X0200Y    R090 S0      
317GND              VIA   -    MD0100PA00X+127345Y+049187X0200Y         S0      
317GND              VIA   -    MD0100PA00X+127606Y+049626X0200Y    R090 S0      
317GND              VIA   -    MD0100PA00X+127950Y+049007X0200Y    R090 S0      
317GND              VIA   -    MD0100PA00X+127950Y+048757X0200Y    R090 S0      
317GND              VIA   -    MD0100PA00X+129678Y+051196X0200Y         S0      
317GND              VIA   -    MD0100PA00X+131900Y+065750X0200Y    R180 S0      
327GND              R4742 -2          A01X+132142Y+065750X0198Y0197R180 S1      
317GND              VIA   -    MD0100PA00X+131900Y+062900X0200Y    R180 S0      
327GND              R4800 -2          A01X+132142Y+062900X0198Y0197R180 S1      
317GND              VIA   -    MD0100PA00X+131900Y+061300X0200Y    R180 S0      
327GND              R4801 -2          A01X+132142Y+061300X0198Y0197R180 S1      
317GND              VIA   -    MD0100PA00X+131900Y+058250X0200Y    R180 S0      
327GND              R4802 -2          A01X+132142Y+058250X0198Y0197R180 S1      
317GND              VIA   -    MD0100PA00X+131900Y+056650X0200Y    R180 S0      
327GND              R4803 -2          A01X+132142Y+056650X0198Y0197R180 S1      
317GND              VIA   -    MD0100PA00X+130800Y+048738X0200Y    R090 S0      
327GND              C2880 -2          A01X+130542Y+048738X0198Y0197     S1      
317GND              VIA   -    MD0100PA00X+133500Y+063700X0200Y         S0      
327GND              R4825 -1          A01X+133258Y+063700X0198Y0197R180 S1      
317GND              VIA   -    M      A01X+133500Y+063300X0200Y         S2      
017GND              VIA   -    M      A18X+133500Y+063300X0260Y         S2      
017GND                    -    MD0100PA00X+133500Y+063300                       
327GND              R4824 -1          A01X+133258Y+063300X0198Y0197R180 S1      
317GND              VIA   -    MD0100PA00X+133500Y+058650X0200Y         S0      
327GND              R4843 -1          A01X+133258Y+058650X0198Y0197R180 S1      
317GND              VIA   -    M      A01X+133500Y+059050X0200Y         S2      
017GND              VIA   -    M      A18X+133500Y+059050X0260Y         S2      
017GND                    -    MD0100PA00X+133500Y+059050                       
317GND              VIA   -    MD0100PA00X+132563Y+051324X0200Y         S0      
317GND              VIA   -    MD0100PA00X+132691Y+049315X0200Y         S0      
317GND              VIA   -    M      A01X+134477Y+076968X0200Y    R180 S2      
017GND              VIA   -    M      A18X+134477Y+076968X0260Y    R180 S2      
017GND                    -    MD0100PA00X+134477Y+076968                       
317GND              VIA   -    MD0100PA00X+134545Y+069903X0200Y         S0      
327GND              U347  -12         A01X+135098Y+069903X0240Y0540R270 S1      
317GND              VIA   -    M      A01X+135526Y+065203X0200Y         S2      
017GND              VIA   -    M      A18X+135526Y+065203X0260Y         S2      
017GND                    -    MD0100PA00X+135526Y+065203                       
327GND              U348  -12         A01X+135098Y+065203X0240Y0540R270 S1      
317GND              VIA   -    MD0100PA00X+135526Y+060753X0200Y         S0      
327GND              U349  -12         A01X+135098Y+060753X0240Y0540R270 S1      
317GND              VIA   -    M      A01X+135526Y+056103X0200Y         S2      
017GND              VIA   -    M      A18X+135526Y+056103X0260Y         S2      
017GND                    -    MD0100PA00X+135526Y+056103                       
327GND              U350  -12         A01X+135098Y+056103X0240Y0540R270 S1      
317GND              VIA   -    MD0100PA00X+138342Y+073158X0200Y         S0      
327GND              C3601 -2          A01X+138050Y+073158X0198Y0197R090 S1      
317GND              VIA   -    MD0100PA00X+138193Y+072255X0200Y         S0      
317GND              VIA   -    MD0100PA00X+138342Y+068414X0200Y         S0      
327GND              C3602 -2          A01X+138050Y+068458X0198Y0197R090 S1      
317GND              VIA   -    MD0100PA00X+138124Y+067362X0200Y         S0      
317GND              VIA   -    MD0100PA00X+138342Y+064008X0200Y         S0      
327GND              C3604 -2          A01X+138050Y+064008X0198Y0197R090 S1      
317GND              VIA   -    MD0100PA00X+138112Y+063403X0200Y         S0      
317GND              VIA   -    MD0100PA00X+138356Y+060484X0200Y         S0      
317GND              VIA   -    M      A01X+138342Y+059358X0200Y         S2      
017GND              VIA   -    M      A18X+138342Y+059358X0260Y         S2      
017GND                    -    MD0100PA00X+138342Y+059358                       
327GND              C3603 -2          A01X+138050Y+059358X0198Y0197R090 S1      
317GND              VIA   -    MD0100PA00X+138318Y+058765X0200Y         S0      
317GND              VIA   -    MD0100PA00X+138356Y+055834X0200Y         S0      
327GND              R4804 -2          A18X+138286Y+056100X0198Y0197     S2      
317GND              VIA   -    MD0100PA00X+140091Y+059122X0200Y         S0      
317GND              VIA   -    MD0100PA00X+140091Y+058122X0200Y         S0      
317GND              VIA   -    MD0100PA00X+139109Y+057719X0200Y         S0      
327GND              R4845 -1          A01X+138866Y+057719X0198Y0197R180 S1      
317GND              VIA   -    MD0100PA00X+139708Y+054073X0200Y    R180 S0      
317GND              VIA   -    MD0100PA00X+139708Y+055273X0200Y    R180 S0      
317GND              VIA   -    MD0100PA00X+139708Y+053673X0200Y    R180 S0      
327GND              PC349 -2          A01X+139966Y+053673X0198Y0197R180 S1      
317GND              VIA   -    M      A01X+139708Y+053173X0200Y    R180 S2      
017GND              VIA   -    M      A18X+139708Y+053173X0260Y    R180 S2      
017GND                    -    MD0100PA00X+139708Y+053173                       
327GND              C2858 -2          A01X+139966Y+053173X0198Y0197R180 S1      
317GND              VIA   -    MD0100PA00X+138824Y+072200X0200Y         S0      
327GND              R4763 -1          A01X+139092Y+072200X0198Y0197     S1      
317GND              VIA   -    MD0100PA00X+138841Y+067500X0200Y         S0      
327GND              R4782 -1          A01X+139092Y+067500X0198Y0197     S1      
317GND              VIA   -    MD0100PA00X+139159Y+062782X0200Y         S0      
327GND              R4826 -1          A01X+138866Y+062782X0198Y0197R180 S1      
317GND              VIA   -    MD0100PA00X+141000Y+074900X0200Y    R180 S0      
327GND              R4613 -2          A01X+141242Y+074900X0198Y0197R180 S1      
317GND              VIA   -    MD0100PA00X+141000Y+073300X0200Y    R180 S0      
327GND              R4614 -2          A01X+141242Y+073300X0198Y0197R180 S1      
317GND              VIA   -    MD0100PA00X+141000Y+070500X0200Y    R180 S0      
327GND              R4676 -2          A01X+141242Y+070500X0198Y0197R180 S1      
317GND              VIA   -    MD0100PA00X+141000Y+068900X0200Y    R180 S0      
327GND              R4677 -2          A01X+141242Y+068900X0198Y0197R180 S1      
317GND              VIA   -    MD0100PA00X+140500Y+069900X0200Y         S0      
327GND              R4743 -2          A01X+140258Y+069900X0198Y0197     S1      
317GND              VIA   -    MD0100PA00X+140500Y+065600X0200Y         S0      
327GND              R4744 -2          A01X+140258Y+065600X0198Y0197     S1      
317GND              VIA   -    MD0100PA00X+140795Y+064182X0200Y    R270 S0      
327GND              PR7057-2   M      A01X+140795Y+063939X0198Y0197R090 S1      
317GND              VIA   -    M      A01X+141345Y+064182X0200Y    R270 S2      
017GND              VIA   -    M      A18X+141345Y+064182X0260Y    R270 S2      
017GND                    -    MD0100PA00X+141345Y+064182                       
327GND              PC831 -2   M      A01X+141345Y+063939X0198Y0197R090 S1      
317GND              VIA   -    MD0100PA00X+140551Y+061109X0200Y         S0      
317GND              VIA   -    MD0100PA00X+140651Y+059122X0200Y         S0      
317GND              VIA   -    MD0100PA00X+140371Y+059122X0200Y         S0      
317GND              VIA   -    MD0100PA00X+140371Y+058122X0200Y         S0      
317GND              VIA   -    MD0100PA00X+140651Y+058122X0200Y         S0      
317GND              VIA   -    MD0100PA00X+141090Y+057119X0200Y         S0      
317GND              VIA   -    MD0100PA00X+140810Y+057119X0200Y         S0      
317GND              VIA   -    MD0100PA00X+141090Y+056319X0200Y         S0      
317GND              VIA   -    MD0100PA00X+140810Y+056319X0200Y         S0      
317GND              VIA   -    MD0100PA00X+141090Y+055519X0200Y         S0      
317GND              VIA   -    MD0100PA00X+140810Y+055519X0200Y         S0      
317GND              VIA   -    MD0100PA00X+140691Y+049998X0200Y    R180 S0      
327GND              PC483 -2          A01X+140949Y+049998X0198Y0197R180 S1      
317GND              VIA   -    MD0100PA00X+140691Y+048798X0200Y    R180 S0      
317GND              VIA   -    MD0100PA00X+143149Y+052180X0200Y    R270 S0      
317GND              VIA   -    MD0100PA00X+143051Y+051698X0200Y         S0      
317GND              VIA   -    MD0100PA00X+143301Y+051698X0200Y         S0      
317GND              VIA   -    MD0100PA00X+143081Y+050470X0200Y         S0      
317GND              VIA   -    MD0100PA00X+143331Y+050470X0200Y         S0      
317GND              VIA   -    MD0100PA00X+143093Y+050009X0200Y    R180 S0      
317GND              VIA   -    MD0100PA00X+142700Y+077450X0200Y    R180 S0      
327GND              R4675 -2          A01X+142942Y+077450X0198Y0197R180 S1      
317GND              VIA   -    MD0100PA00X+142600Y+075300X0200Y         S0      
327GND              R4654 -1          A01X+142358Y+075300X0198Y0197R180 S1      
317GND              VIA   -    MD0100PA00X+142600Y+075700X0200Y         S0      
327GND              R4655 -1          A01X+142358Y+075700X0198Y0197R180 S1      
317GND              VIA   -    MD0100PA00X+142600Y+071300X0200Y         S0      
327GND              R4718 -1          A01X+142358Y+071300X0198Y0197R180 S1      
317GND              VIA   -    MD0100PA00X+142600Y+070900X0200Y         S0      
327GND              R4717 -1          A01X+142358Y+070900X0198Y0197R180 S1      
317GND              VIA   -    MD0100PA00X+142439Y+062795X0200Y         S0      
327GND              PU105 -3          A01X+142439Y+062482X0100Y0320R180 S1      
317GND              VIA   -    MD0100PA00X+142723Y+062818X0200Y         S0      
327GND              PU105 -2          A01X+142636Y+062482X0100Y0320R180 S1      
317GND              VIA   -    M      A01X+142110Y+054683X0200Y    R180 S2      
017GND              VIA   -    M      A18X+142110Y+054683X0260Y    R180 S2      
017GND                    -    MD0100PA00X+142110Y+054683                       
317GND              VIA   -    MD0100PA00X+142780Y+053138X0200Y    R270 S0      
317GND              VIA   -    MD0100PA00X+143149Y+052430X0200Y    R270 S0      
317GND              VIA   -    MD0100PA00X+143296Y+052745X0200Y    R180 S0      
317GND              VIA   -    M      A01X+142780Y+052858X0200Y    R270 S2      
017GND              VIA   -    M      A18X+142780Y+052858X0260Y    R270 S2      
017GND                    -    MD0100PA00X+142780Y+052858                       
317GND              VIA   -    MD0100PA00X+143567Y+057298X0200Y    R090 S0      
327GND              C946  -2          A01X+143567Y+057576X0198Y0197R270 S1      
317GND              VIA   -    MD0100PA00X+144299Y+057948X0200Y    R090 S0      
327GND              U85   -10         A01X+144378Y+058234X0090Y0240R180 S1      
317GND              VIA   -    MD0100PA00X+144244Y+058551X0200Y    R090 S0      
317GND              VIA   -    MD0100PA00X+144704Y+058551X0200Y    R090 S0      
317GND              VIA   -    MD0100PA00X+143888Y+057284X0200Y    R090 S0      
317GND              VIA   -    MD0100PA00X+144204Y+051952X0200Y         S0      
317GND              VIA   -    MD0100PA00X+143954Y+051952X0200Y         S0      
317GND              VIA   -    MD0100PA00X+144454Y+051952X0200Y         S0      
317GND              VIA   -    MD0100PA00X+143946Y+052463X0200Y    R270 S0      
317GND              VIA   -    MD0100PA00X+143946Y+052713X0200Y    R270 S0      
317GND              VIA   -    MD0100PA00X+143576Y+052745X0200Y    R180 S0      
317GND              VIA   -    M      A01X+143946Y+052993X0200Y    R270 S2      
017GND              VIA   -    M      A18X+143946Y+052993X0260Y    R270 S2      
017GND                    -    MD0100PA00X+143946Y+052993                       
317GND              VIA   -    MD0100PA00X+143946Y+052213X0200Y    R270 S0      
317GND              VIA   -    MD0100PA00X+143551Y+051698X0200Y         S0      
317GND              VIA   -    MD0100PA00X+144704Y+051952X0200Y         S0      
317GND              VIA   -    MD0100PA00X+143581Y+050470X0200Y         S0      
317GND              VIA   -    MD0100PA00X+143657Y+072753X0200Y         S0      
327GND              U344  -12         A01X+144198Y+072753X0240Y0540R270 S1      
317GND              VIA   -    MD0100PA00X+143778Y+068353X0200Y         S0      
327GND              U346  -12         A01X+144198Y+068353X0240Y0540R270 S1      
317GND              VIA   -    MD0100PA00X+144093Y+063880X0200Y         S0      
317GND              VIA   -    MD0100PA00X+144093Y+063320X0200Y         S0      
317GND              VIA   -    MD0100PA00X+144093Y+063600X0200Y         S0      
317GND              VIA   -    M      A01X+143777Y+062824X0200Y    R270 S2      
017GND              VIA   -    M      A18X+143777Y+062824X0260Y    R270 S2      
017GND                    -    MD0100PA00X+143777Y+062824                       
327GND              PC798 -2   M      A01X+143525Y+062824X0198Y0197R090 S1      
317GND              VIA   -    MD0100PA00X+144694Y+060544X0200Y    R090 S0      
327GND              R752  -2          A01X+144694Y+060280X0198Y0197R090 S1      
317GND              VIA   -    MD0100PA00X+143405Y+060831X0200Y    R270 S0      
327GND              PC820 -2          A01X+143153Y+060831X0198Y0197     S1      
317GND              VIA   -    MD0100PA00X+143524Y+059380X0200Y         S0      
317GND              VIA   -    MD0100PA00X+144708Y+059019X0200Y    R090 S0      
317GND              VIA   -    MD0100PA00X+144249Y+059014X0200Y    R090 S0      
327GND              U85   -TH  M      A01X+144476Y+058785X0670Y0670R270 S1      
317GND              VIA   -    MD0100PA00X+145303Y+076903X0200Y         S0      
317GND              VIA   -    MD0100PA00X+145300Y+063905X0200Y         S0      
317GND              VIA   -    MD0100PA00X+145300Y+063625X0200Y         S0      
317GND              VIA   -    MD0100PA00X+145300Y+063345X0200Y         S0      
317GND              VIA   -    MD0100PA00X+145494Y+060544X0200Y    R090 S0      
327GND              R751  -2          A01X+145494Y+060280X0198Y0197R090 S1      
317GND              VIA   -    MD0100PA00X+147871Y+068563X0200Y         S0      
327GND              R4679 -2          A01X+148192Y+068563X0198Y0197R180 S1      
317GND              VIA   -    MD0100PA00X+147442Y+076008X0200Y         S0      
327GND              C3598 -2          A01X+147150Y+076008X0198Y0197R090 S1      
317GND              VIA   -    MD0100PA00X+147950Y+075050X0200Y    R180 S0      
327GND              R4656 -1          A01X+148192Y+075050X0198Y0197     S1      
317GND              VIA   -    MD0100PA00X+147142Y+074863X0200Y         S0      
317GND              VIA   -    MD0100PA00X+147996Y+072750X0200Y         S0      
327GND              R4616 -2          A01X+148242Y+072750X0198Y0197R180 S1      
317GND              VIA   -    MD0100PA00X+147442Y+071608X0200Y         S0      
327GND              C3599 -2          A01X+147150Y+071608X0198Y0197R090 S1      
317GND              VIA   -    MD0100PA00X+147950Y+070650X0200Y    R180 S0      
327GND              R4719 -1          A01X+148192Y+070650X0198Y0197     S1      
317GND              VIA   -    MD0100PA00X+147352Y+071005X0200Y         S0      
317GND              VIA   -    MD0100PA00X+149647Y+076900X0200Y         S0      
327GND              R4678 -2          A01X+149942Y+076900X0198Y0197R180 S1      
317GND              VIA   -    MD0100PA00X+151205Y+052692X0200Y    R090 S0      
317GND              VIA   -    MD0100PA00X+150705Y+053187X0200Y    R270 S0      
317GND              VIA   -    MD0100PA00X+151205Y+053187X0200Y    R090 S0      
317GND              VIA   -    MD0100PA00X+150705Y+052692X0200Y    R270 S0      
317GND              VIA   -    MD0100PA00X+151196Y+053638X0200Y         S0      
327GND              C949  -2          A01X+151422Y+053878X0198Y0197R270 S1      
327GND              C944  -2          A01X+151023Y+053882X0198Y0197R270 S1      
317GND              VIA   -    MD0100PA00X+151205Y+051274X0200Y    R090 S0      
317GND              VIA   -    MD0100PA00X+150705Y+051274X0200Y    R270 S0      
317GND              VIA   -    MD0100PA00X+151205Y+051770X0200Y    R090 S0      
317GND              VIA   -    MD0100PA00X+150705Y+051770X0200Y    R270 S0      
317GND              VIA   -    MD0100PA00X+151205Y+048774X0200Y    R090 S0      
317GND              VIA   -    MD0100PA00X+150705Y+048774X0200Y    R270 S0      
317GND              VIA   -    MD0100PA00X+152864Y+055523X0200Y         S0      
327GND              R338  -2          A01X+152552Y+055856X0198Y0197     S1      
327GND              R340  -2   M      A01X+152552Y+055456X0198Y0197     S1      
317GND              VIA   -    MD0100PA00X+152245Y+052481X0200Y    R090 S0      
317GND              VIA   -    MD0100PA00X+152245Y+053403X0200Y    R090 S0      
317GND              VIA   -    MD0100PA00X+151746Y+053403X0200Y    R270 S0      
317GND              VIA   -    MD0100PA00X+151746Y+052481X0200Y    R270 S0      
317GND              VIA   -    MD0100PA00X+151746Y+053898X0200Y    R270 S0      
317GND              VIA   -    MD0100PA00X+152245Y+053898X0200Y    R090 S0      
317GND              VIA   -    MD0100PA00X+152245Y+051986X0200Y    R090 S0      
317GND              VIA   -    MD0100PA00X+151746Y+051986X0200Y    R270 S0      
317GND              VIA   -    MD0100PA00X+152245Y+049485X0200Y    R090 S0      
317GND              VIA   -    MD0100PA00X+151746Y+049485X0200Y    R270 S0      
317GND              VIA   -    MD0100PA00X+152245Y+048990X0200Y    R090 S0      
317GND              VIA   -    MD0100PA00X+151746Y+048990X0200Y    R270 S0      
317GND              VIA   -    MD0100PA00X+152365Y+063495X0200Y         S0      
327GND              R328  -2          A01X+152168Y+063797X0198Y0197R180 S1      
327GND              R329  -2          A01X+152484Y+063142X0198Y0197     S1      
317GND              VIA   -    MD0100PA00X+151915Y+060759X0200Y         S0      
327GND              R332  -2          A01X+152165Y+060759X0198Y0197R180 S1      
317GND              VIA   -    M      A01X+151918Y+061560X0200Y         S2      
017GND              VIA   -    M      A18X+151918Y+061560X0260Y         S2      
017GND                    -    MD0100PA00X+151918Y+061560                       
327GND              R320  -2          A01X+152168Y+061160X0198Y0197R180 S1      
327GND              R319  -2   M      A01X+152168Y+061560X0198Y0197R180 S1      
317GND              VIA   -    MD0100PA00X+151693Y+059758X0200Y         S0      
317GND              VIA   -    MD0100PA00X+151915Y+059959X0200Y         S0      
317GND              VIA   -    MD0100PA00X+151842Y+058956X0200Y         S0      
317GND              VIA   -    MD0100PA00X+151835Y+059235X0200Y         S0      
317GND              VIA   -    MD0100PA00X+151687Y+059467X0200Y         S0      
317GND              VIA   -    MD0100PA00X+151916Y+059610X0200Y         S0      
317GND              VIA   -    MD0100PA00X+152835Y+056200X0200Y         S0      
327GND              R336  -2          A01X+152556Y+056257X0198Y0197     S1      
327GND              J26   -B67 M      A01X+155253Y+038915X0140Y0480R270 S1      
317GND              VIA   -    M      A01X+156513Y+067784X0200Y         S2      
017GND              VIA   -    M      A18X+156513Y+067784X0260Y         S2      
017GND                    -    MD0100PA00X+156513Y+067784                       
317GND              VIA   -    MD0100PA00X+156154Y+065316X0200Y         S0      
327GND              U40   -3          A01X+155811Y+065316X0160Y0360R270 S1      
317GND              VIA   -    MD0100PA00X+156238Y+060640X0200Y    R180 S0      
327GND              R327  -2          A18X+156478Y+060640X0198Y0197     S2      
317GND              VIA   -    MD0100PA00X+156238Y+061440X0200Y    R180 S0      
327GND              R334  -2          A18X+156478Y+061440X0198Y0197     S2      
317GND              VIA   -    MD0100PA00X+154837Y+059511X0200Y         S0      
327GND              J26   -OB13       A01X+155253Y+059512X0140Y0480R270 S1      
317GND              VIA   -    MD0100PA00X+156238Y+059440X0200Y    R180 S0      
327GND              R326  -2          A18X+156478Y+059440X0198Y0197     S2      
317GND              VIA   -    MD0100PA00X+156238Y+060240X0200Y    R180 S0      
327GND              R325  -2          A18X+156478Y+060240X0198Y0197     S2      
317GND              VIA   -    MD0100PA00X+156238Y+059840X0200Y    R180 S0      
327GND              R324  -2          A18X+156478Y+059840X0198Y0197     S2      
317GND              VIA   -    MD0100PA00X+154791Y+060220X0200Y         S0      
327GND              J26   -OB10       A01X+155253Y+060220X0140Y0480R270 S1      
317GND              VIA   -    MD0100PA00X+155690Y+057410X0200Y         S0      
317GND              VIA   -    MD0100PA00X+155813Y+056068X0200Y         S0      
317GND              VIA   -    MD0100PA00X+155867Y+057233X0200Y         S0      
317GND              VIA   -    MD0100PA00X+155636Y+056244X0200Y         S0      
317GND              VIA   -    MD0100PA00X+155704Y+055012X0200Y         S0      
317GND              VIA   -    MD0100PA00X+155691Y+055287X0200Y         S0      
317GND              VIA   -    MD0100PA00X+154863Y+054711X0200Y         S0      
327GND              J26   -B13        A01X+155253Y+054711X0140Y0480R270 S1      
317GND              VIA   -    MD0100PA00X+155643Y+052585X0200Y    R180 S0      
317GND              VIA   -    MD0100PA00X+154863Y+053293X0200Y         S0      
327GND              J26   -B19        A01X+155253Y+053293X0140Y0480R270 S1      
317GND              VIA   -    MD0100PA00X+154863Y+052585X0200Y         S0      
327GND              J26   -B22 M      A01X+155253Y+052585X0140Y0480R270 S1      
317GND              VIA   -    MD0100PA00X+154863Y+054002X0200Y         S0      
317GND              VIA   -    MD0100PA00X+155643Y+051167X0200Y    R180 S0      
317GND              VIA   -    MD0100PA00X+155643Y+051876X0200Y    R180 S0      
317GND              VIA   -    MD0100PA00X+156209Y+051684X0200Y         S0      
317GND              VIA   -    MD0100PA00X+154863Y+051876X0200Y         S0      
327GND              J26   -B25 M      A01X+155253Y+051876X0140Y0480R270 S1      
317GND              VIA   -    MD0100PA00X+154863Y+051167X0200Y         S0      
327GND              J26   -B28 M      A01X+155253Y+051167X0140Y0480R270 S1      
317GND              VIA   -    MD0100PA00X+155864Y+049883X0200Y    R180 S0      
317GND              VIA   -    MD0100PA00X+154863Y+049589X0200Y         S0      
327GND              J26   -B29 M      A01X+155253Y+049589X0140Y0480R270 S1      
327GND              J26   -B35 M      A01X+155253Y+048171X0140Y0480R270 S1      
317GND              VIA   -    MD0100PA00X+154863Y+048880X0200Y         S0      
327GND              J26   -B32        A01X+155253Y+048880X0140Y0480R270 S1      
327GND              J26   -B38 M      A01X+155253Y+047463X0140Y0480R270 S1      
327GND              J26   -B41 M      A01X+155253Y+046754X0140Y0480R270 S1      
327GND              J26   -B43 M      A01X+155253Y+044585X0140Y0480R270 S1      
327GND              J26   -B46        A01X+155253Y+043876X0140Y0480R270 S1      
327GND              J26   -B49        A01X+155253Y+043167X0140Y0480R270 S1      
327GND              J26   -B58 M      A01X+155253Y+041041X0140Y0480R270 S1      
327GND              J26   -B55        A01X+155253Y+041750X0140Y0480R270 S1      
327GND              J26   -B52 M      A01X+155253Y+042459X0140Y0480R270 S1      
327GND              J26   -B61 M      A01X+155253Y+040333X0140Y0480R270 S1      
327GND              J26   -B64 M      A01X+155253Y+039624X0140Y0480R270 S1      
327GND              J26   -A38 M      A01X+157064Y+047463X0140Y0480R270 S1      
327GND              J26   -A41 M      A01X+157064Y+046754X0140Y0480R270 S1      
327GND              J26   -A43 M      A01X+157064Y+044585X0140Y0480R270 S1      
327GND              J26   -A46 M      A01X+157064Y+043876X0140Y0480R270 S1      
327GND              J26   -A49 M      A01X+157064Y+043167X0140Y0480R270 S1      
327GND              J26   -A55 M      A01X+157064Y+041750X0140Y0480R270 S1      
327GND              J26   -A52 M      A01X+157064Y+042459X0140Y0480R270 S1      
327GND              J26   -A64 M      A01X+157064Y+039624X0140Y0480R270 S1      
327GND              J26   -A61        A01X+157064Y+040333X0140Y0480R270 S1      
327GND              J26   -A58        A01X+157064Y+041041X0140Y0480R270 S1      
327GND              J26   -A67 M      A01X+157064Y+038915X0140Y0480R270 S1      
317GND              VIA   -    MD0100PA00X+157594Y+070504X0200Y         S0      
327GND              Q7    -1          A01X+157594Y+070228X0170Y0240R180 S1      
317GND              VIA   -    MD0100PA00X+157033Y+069185X0200Y         S0      
327GND              Q7    -4          A01X+157082Y+069480X0170Y0240R180 S1      
317GND              VIA   -    MD0100PA00X+157595Y+066298X0200Y         S0      
327GND              C619  -2          A01X+157529Y+066040X0198Y0197     S1      
317GND              VIA   -    MD0100PA00X+156993Y+066888X0200Y         S0      
327GND              C948  -2          A01X+156993Y+066628X0198Y0197R180 S1      
317GND              VIA   -    MD0100PA00X+157422Y+062987X0200Y         S0      
317GND              VIA   -    MD0100PA00X+157811Y+060756X0200Y    R090 S0      
317GND              VIA   -    MD0100PA00X+157868Y+061305X0200Y    R090 S0      
317GND              VIA   -    MD0100PA00X+157975Y+059910X0200Y    R090 S0      
317GND              VIA   -    MD0100PA00X+157454Y+059512X0200Y    R180 S0      
327GND              J26   -OA13       A01X+157064Y+059512X0140Y0480R270 S1      
317GND              VIA   -    MD0100PA00X+157454Y+060220X0200Y    R180 S0      
327GND              J26   -OA10       A01X+157064Y+060220X0140Y0480R270 S1      
317GND              VIA   -    MD0100PA00X+157500Y+057541X0200Y    R090 S0      
317GND              VIA   -    MD0100PA00X+157500Y+057291X0200Y    R090 S0      
317GND              VIA   -    MD0100PA00X+157500Y+057041X0200Y    R090 S0      
317GND              VIA   -    MD0100PA00X+157500Y+056791X0200Y    R090 S0      
317GND              VIA   -    MD0100PA00X+157500Y+056541X0200Y    R090 S0      
317GND              VIA   -    MD0100PA00X+157454Y+055419X0200Y    R180 S0      
327GND              J26   -A10        A01X+157064Y+055419X0140Y0480R270 S1      
327GND              J26   -A13        A01X+157064Y+054711X0140Y0480R270 S1      
317GND              VIA   -    MD0100PA00X+157454Y+054711X0200Y    R180 S0      
327GND              R330  -2          A18X+157222Y+054497X0198Y0197R180 S2      
317GND              VIA   -    MD0100PA00X+157454Y+053293X0200Y    R180 S0      
327GND              J26   -A19        A01X+157064Y+053293X0140Y0480R270 S1      
317GND              VIA   -    MD0100PA00X+157454Y+052585X0200Y    R180 S0      
327GND              J26   -A22        A01X+157064Y+052585X0140Y0480R270 S1      
317GND              VIA   -    MD0100PA00X+157934Y+052585X0200Y         S0      
317GND              VIA   -    MD0100PA00X+157934Y+053293X0200Y         S0      
317GND              VIA   -    MD0100PA00X+157934Y+054002X0200Y         S0      
327GND              J26   -A16        A01X+157064Y+054002X0140Y0480R270 S1      
317GND              VIA   -    MD0100PA00X+157454Y+054002X0200Y    R180 S0      
317GND              VIA   -    MD0100PA00X+156505Y+051167X0200Y         S0      
317GND              VIA   -    MD0100PA00X+157454Y+051876X0200Y    R180 S0      
327GND              J26   -A25 M      A01X+157064Y+051876X0140Y0480R270 S1      
317GND              VIA   -    MD0100PA00X+157454Y+051167X0200Y    R180 S0      
327GND              J26   -A28 M      A01X+157064Y+051167X0140Y0480R270 S1      
317GND              VIA   -    MD0100PA00X+157934Y+051876X0200Y         S0      
317GND              VIA   -    MD0100PA00X+156674Y+049589X0200Y         S0      
317GND              VIA   -    MD0100PA00X+157454Y+049589X0200Y    R180 S0      
327GND              J26   -A29 M      A01X+157064Y+049589X0140Y0480R270 S1      
317GND              VIA   -    MD0100PA00X+157934Y+049589X0200Y         S0      
317GND              VIA   -    MD0100PA00X+156622Y+048771X0200Y         S0      
327GND              J26   -A35 M      A01X+157064Y+048171X0140Y0480R270 S1      
317GND              VIA   -    MD0100PA00X+157454Y+048880X0200Y    R180 S0      
327GND              J26   -A32 M      A01X+157064Y+048880X0140Y0480R270 S1      
317GND              VIA   -    MD0100PA00X+157934Y+048880X0200Y         S0      
317GND              VIA   -    MD0100PA00X+158372Y+056050X0200Y         S0      
327GND              U38   -3          A18X+158372Y+055780X0240Y0240R180 S2      
317GND              VIA   -    MD0100PA00X+159576Y+055500X0200Y         S0      
317GND              VIA   -    MD0100PA00X+159518Y+054392X0200Y         S0      
327GND              C947  -2          A18X+159176Y+054392X0198Y0197R090 S2      
317GND              VIA   -    MD0100PA00X+158184Y+052585X0200Y         S0      
317GND              VIA   -    MD0100PA00X+158184Y+053293X0200Y         S0      
317GND              VIA   -    MD0100PA00X+158664Y+053293X0200Y         S0      
317GND              VIA   -    MD0100PA00X+158664Y+052585X0200Y         S0      
317GND              VIA   -    MD0100PA00X+158664Y+051876X0200Y         S0      
317GND              VIA   -    MD0100PA00X+158664Y+051167X0200Y         S0      
317GND              VIA   -    MD0100PA00X+158184Y+051167X0200Y         S0      
317GND              VIA   -    MD0100PA00X+158184Y+051876X0200Y         S0      
317GND              VIA   -    MD0100PA00X+158664Y+048880X0200Y         S0      
317GND              VIA   -    MD0100PA00X+158184Y+048880X0200Y         S0      
317GND              VIA   -    MD0100PA00X+162556Y+058093X0200Y         S0      
317GND              VIA   -    MD0100PA00X+162556Y+057384X0200Y         S0      
317GND              VIA   -    MD0100PA00X+162556Y+058801X0200Y         S0      
317GND              VIA   -    MD0100PA00X+162556Y+056675X0200Y         S0      
317GND              VIA   -    MD0100PA00X+162556Y+053089X0200Y         S0      
317GND              VIA   -    MD0100PA00X+162556Y+053797X0200Y         S0      
317GND              VIA   -    MD0100PA00X+162556Y+051671X0200Y         S0      
317GND              VIA   -    MD0100PA00X+162556Y+052380X0200Y         S0      
317GND              VIA   -    MD0100PA00X+162556Y+049384X0200Y         S0      
317GND              VIA   -    M      A01X+161434Y+063684X0200Y         S2      
017GND              VIA   -    M      A18X+161434Y+063684X0260Y         S2      
017GND                    -    MD0100PA00X+161434Y+063684                       
317GND              VIA   -    MD0100PA00X+161311Y+067846X0200Y         S0      
327GND              C943  -2          A01X+161311Y+067583X0198Y0197R180 S1      
317GND              VIA   -    M      A01X+161784Y+066514X0200Y         S2      
017GND              VIA   -    M      A18X+161784Y+066514X0260Y         S2      
017GND                    -    MD0100PA00X+161784Y+066514                       
327GND              U42   -3          A01X+161784Y+066111X0400Y0500R180 S1      
317GND              VIA   -    MD0100PA00X+162024Y+063812X0200Y         S0      
327GND              Q122  -4          A01X+162024Y+064087X0240Y0240     S1      
317GND              VIA   -    MD0100PA00X+162556Y+061636X0200Y         S0      
317GND              VIA   -    MD0100PA00X+162556Y+060927X0200Y         S0      
317GND              VIA   -    MD0100PA00X+162556Y+059510X0200Y         S0      
317GND              VIA   -    MD0100PA00X+162556Y+060219X0200Y         S0      
317GND              VIA   -    MD0100PA00X+163036Y+053797X0200Y         S0      
317GND              VIA   -    MD0100PA00X+163766Y+053797X0200Y         S0      
317GND              VIA   -    MD0100PA00X+163286Y+053089X0200Y         S0      
317GND              VIA   -    MD0100PA00X+163766Y+053089X0200Y         S0      
317GND              VIA   -    MD0100PA00X+163036Y+053089X0200Y         S0      
317GND              VIA   -    MD0100PA00X+163766Y+050963X0200Y         S0      
317GND              VIA   -    MD0100PA00X+163766Y+051671X0200Y         S0      
317GND              VIA   -    MD0100PA00X+163766Y+052380X0200Y         S0      
317GND              VIA   -    MD0100PA00X+163286Y+052380X0200Y         S0      
317GND              VIA   -    MD0100PA00X+163036Y+052380X0200Y         S0      
317GND              VIA   -    MD0100PA00X+163036Y+051671X0200Y         S0      
317GND              VIA   -    MD0100PA00X+163286Y+051671X0200Y         S0      
317GND              VIA   -    MD0100PA00X+163286Y+050963X0200Y         S0      
317GND              VIA   -    MD0100PA00X+163766Y+049384X0200Y         S0      
317GND              VIA   -    MD0100PA00X+163036Y+049384X0200Y         S0      
327GND              J27   -A13        A01X+164156Y+045841X0140Y0480R090 S1      
327GND              J27   -A10        A01X+164156Y+045132X0140Y0480R090 S1      
327GND              J27   -OA13       A01X+164156Y+041039X0140Y0480R090 S1      
327GND              J27   -OA10       A01X+164156Y+040331X0140Y0480R090 S1      
317GND              VIA   -    MD0100PA00X+163766Y+060927X0200Y         S0      
327GND              J27   -A64        A01X+164156Y+060927X0140Y0480R090 S1      
317GND              VIA   -    MD0100PA00X+163766Y+061636X0200Y         S0      
317GND              VIA   -    MD0100PA00X+163036Y+060927X0200Y         S0      
317GND              VIA   -    MD0100PA00X+163286Y+060927X0200Y         S0      
317GND              VIA   -    MD0100PA00X+163036Y+061636X0200Y         S0      
317GND              VIA   -    MD0100PA00X+163036Y+059510X0200Y         S0      
317GND              VIA   -    MD0100PA00X+163286Y+059510X0200Y         S0      
317GND              VIA   -    MD0100PA00X+163766Y+059510X0200Y         S0      
327GND              J27   -A58        A01X+164156Y+059510X0140Y0480R090 S1      
317GND              VIA   -    MD0100PA00X+163766Y+060218X0200Y         S0      
327GND              J27   -A61        A01X+164156Y+060218X0140Y0480R090 S1      
317GND              VIA   -    MD0100PA00X+163036Y+060219X0200Y         S0      
317GND              VIA   -    MD0100PA00X+163286Y+060218X0200Y         S0      
317GND              VIA   -    MD0100PA00X+163036Y+057384X0200Y         S0      
317GND              VIA   -    MD0100PA00X+163766Y+057384X0200Y         S0      
317GND              VIA   -    MD0100PA00X+163286Y+058801X0200Y         S0      
317GND              VIA   -    MD0100PA00X+163036Y+058801X0200Y         S0      
317GND              VIA   -    MD0100PA00X+163766Y+058801X0200Y         S0      
327GND              J27   -A55        A01X+164156Y+058801X0140Y0480R090 S1      
317GND              VIA   -    MD0100PA00X+163766Y+058093X0200Y         S0      
327GND              J27   -A52        A01X+164156Y+058092X0140Y0480R090 S1      
317GND              VIA   -    MD0100PA00X+163286Y+058093X0200Y         S0      
317GND              VIA   -    MD0100PA00X+163036Y+058093X0200Y         S0      
317GND              VIA   -    MD0100PA00X+163286Y+057384X0200Y         S0      
317GND              VIA   -    MD0100PA00X+163286Y+055966X0200Y         S0      
317GND              VIA   -    MD0100PA00X+163286Y+056675X0200Y         S0      
317GND              VIA   -    MD0100PA00X+163036Y+056675X0200Y         S0      
317GND              VIA   -    MD0100PA00X+163766Y+056675X0200Y         S0      
317GND              VIA   -    MD0100PA00X+163766Y+055966X0200Y         S0      
317GND              VIA   -    MD0100PA00X+165457Y+077170X0200Y         S0      
317GND              VIA   -    MD0100PA00X+165584Y+060812X0200Y         S0      
317GND              VIA   -    MD0100PA00X+164559Y+061636X0200Y    R180 S0      
327GND              J27   -A67 M      A01X+164156Y+061636X0140Y0480R090 S1      
317GND              VIA   -    MD0100PA00X+165578Y+057384X0200Y         S0      
317GND              VIA   -    MD0100PA00X+165563Y+057998X0200Y         S0      
317GND              VIA   -    MD0100PA00X+164549Y+057434X0200Y    R180 S0      
327GND              J27   -A49 M      A01X+164156Y+057384X0140Y0480R090 S1      
317GND              VIA   -    MD0100PA00X+165578Y+056675X0200Y         S0      
317GND              VIA   -    MD0100PA00X+165578Y+055966X0200Y         S0      
317GND              VIA   -    MD0100PA00X+164585Y+056557X0200Y    R180 S0      
327GND              J27   -A46 M      A01X+164156Y+056675X0140Y0480R090 S1      
317GND              VIA   -    MD0100PA00X+164546Y+055966X0200Y    R180 S0      
327GND              J27   -A43 M      A01X+164156Y+055966X0140Y0480R090 S1      
317GND              VIA   -    MD0100PA00X+165464Y+053276X0200Y         S0      
317GND              VIA   -    MD0100PA00X+165472Y+052548X0200Y         S0      
317GND              VIA   -    MD0100PA00X+165224Y+053797X0200Y         S0      
317GND              VIA   -    MD0100PA00X+164672Y+052914X0200Y    R180 S0      
327GND              J27   -A38 M      A01X+164156Y+053089X0140Y0480R090 S1      
317GND              VIA   -    MD0100PA00X+164656Y+053568X0200Y    R180 S0      
327GND              J27   -A41 M      A01X+164156Y+053797X0140Y0480R090 S1      
317GND              VIA   -    MD0100PA00X+165578Y+051671X0200Y         S0      
317GND              VIA   -    MD0100PA00X+165578Y+050963X0200Y         S0      
317GND              VIA   -    MD0100PA00X+164546Y+050963X0200Y    R180 S0      
327GND              J27   -A29 M      A01X+164156Y+050963X0140Y0480R090 S1      
317GND              VIA   -    MD0100PA00X+164608Y+052213X0200Y    R180 S0      
327GND              J27   -A35 M      A01X+164156Y+052380X0140Y0480R090 S1      
317GND              VIA   -    MD0100PA00X+164616Y+051461X0200Y    R180 S0      
327GND              J27   -A32 M      A01X+164156Y+051671X0140Y0480R090 S1      
317GND              VIA   -    MD0100PA00X+165578Y+049384X0200Y         S0      
317GND              VIA   -    MD0100PA00X+164542Y+049509X0200Y    R180 S0      
327GND              J27   -A28 M      A01X+164156Y+049384X0140Y0480R090 S1      
317GND              VIA   -    MD0100PA00X+164561Y+048944X0200Y    R180 S0      
327GND              J27   -A25 M      A01X+164156Y+048675X0140Y0480R090 S1      
327GND              J27   -A22 M      A01X+164156Y+047966X0140Y0480R090 S1      
327GND              J27   -A16 M      A01X+164156Y+046549X0140Y0480R090 S1      
327GND              J27   -A19 M      A01X+164156Y+047258X0140Y0480R090 S1      
317GND              VIA   -    MD0100PA00X+166358Y+057384X0200Y    R180 S0      
327GND              J27   -B49 M      A01X+165968Y+057384X0140Y0480R090 S1      
317GND              VIA   -    MD0100PA00X+166358Y+058801X0200Y    R180 S0      
327GND              J27   -B55        A01X+165968Y+058801X0140Y0480R090 S1      
317GND              VIA   -    MD0100PA00X+166358Y+058092X0200Y    R180 S0      
327GND              J27   -B52 M      A01X+165968Y+058092X0140Y0480R090 S1      
317GND              VIA   -    MD0100PA00X+166358Y+056675X0200Y    R180 S0      
327GND              J27   -B46 M      A01X+165968Y+056675X0140Y0480R090 S1      
317GND              VIA   -    MD0100PA00X+166358Y+055966X0200Y    R180 S0      
327GND              J27   -B43 M      A01X+165968Y+055966X0140Y0480R090 S1      
317GND              VIA   -    MD0100PA00X+166358Y+053089X0200Y    R180 S0      
327GND              J27   -B38 M      A01X+165968Y+053089X0140Y0480R090 S1      
317GND              VIA   -    MD0100PA00X+166358Y+053797X0200Y    R180 S0      
327GND              J27   -B41 M      A01X+165968Y+053797X0140Y0480R090 S1      
317GND              VIA   -    MD0100PA00X+166358Y+050963X0200Y    R180 S0      
327GND              J27   -B29 M      A01X+165968Y+050963X0140Y0480R090 S1      
317GND              VIA   -    MD0100PA00X+166358Y+051671X0200Y    R180 S0      
327GND              J27   -B32 M      A01X+165968Y+051671X0140Y0480R090 S1      
327GND              J27   -B35 M      A01X+165968Y+052380X0140Y0480R090 S1      
317GND              VIA   -    MD0100PA00X+166358Y+052380X0200Y    R180 S0      
317GND              VIA   -    MD0100PA00X+166358Y+049384X0200Y    R180 S0      
327GND              J27   -B28 M      A01X+165968Y+049384X0140Y0480R090 S1      
327GND              J27   -B22 M      A01X+165968Y+047966X0140Y0480R090 S1      
327GND              J27   -B25 M      A01X+165968Y+048675X0140Y0480R090 S1      
327GND              J27   -B19 M      A01X+165968Y+047258X0140Y0480R090 S1      
327GND              J27   -B16 M      A01X+165968Y+046549X0140Y0480R090 S1      
327GND              J27   -B13 M      A01X+165968Y+045841X0140Y0480R090 S1      
327GND              J27   -OB13       A01X+165968Y+041039X0140Y0480R090 S1      
327GND              J27   -OB10       A01X+165968Y+040331X0140Y0480R090 S1      
317GND              VIA   -    MD0100PA00X+166358Y+060927X0200Y    R180 S0      
327GND              J27   -B64 M      A01X+165968Y+060927X0140Y0480R090 S1      
317GND              VIA   -    MD0100PA00X+166358Y+061636X0200Y    R180 S0      
327GND              J27   -B67        A01X+165968Y+061636X0140Y0480R090 S1      
317GND              VIA   -    MD0100PA00X+166358Y+059510X0200Y    R180 S0      
327GND              J27   -B58        A01X+165968Y+059510X0140Y0480R090 S1      
317GND              VIA   -    MD0100PA00X+166358Y+060218X0200Y    R180 S0      
327GND              J27   -B61        A01X+165968Y+060218X0140Y0480R090 S1      
317GND              VIA   -    MD0100PA00X+168976Y+060818X0200Y    R270 S0      
317GND              VIA   -    MD0100PA00X+168976Y+059400X0200Y    R270 S0      
317GND              VIA   -    MD0100PA00X+168976Y+060322X0200Y    R270 S0      
317GND              VIA   -    MD0100PA00X+168976Y+057983X0200Y    R270 S0      
317GND              VIA   -    MD0100PA00X+168976Y+057487X0200Y    R270 S0      
317GND              VIA   -    MD0100PA00X+168976Y+058905X0200Y    R270 S0      
317GND              VIA   -    MD0100PA00X+168976Y+056070X0200Y    R270 S0      
317GND              VIA   -    MD0100PA00X+168976Y+056566X0200Y    R270 S0      
317GND              VIA   -    MD0100PA00X+168976Y+052979X0200Y    R270 S0      
317GND              VIA   -    MD0100PA00X+168976Y+052484X0200Y    R270 S0      
317GND              VIA   -    MD0100PA00X+168976Y+051066X0200Y    R270 S0      
317GND              VIA   -    MD0100PA00X+168976Y+051562X0200Y    R270 S0      
317GND              VIA   -    MD0100PA00X+170016Y+053195X0200Y    R270 S0      
317GND              VIA   -    MD0100PA00X+169475Y+052979X0200Y    R090 S0      
317GND              VIA   -    MD0100PA00X+169475Y+052484X0200Y    R090 S0      
317GND              VIA   -    MD0100PA00X+170515Y+053195X0200Y    R090 S0      
317GND              VIA   -    MD0100PA00X+170515Y+053690X0200Y    R090 S0      
317GND              VIA   -    MD0100PA00X+170016Y+053690X0200Y    R270 S0      
317GND              VIA   -    MD0100PA00X+170016Y+052273X0200Y    R270 S0      
317GND              VIA   -    MD0100PA00X+170016Y+051777X0200Y    R270 S0      
317GND              VIA   -    MD0100PA00X+169475Y+051562X0200Y    R090 S0      
317GND              VIA   -    MD0100PA00X+169475Y+051066X0200Y    R090 S0      
317GND              VIA   -    MD0100PA00X+170515Y+052273X0200Y    R090 S0      
317GND              VIA   -    MD0100PA00X+170515Y+051777X0200Y    R090 S0      
317GND              VIA   -    MD0100PA00X+170515Y+049277X0200Y    R090 S0      
317GND              VIA   -    MD0100PA00X+170016Y+049277X0200Y    R270 S0      
317GND              VIA   -    MD0100PA00X+170016Y+048781X0200Y    R270 S0      
317GND              VIA   -    MD0100PA00X+170515Y+048781X0200Y    R090 S0      
317GND              VIA   -    MD0100PA00X+170515Y+061033X0200Y    R090 S0      
317GND              VIA   -    MD0100PA00X+170016Y+061529X0200Y    R270 S0      
317GND              VIA   -    MD0100PA00X+169475Y+060818X0200Y    R090 S0      
317GND              VIA   -    MD0100PA00X+170016Y+061033X0200Y    R270 S0      
317GND              VIA   -    MD0100PA00X+170515Y+061529X0200Y    R090 S0      
317GND              VIA   -    MD0100PA00X+169475Y+059400X0200Y    R090 S0      
317GND              VIA   -    MD0100PA00X+170016Y+059616X0200Y    R270 S0      
317GND              VIA   -    MD0100PA00X+170515Y+059616X0200Y    R090 S0      
317GND              VIA   -    MD0100PA00X+170515Y+060112X0200Y    R090 S0      
317GND              VIA   -    MD0100PA00X+170016Y+060112X0200Y    R270 S0      
317GND              VIA   -    MD0100PA00X+169475Y+060322X0200Y    R090 S0      
317GND              VIA   -    MD0100PA00X+169475Y+057487X0200Y    R090 S0      
317GND              VIA   -    MD0100PA00X+170016Y+058199X0200Y    R270 S0      
317GND              VIA   -    MD0100PA00X+170016Y+058694X0200Y    R270 S0      
317GND              VIA   -    MD0100PA00X+169475Y+058905X0200Y    R090 S0      
317GND              VIA   -    MD0100PA00X+170515Y+058199X0200Y    R090 S0      
317GND              VIA   -    MD0100PA00X+170515Y+058694X0200Y    R090 S0      
317GND              VIA   -    MD0100PA00X+169475Y+057983X0200Y    R090 S0      
317GND              VIA   -    MD0100PA00X+169475Y+056070X0200Y    R090 S0      
317GND              VIA   -    MD0100PA00X+169475Y+056566X0200Y    R090 S0      
317GND              VIA   -    MD0100PA00X+170016Y+056781X0200Y    R270 S0      
317GND              VIA   -    MD0100PA00X+169884Y+056484X0200Y    R180 S0      
327GND              C4005 -2          A01X+171354Y+056529X0198Y0197R090 S1      
327GND              U44   -S   M      A01X+170020Y+056004X0400Y0560R180 S1      
317GND              VIA   -    MD0100PA00X+170515Y+056781X0200Y    R090 S0      
317GND              VIA   -    MD0100PA00X+170016Y+057277X0200Y    R270 S0      
317GND              VIA   -    MD0100PA00X+170515Y+057277X0200Y    R090 S0      
317GND              VIA   -    MD0100PA00X+172493Y+049612X0200Y    R090 S0      
317GND              VIA   -    MD0100PA00X+172493Y+049362X0200Y    R090 S0      
317GND              VIA   -    MD0100PA00X+172493Y+048862X0200Y    R090 S0      
317GND              VIA   -    MD0100PA00X+172493Y+049112X0200Y    R090 S0      
317GND              VIA   -    MD0100PA00X+173315Y+049626X0200Y    R090 S0      
317GND              VIA   -    MD0100PA00X+173315Y+049376X0200Y    R090 S0      
317GND              VIA   -    MD0100PA00X+173054Y+049187X0200Y         S0      
317GND              VIA   -    MD0100PA00X+172804Y+049187X0200Y         S0      
317GND              VIA   -    MD0100PA00X+173659Y+049007X0200Y    R090 S0      
317GND              VIA   -    MD0100PA00X+173659Y+048757X0200Y    R090 S0      
317GND              VIA   -    MD0100PA00X+175347Y+054270X0200Y         S0      
317GND              VIA   -    MD0100PA00X+176195Y+070683X0200Y         S0      
317GND              VIA   -    MD0100PA00X+176508Y+048738X0200Y    R090 S0      
327GND              C2884 -2          A01X+176250Y+048738X0198Y0197     S1      
317GND              VIA   -    MD0100PA00X+178460Y+056409X0200Y         S0      
317GND              VIA   -    MD0100PA00X+182298Y+076605X0200Y    R270 S0      
317GND              VIA   -    MD0100PA00X+182298Y+074605X0200Y    R270 S0      
317GND              VIA   -    MD0100PA00X+182298Y+072605X0200Y    R270 S0      
317GND              VIA   -    MD0100PA00X+182298Y+070605X0200Y    R270 S0      
317GND              VIA   -    MD0100PA00X+182298Y+068605X0200Y    R270 S0      
317GND              VIA   -    MD0100PA00X+182298Y+066605X0200Y    R270 S0      
317GND              VIA   -    MD0100PA00X+182298Y+064605X0200Y    R270 S0      
317GND              VIA   -    MD0100PA00X+182298Y+062605X0200Y    R270 S0      
317GND              VIA   -    MD0100PA00X+182298Y+060605X0200Y    R270 S0      
317GND              VIA   -    MD0100PA00X+182298Y+058605X0200Y    R270 S0      
317GND              VIA   -    MD0100PA00X+182298Y+056605X0200Y    R270 S0      
317GND              VIA   -    MD0100PA00X+182298Y+054605X0200Y    R270 S0      
317GND              VIA   -    MD0100PA00X+182298Y+052605X0200Y    R270 S0      
317GND              VIA   -    MD0100PA00X+182298Y+050605X0200Y    R270 S0      
317GND              VIA   -    MD0100PA00X+179870Y+071879X0200Y         S0      
317GND              VIA   -    MD0100PA00X+179315Y+066281X0200Y         S0      
327GND              Y4    -4   M      A01X+053794Y+076747X0480Y0560R090 S1      
317GND              J20   -G9  MD0440PA00X+020284Y+045549X0640Y         S3      
317GND              J20   -G8  MD0440PA00X+020284Y+058396X0640Y         S3      
317GND              J20   -G7  MD0440PA00X+017383Y+045549X0640Y         S3      
317GND              J20   -G6  MD0440PA00X+017383Y+058396X0640Y         S3      
317GND              J20   -G5  MD0440PA00X+019032Y+036876X0620Y1370R270 S3      
317GND              J20   -G4  MD0440PA00X+019032Y+045549X0640Y1370R270 S3      
317GND              J20   -G3  MD0440PA00X+019032Y+050376X0640Y1370R270 S3      
317GND              J20   -G2  MD0440PA00X+019032Y+058396X0640Y1370R270 S3      
317GND              J20   -G1  MD0440PA00X+019032Y+063675X0640Y1370R270 S3      
317GND              J21   -G9  MD0440PA00X+026684Y+055002X0640Y    R180 S3      
317GND              J21   -G8  MD0440PA00X+026684Y+042156X0640Y    R180 S3      
317GND              J21   -G7  MD0440PA00X+029586Y+055002X0640Y    R180 S3      
317GND              J21   -G6  MD0440PA00X+029586Y+042156X0640Y    R180 S3      
317GND              J21   -G5  MD0440PA00X+027936Y+063675X0620Y1370R090 S3      
317GND              J21   -G4  MD0440PA00X+027936Y+055002X0640Y1370R090 S3      
317GND              J21   -G3  MD0440PA00X+027936Y+050175X0640Y1370R090 S3      
317GND              J21   -G2  MD0440PA00X+027936Y+042156X0640Y1370R090 S3      
317GND              J21   -G1  MD0440PA00X+027936Y+036876X0640Y1370R090 S3      
317GND              J22   -G9  MD0440PA00X+065993Y+045549X0640Y         S3      
317GND              J22   -G8  MD0440PA00X+065993Y+058396X0640Y         S3      
317GND              J22   -G7  MD0440PA00X+063092Y+045549X0640Y         S3      
317GND              J22   -G6  MD0440PA00X+063092Y+058396X0640Y         S3      
317GND              J22   -G5  MD0440PA00X+064741Y+036876X0620Y1370R270 S3      
317GND              J22   -G4  MD0440PA00X+064741Y+045549X0640Y1370R270 S3      
317GND              J22   -G3  MD0440PA00X+064741Y+050376X0640Y1370R270 S3      
317GND              J22   -G2  MD0440PA00X+064741Y+058396X0640Y1370R270 S3      
317GND              J22   -G1  MD0440PA00X+064741Y+063675X0640Y1370R270 S3      
317GND              J23   -G9  MD0440PA00X+072393Y+055002X0640Y    R180 S3      
317GND              J23   -G8  MD0440PA00X+072393Y+042156X0640Y    R180 S3      
317GND              J23   -G7  MD0440PA00X+075294Y+055002X0640Y    R180 S3      
317GND              J23   -G6  MD0440PA00X+075294Y+042156X0640Y    R180 S3      
317GND              J23   -G5  MD0440PA00X+073645Y+063675X0620Y1370R090 S3      
317GND              J23   -G4  MD0440PA00X+073645Y+055002X0640Y1370R090 S3      
317GND              J23   -G3  MD0440PA00X+073645Y+050175X0640Y1370R090 S3      
317GND              J23   -G2  MD0440PA00X+073645Y+042156X0640Y1370R090 S3      
317GND              J23   -G1  MD0440PA00X+073645Y+036876X0640Y1370R090 S3      
317GND              J24   -G9  MD0440PA00X+111702Y+045549X0640Y         S3      
317GND              J24   -G8  MD0440PA00X+111702Y+058396X0640Y         S3      
317GND              J24   -G7  MD0440PA00X+108800Y+045549X0640Y         S3      
317GND              J24   -G6  MD0440PA00X+108800Y+058396X0640Y         S3      
317GND              J24   -G5  MD0440PA00X+110450Y+036876X0620Y1370R270 S3      
317GND              J24   -G4  MD0440PA00X+110450Y+045549X0640Y1370R270 S3      
317GND              J24   -G3  MD0440PA00X+110450Y+050376X0640Y1370R270 S3      
317GND              J24   -G2  MD0440PA00X+110450Y+058396X0640Y1370R270 S3      
317GND              J24   -G1  MD0440PA00X+110450Y+063675X0640Y1370R270 S3      
317GND              J25   -G9  MD0440PA00X+118101Y+055002X0640Y    R180 S3      
317GND              J25   -G8  MD0440PA00X+118101Y+042156X0640Y    R180 S3      
317GND              J25   -G7  MD0440PA00X+121003Y+055002X0640Y    R180 S3      
317GND              J25   -G6  MD0440PA00X+121003Y+042156X0640Y    R180 S3      
317GND              J25   -G5  MD0440PA00X+119353Y+063675X0620Y1370R090 S3      
317GND              J25   -G4  MD0440PA00X+119353Y+055002X0640Y1370R090 S3      
317GND              J25   -G3  MD0440PA00X+119353Y+050175X0640Y1370R090 S3      
317GND              J25   -G2  MD0440PA00X+119353Y+042156X0640Y1370R090 S3      
317GND              J25   -G1  MD0440PA00X+119353Y+036876X0640Y1370R090 S3      
317GND              J26   -G9  MD0440PA00X+157410Y+045549X0640Y         S3      
317GND              J26   -G8  MD0440PA00X+157410Y+058396X0640Y         S3      
317GND              J26   -G7  MD0440PA00X+154509Y+045549X0640Y         S3      
317GND              J26   -G6  MD0440PA00X+154509Y+058396X0640Y         S3      
317GND              J26   -G5  MD0440PA00X+156158Y+036876X0620Y1370R270 S3      
317GND              J26   -G4  MD0440PA00X+156158Y+045549X0640Y1370R270 S3      
317GND              J26   -G3  MD0440PA00X+156158Y+050376X0640Y1370R270 S3      
317GND              J26   -G2  MD0440PA00X+156158Y+058396X0640Y1370R270 S3      
317GND              J26   -G1  MD0440PA00X+156158Y+063675X0640Y1370R270 S3      
317GND              J27   -G9  MD0440PA00X+163810Y+055002X0640Y    R180 S3      
317GND              J27   -G8  MD0440PA00X+163810Y+042156X0640Y    R180 S3      
317GND              J27   -G7  MD0440PA00X+166712Y+055002X0640Y    R180 S3      
317GND              J27   -G6  MD0440PA00X+166712Y+042156X0640Y    R180 S3      
317GND              J27   -G5  MD0440PA00X+165062Y+063675X0620Y1370R090 S3      
317GND              J27   -G4  MD0440PA00X+165062Y+055002X0640Y1370R090 S3      
317GND              J27   -G3  MD0440PA00X+165062Y+050175X0640Y1370R090 S3      
317GND              J27   -G2  MD0440PA00X+165062Y+042156X0640Y1370R090 S3      
317GND              J27   -G1  MD0440PA00X+165062Y+036876X0640Y1370R090 S3      
327GND              PC594 -2          A01X+045354Y+047281X0198Y0197R180 S1      
327GND              PC596 -2   M      A01X+047969Y+047678X0198Y0197     S1      
327GND              PC597 -2          A01X+045354Y+046481X0198Y0197R180 S1      
327GND              PR6853-2   M      A01X+047969Y+047278X0198Y0197     S1      
327GND              PR6854-2   M      A01X+047969Y+046878X0198Y0197     S1      
317GND              VIA   -    MD0100PA00X+045114Y+047281X0200Y    R090 S0      
317GND              VIA   -    MD0100PA00X+045354Y+046196X0200Y    R090 S0      
317GND              VIA   -    MD0100PA00X+047105Y+046457X0200Y    R090 S0      
327GND              PU70  -3   M      A01X+047076Y+046855X0100Y0280R090 S1      
317GND              VIA   -    MD0100PA00X+047366Y+046722X0200Y    R090 S0      
317GND              VIA   -    MD0100PA00X+048219Y+046878X0200Y    R270 S0      
317GND              VIA   -    MD0100PA00X+048219Y+047278X0200Y    R270 S0      
317GND              VIA   -    MD0100PA00X+048219Y+047678X0200Y    R270 S0      
317GND              VIA   -    MD0100PA00X+005952Y+044887X0200Y         S0      
317GND              VIA   -    MD0100PA00X+005822Y+047304X0200Y    R180 S0      
317GND              VIA   -    MD0100PA00X+005776Y+043751X0200Y         S0      
317GND              VIA   -    MD0100PA00X+005494Y+044935X0200Y         S0      
317GND              VIA   -    MD0100PA00X+004860Y+045847X0200Y         S0      
317GND              VIA   -    MD0100PA00X+004269Y+045147X0200Y         S0      
317GND              VIA   -    MD0100PA00X+006622Y+047304X0200Y    R180 S0      
317GND              VIA   -    MD0100PA00X+006176Y+043751X0200Y         S0      
317GND              VIA   -    MD0100PA00X+006576Y+043751X0200Y         S0      
327GND              PC792 -2          A01X+080454Y+045233X0198Y0197R180 S1      
327GND              PC795 -2   M      A01X+083068Y+045631X0198Y0197     S1      
327GND              PC797 -2          A01X+080454Y+044433X0198Y0197R180 S1      
327GND              PR7012-2   M      A01X+083068Y+045231X0198Y0197     S1      
327GND              PR7014-2   M      A01X+083068Y+044831X0198Y0197     S1      
317GND              VIA   -    MD0100PA00X+082204Y+044409X0200Y    R090 S0      
317GND              VIA   -    MD0100PA00X+080454Y+044149X0200Y    R090 S0      
317GND              VIA   -    MD0100PA00X+082465Y+044674X0200Y    R090 S0      
327GND              PU102 -3   M      A01X+082175Y+044808X0100Y0280R090 S1      
317GND              VIA   -    MD0100PA00X+083318Y+044831X0200Y    R270 S0      
317GND              VIA   -    MD0100PA00X+083318Y+045231X0200Y    R270 S0      
317GND              VIA   -    MD0100PA00X+083318Y+045631X0200Y    R270 S0      
317GND              VIA   -    MD0100PA00X+080214Y+045233X0200Y    R090 S0      
317GND              VIA   -    MD0100PA00X+004926Y+088666X0200Y         S0      
317GND              VIA   -    MD0100PA00X+002660Y+087452X0200Y         S0      
317GND              VIA   -    MD0100PA00X+002684Y+092035X0200Y         S0      
317GND              VIA   -    MD0100PA00X+004792Y+094762X0200Y         S0      
317GND              VIA   -    MD0100PA00X+005718Y+098139X0200Y         S0      
317GND              VIA   -    MD0100PA00X+002413Y+095815X0200Y         S0      
317GND              VIA   -    MD0100PA00X+002537Y+098070X0200Y         S0      
317GND              VIA   -    MD0100PA00X+035808Y+092333X0200Y         S0      
317GND              VIA   -    MD0100PA00X+035802Y+091208X0200Y         S0      
317GND              VIA   -    MD0100PA00X+035796Y+089880X0200Y         S0      
317GND              VIA   -    MD0100PA00X+035809Y+088462X0200Y         S0      
317GND              VIA   -    MD0100PA00X+035810Y+086746X0200Y         S0      
327GND              PC1010-2          A01X+178440Y+125078X0400Y0500     S1      
317GND              VIA   -    MD0100PA00X+057533Y+152374X0200Y         S0      
327GND              R6298 -2          A01X+057533Y+152622X0198Y0197     S1      
317GND              VIA   -    MD0100PA00X+040199Y+144681X0200Y         S0      
327GND              R6299 -2   M      A01X+040439Y+144681X0198Y0197R180 S1      
317GND              VIA   -    MD0100PA00X+024327Y+150190X0200Y         S0      
317GND              VIA   -    MD0100PA00X+024047Y+150386X0200Y         S0      
317GND              VIA   -    MD0100PA00X+094484Y+090240X0200Y         S0      
317GND              VIA   -    MD0100PA00X+095359Y+090281X0200Y         S0      
317GND              VIA   -    MD0100PA00X+094263Y+088652X0200Y         S0      
317GND              VIA   -    MD0100PA00X+095274Y+088662X0200Y         S0      
317GND              VIA   -    MD0100PA00X+095314Y+087424X0200Y         S0      
327GND              R6194 -1          A01X+095412Y+088000X0198Y0197R090 S1      
327GND              PC1009-2          A01X+094042Y+125029X0400Y0500     S1      
327GND              PC1008-2          A01X+087644Y+125029X0400Y0500     S1      
317GND              VIA   -    MD0100PA00X+159202Y+143306X0200Y         S0      
327GND              R6297 -2          A18X+156030Y+141881X0198Y0197R180 S2      
327GND              PC1007-2          A01X+003441Y+124120X0400Y0500     S1      
317GND              VIA   -    MD0100PA00X+045006Y+104314X0200Y         S0      
317GND              VIA   -    MD0100PA00X+044977Y+104705X0200Y         S0      
317GND              VIA   -    MD0100PA00X+092760Y+114771X0200Y         S0      
317GND              VIA   -    MD0100PA00X+092510Y+114771X0200Y         S0      
317GND              VIA   -    MD0100PA00X+001681Y+113870X0200Y         S0      
317GND              VIA   -    MD0100PA00X+001431Y+113870X0200Y         S0      
317GND              VIA   -    MD0100PA00X+005790Y+113369X0200Y         S0      
317GND              VIA   -    MD0100PA00X+005540Y+113369X0200Y         S0      
327GND              PC989 -2          A18X+005670Y+112969X0400Y0500     S2      
327GND              PC988 -2          A18X+005670Y+113769X0400Y0500     S2      
327GND              PC987 -2          A18X+001577Y+114270X0400Y0500R180 S2      
327GND              PC986 -2          A18X+001577Y+113470X0400Y0500R180 S2      
327GND              PC997 -2          A18X+092656Y+114371X0400Y0500R180 S2      
327GND              PC996 -2          A18X+092656Y+115171X0400Y0500R180 S2      
327GND              PC995 -2          A18X+096768Y+114917X0400Y0500     S2      
327GND              PC994 -2          A18X+096768Y+114117X0400Y0500     S2      
327GND              PC993 -2          A18X+090370Y+114917X0400Y0500     S2      
327GND              PC990 -2          A18X+090370Y+114117X0400Y0500     S2      
327GND              PC991 -2          A18X+086258Y+114408X0400Y0500R180 S2      
327GND              PC992 -2          A18X+086258Y+115208X0400Y0500R180 S2      
317GND              VIA   -    MD0100PA00X+090240Y+114517X0200Y    R090 S0      
317GND              VIA   -    MD0100PA00X+090490Y+114517X0200Y    R090 S0      
317GND              VIA   -    MD0100PA00X+086362Y+114808X0200Y         S0      
317GND              VIA   -    MD0100PA00X+086112Y+114808X0200Y         S0      
327GND              R1387 -1          A01X+127322Y+121842X0198Y0197R135 S1      
327GND              R1385 -1          A01X+127039Y+121559X0198Y0197R135 S1      
327GND              R1390 -1          A01X+126757Y+121276X0198Y0197R135 S1      
327GND              PR18  -2          A18X+142731Y+119837X0280Y0320     S2      
327GND              PC182 -2          A18X+141431Y+119897X0400Y0500R090 S2      
327GND              PC199 -2          A18X+140084Y+119897X0400Y0500R090 S2      
327GND              PR130 -2          A18X+138562Y+119747X0198Y0197R180 S2      
327GND              PR127 -2          A18X+136980Y+119747X0198Y0197     S2      
327GND              PR12  -2          A18X+135216Y+121211X0280Y0320R180 S2      
327GND              PC149 -2          A18X+134111Y+119897X0400Y0500R090 S2      
327GND              PC168 -2          A18X+132764Y+119897X0400Y0500R090 S2      
327GND              PC198 -2          A01X+144124Y+119897X0400Y0500R270 S1      
327GND              PC185 -2          A01X+142778Y+120826X0950Y1110R090 S1      
327GND              PC197 -2          A01X+141431Y+119897X0400Y0500R270 S1      
327GND              PC201 -2          A01X+140084Y+120826X0950Y1110R090 S1      
327GND              PC183 -2          A01X+138738Y+119897X0400Y0500R270 S1      
327GND              PC167 -2          A01X+136804Y+119897X0400Y0500R270 S1      
327GND              PC164 -2          A01X+134111Y+119897X0400Y0500R270 S1      
327GND              PC152 -2          A01X+135457Y+120826X0950Y1110R090 S1      
327GND              PC169 -2          A01X+132764Y+120826X0950Y1110R090 S1      
327GND              PC150 -2          A01X+131418Y+119897X0400Y0500R270 S1      
327GND              PC192 -2          A18X+142298Y+110290X0400Y0500R270 S2      
327GND              PC160 -2          A18X+135740Y+110290X0400Y0500R270 S2      
327GND              PC153 -2          A01X+134209Y+109877X0198Y0197R270 S1      
327GND              PC138 -2          A01X+132644Y+109883X0198Y0197     S1      
327GND              PC141 -2          A18X+132527Y+110290X0400Y0500R270 S2      
327GND              C2071 -2          A18X+135312Y+086609X0164Y0164R090 S2      
327GND              C2074 -2          A18X+134997Y+086609X0164Y0164R090 S2      
327GND              C2070 -2          A18X+134682Y+086609X0164Y0164R090 S2      
327GND              C2072 -2          A18X+134053Y+086609X0164Y0164R090 S2      
327GND              C2067 -2          A18X+134368Y+086609X0164Y0164R090 S2      
327GND              C2063 -2          A18X+135628Y+086294X0164Y0164R270 S2      
327GND              C2047 -2          A18X+135942Y+086294X0164Y0164R270 S2      
327GND              C2062 -2          A18X+135313Y+086294X0164Y0164R270 S2      
327GND              C2068 -2          A18X+134998Y+086294X0164Y0164R270 S2      
327GND              C2064 -2          A18X+134053Y+086294X0164Y0164R270 S2      
327GND              C2066 -2          A18X+134683Y+086294X0164Y0164R270 S2      
327GND              C2069 -2          A18X+134368Y+086294X0164Y0164R270 S2      
327GND              PC128 -2          A01X+137038Y+100218X0198Y0197R180 S1      
327GND              PC127 -2          A01X+136676Y+099677X0400Y0500     S1      
327GND              VIA   -           A18X+139046Y+101718X0260Y    R090 S2      
327GND              PC133 -2          A18X+138184Y+101457X0198Y0197R180 S2      
327GND              PC124 -2          A18X+137663Y+100732X0198Y0197R180 S2      
327GND              PC163 -2          A01X+137686Y+115518X0198Y0197R270 S1      
327GND              PC180 -2          A01X+138302Y+115518X0198Y0197R270 S1      
327GND              PC172 -2          A01X+138292Y+112297X0198Y0197R090 S1      
327GND              PC173 -2          A18X+138499Y+112475X0400Y0500R090 S2      
327GND              PC174 -2          A18X+139086Y+110290X0400Y0500R270 S2      
327GND              PC186 -2          A01X+140767Y+109877X0198Y0197R270 S1      
327GND              PC171 -2          A01X+139203Y+109883X0198Y0197     S1      
327GND              C2504 -1          A18X+146683Y+087919X0198Y0197R180 S2      
327GND              C2784 -1          A18X+146683Y+087519X0198Y0197R180 S2      
327GND              C3592 -2          A01X+146813Y+102766X0280Y0320R090 S1      
327GND              C3553 -2          A01X+148679Y+117871X0280Y0320R090 S1      
327GND              C3540 -2          A01X+148169Y+118083X0120Y0150R270 S1      
327GND              C3539 -2          A01X+147728Y+117980X0280Y0320R180 S1      
327GND              C3552 -2          A01X+148679Y+116611X0280Y0320R090 S1      
327GND              C3538 -2          A01X+148169Y+116823X0120Y0150R270 S1      
327GND              C3537 -2          A01X+147728Y+116720X0280Y0320R180 S1      
327GND              C3554 -2          A01X+148679Y+115351X0280Y0320R090 S1      
327GND              C3542 -2          A01X+148169Y+115563X0120Y0150R270 S1      
327GND              C3541 -2          A01X+147728Y+115460X0280Y0320R180 S1      
327GND              C3558 -2          A01X+148169Y+114303X0120Y0150R270 S1      
327GND              C3557 -2          A01X+147728Y+114200X0280Y0320R180 S1      
327GND              C3571 -2          A01X+148679Y+114091X0280Y0320R090 S1      
327GND              C3583 -2          A01X+148679Y+112831X0280Y0320R090 S1      
327GND              C3574 -2          A01X+148169Y+113043X0120Y0150R270 S1      
327GND              C3575 -2          A01X+147728Y+112940X0280Y0320R180 S1      
327GND              C3584 -2          A01X+148679Y+111571X0280Y0320R090 S1      
327GND              C3560 -2          A01X+148169Y+111783X0120Y0150R270 S1      
327GND              C3573 -2          A01X+147728Y+111680X0280Y0320R180 S1      
327GND              C3595 -2          A01X+148679Y+110311X0280Y0320R090 S1      
327GND              C3586 -2          A01X+148169Y+110523X0120Y0150R270 S1      
327GND              C3585 -2          A01X+147728Y+110420X0280Y0320R180 S1      
327GND              C3556 -2          A01X+149334Y+102509X0120Y0150R270 S1      
327GND              C3555 -2          A01X+148893Y+102406X0280Y0320R180 S1      
327GND              C3570 -2          A01X+149844Y+102297X0280Y0320R090 S1      
327GND              R1452 -1          A01X+172748Y+121559X0198Y0197R135 S1      
327GND              R1454 -1          A01X+173031Y+121842X0198Y0197R135 S1      
327GND              R1457 -1          A01X+172465Y+121276X0198Y0197R135 S1      
327GND              PC266 -2          A01X+180640Y+124528X0400Y0500R180 S1      
327GND              PC263 -2          A01X+178440Y+124388X0400Y0500     S1      
327GND              PC265 -2          A01X+180640Y+123148X0400Y0500R180 S1      
327GND              PC267 -2          A01X+180640Y+123838X0400Y0500R180 S1      
327GND              PC269 -2          A01X+178440Y+123698X0400Y0500     S1      
327GND              PC268 -2          A01X+178440Y+123008X0400Y0500     S1      
327GND              PC277 -2          A01X+178077Y+121126X0198Y0197R090 S1      
327GND              PC999 -2          A18X+181519Y+114891X0400Y0500     S2      
327GND              PC1001-2          A18X+177636Y+115182X0400Y0500R180 S2      
327GND              PC1000-2          A18X+177636Y+114382X0400Y0500R180 S2      
327GND              PC273 -2          A18X+181519Y+112859X0400Y0500     S2      
327GND              PC998 -2          A18X+181519Y+114091X0400Y0500     S2      
327GND              PC272 -2          A18X+177636Y+113512X0400Y0500R180 S2      
327GND              PC274 -2          A18X+181519Y+111959X0400Y0500     S2      
327GND              PC275 -2          A18X+177636Y+112612X0400Y0500R180 S2      
317GND              VIA   -    MD0100PA00X+107401Y+099786X0200Y         S0      
317GND              VIA   -    MD0100PA00X+111200Y+164498X0200Y         S0      
317GND              VIA   -    MD0100PA00X+109200Y+164498X0200Y         S0      
317GND              VIA   -    MD0100PA00X+107981Y+103439X0200Y         S0      
317GND              VIA   -    MD0100PA00X+110804Y+067784X0200Y         S0      
327GND              U31   -3          A01X+110804Y+068201X0220Y0530R180 S1      
317GND              VIA   -    MD0100PA00X+111886Y+070504X0200Y         S0      
327GND              Q5    -1          A01X+111886Y+070228X0170Y0240R180 S1      
317GND              VIA   -    MD0100PA00X+111324Y+069185X0200Y         S0      
327GND              Q5    -4          A01X+111374Y+069480X0170Y0240R180 S1      
317GND              VIA   -    MD0100PA00X+112964Y+148716X0200Y         S0      
317GND              VIA   -    MD0100PA00X+112964Y+149189X0200Y         S0      
317GND              VIA   -    MD0100PA00X+113830Y+149622X0200Y         S0      
317GND              VIA   -    MD0100PA00X+113830Y+148560X0200Y         S0      
317GND              VIA   -    MD0100PA00X+113830Y+149149X0200Y         S0      
317GND              VIA   -    MD0100PA00X+112964Y+149662X0200Y         S0      
317GND              VIA   -    MD0100PA00X+112964Y+147180X0200Y         S0      
317GND              VIA   -    MD0100PA00X+113830Y+148087X0200Y         S0      
317GND              VIA   -    MD0100PA00X+113830Y+147024X0200Y         S0      
317GND              VIA   -    MD0100PA00X+113830Y+147614X0200Y         S0      
317GND              VIA   -    MD0100PA00X+112964Y+148127X0200Y         S0      
317GND              VIA   -    MD0100PA00X+112964Y+147654X0200Y         S0      
317GND              VIA   -    MD0100PA00X+113830Y+146078X0200Y         S0      
317GND              VIA   -    MD0100PA00X+113830Y+146551X0200Y         S0      
317GND              VIA   -    MD0100PA00X+112964Y+145645X0200Y         S0      
317GND              VIA   -    MD0100PA00X+112964Y+146118X0200Y         S0      
317GND              VIA   -    MD0100PA00X+112964Y+146591X0200Y         S0      
317GND              VIA   -    MD0100PA00X+113830Y+158796X0200Y         S0      
317GND              VIA   -    MD0100PA00X+113830Y+159385X0200Y         S0      
317GND              VIA   -    MD0100PA00X+113830Y+158323X0200Y         S0      
317GND              VIA   -    MD0100PA00X+112964Y+158952X0200Y         S0      
317GND              VIA   -    MD0100PA00X+112964Y+159425X0200Y         S0      
317GND              VIA   -    MD0100PA00X+112964Y+158363X0200Y         S0      
317GND              VIA   -    MD0100PA00X+113830Y+157850X0200Y         S0      
317GND              VIA   -    MD0100PA00X+113830Y+156788X0200Y         S0      
317GND              VIA   -    MD0100PA00X+112964Y+157417X0200Y         S0      
317GND              VIA   -    MD0100PA00X+112964Y+157890X0200Y         S0      
317GND              VIA   -    MD0100PA00X+112964Y+156828X0200Y         S0      
317GND              VIA   -    MD0100PA00X+113830Y+157261X0200Y         S0      
317GND              VIA   -    MD0100PA00X+113830Y+156314X0200Y         S0      
317GND              VIA   -    MD0100PA00X+112964Y+155881X0200Y         S0      
317GND              VIA   -    MD0100PA00X+112964Y+156354X0200Y         S0      
317GND              VIA   -    MD0100PA00X+113830Y+151631X0200Y         S0      
317GND              VIA   -    MD0100PA00X+113830Y+150684X0200Y         S0      
317GND              VIA   -    MD0100PA00X+112964Y+151198X0200Y         S0      
317GND              VIA   -    MD0100PA00X+112964Y+150251X0200Y         S0      
317GND              VIA   -    MD0100PA00X+112964Y+150724X0200Y         S0      
317GND              VIA   -    MD0100PA00X+113830Y+151158X0200Y         S0      
317GND              VIA   -    MD0100PA00X+113830Y+150095X0200Y         S0      
317GND              VIA   -    MD0100PA00X+115251Y+084464X0200Y         S0      
317GND              VIA   -    MD0100PA00X+114698Y+081264X0200Y         S0      
327GND              R1044 -1          A18X+114591Y+081014X0198Y0197R180 S2      
317GND              VIA   -    MD0100PA00X+114963Y+081332X0200Y         S0      
317GND              VIA   -    MD0100PA00X+115128Y+079100X0200Y         S0      
327GND              C2110 -1          A18X+115244Y+078843X0198Y0197R180 S2      
317GND              VIA   -    MD0100PA00X+114591Y+079422X0200Y         S0      
327GND              R1043 -1          A18X+114591Y+079714X0198Y0197R180 S2      
317GND              VIA   -    MD0100PA00X+114934Y+077152X0200Y         S0      
317GND              VIA   -    MD0100PA00X+115232Y+074662X0200Y    R090 S0      
317GND              VIA   -    MD0100PA00X+114944Y+072854X0200Y    R090 S0      
317GND              VIA   -    MD0100PA00X+115602Y+067846X0200Y         S0      
327GND              C919  -2          A01X+115602Y+067583X0198Y0197R180 S1      
317GND              VIA   -    MD0100PA00X+113200Y+164498X0200Y         S0      
317GND              VIA   -    MD0100PA00X+113830Y+161867X0200Y         S0      
317GND              VIA   -    MD0100PA00X+113830Y+161394X0200Y         S0      
317GND              VIA   -    MD0100PA00X+112964Y+161434X0200Y         S0      
317GND              VIA   -    MD0100PA00X+113830Y+160921X0200Y         S0      
317GND              VIA   -    MD0100PA00X+112964Y+160488X0200Y         S0      
317GND              VIA   -    MD0100PA00X+112964Y+159898X0200Y         S0      
317GND              VIA   -    MD0100PA00X+112964Y+160961X0200Y         S0      
317GND              VIA   -    MD0100PA00X+113830Y+160332X0200Y         S0      
317GND              VIA   -    MD0100PA00X+113830Y+159858X0200Y         S0      
317GND              VIA   -    MD0100PA00X+114696Y+149662X0200Y         S0      
317GND              VIA   -    MD0100PA00X+114696Y+149189X0200Y         S0      
317GND              VIA   -    MD0100PA00X+114696Y+148716X0200Y         S0      
317GND              VIA   -    MD0100PA00X+115562Y+149622X0200Y         S0      
317GND              VIA   -    MD0100PA00X+115562Y+148560X0200Y         S0      
317GND              VIA   -    MD0100PA00X+115562Y+149149X0200Y         S0      
317GND              VIA   -    MD0100PA00X+115562Y+147024X0200Y         S0      
317GND              VIA   -    MD0100PA00X+115562Y+147614X0200Y         S0      
317GND              VIA   -    MD0100PA00X+114696Y+148127X0200Y         S0      
317GND              VIA   -    MD0100PA00X+114696Y+147654X0200Y         S0      
317GND              VIA   -    MD0100PA00X+114696Y+147180X0200Y         S0      
317GND              VIA   -    MD0100PA00X+115562Y+148087X0200Y         S0      
317GND              VIA   -    MD0100PA00X+114696Y+145645X0200Y         S0      
317GND              VIA   -    MD0100PA00X+115562Y+146078X0200Y         S0      
317GND              VIA   -    MD0100PA00X+115562Y+146551X0200Y         S0      
317GND              VIA   -    MD0100PA00X+114696Y+146118X0200Y         S0      
317GND              VIA   -    MD0100PA00X+114696Y+146591X0200Y         S0      
317GND              VIA   -    MD0100PA00X+115200Y+164498X0200Y         S0      
317GND              VIA   -    MD0100PA00X+115562Y+161867X0200Y         S0      
317GND              VIA   -    MD0100PA00X+115562Y+161394X0200Y         S0      
317GND              VIA   -    MD0100PA00X+114696Y+161434X0200Y         S0      
317GND              VIA   -    MD0100PA00X+115562Y+160332X0200Y         S0      
317GND              VIA   -    MD0100PA00X+115562Y+159858X0200Y         S0      
317GND              VIA   -    MD0100PA00X+115562Y+160921X0200Y         S0      
317GND              VIA   -    MD0100PA00X+114696Y+159898X0200Y         S0      
317GND              VIA   -    MD0100PA00X+114696Y+160488X0200Y         S0      
317GND              VIA   -    MD0100PA00X+114696Y+160961X0200Y         S0      
317GND              VIA   -    MD0100PA00X+114696Y+158952X0200Y         S0      
317GND              VIA   -    MD0100PA00X+115562Y+158323X0200Y         S0      
317GND              VIA   -    MD0100PA00X+114696Y+158363X0200Y         S0      
317GND              VIA   -    MD0100PA00X+115562Y+158796X0200Y         S0      
317GND              VIA   -    MD0100PA00X+115562Y+159385X0200Y         S0      
317GND              VIA   -    MD0100PA00X+114696Y+159425X0200Y         S0      
317GND              VIA   -    MD0100PA00X+115562Y+157850X0200Y         S0      
317GND              VIA   -    MD0100PA00X+114696Y+157890X0200Y         S0      
317GND              VIA   -    MD0100PA00X+114696Y+157417X0200Y         S0      
317GND              VIA   -    MD0100PA00X+115562Y+156788X0200Y         S0      
317GND              VIA   -    MD0100PA00X+114696Y+156828X0200Y         S0      
317GND              VIA   -    MD0100PA00X+115562Y+157261X0200Y         S0      
317GND              VIA   -    MD0100PA00X+114696Y+155881X0200Y         S0      
317GND              VIA   -    MD0100PA00X+115562Y+156314X0200Y         S0      
317GND              VIA   -    MD0100PA00X+114696Y+156354X0200Y         S0      
317GND              VIA   -    MD0100PA00X+115562Y+151631X0200Y         S0      
317GND              VIA   -    MD0100PA00X+114696Y+151198X0200Y         S0      
317GND              VIA   -    MD0100PA00X+115562Y+151158X0200Y         S0      
317GND              VIA   -    MD0100PA00X+115562Y+150095X0200Y         S0      
317GND              VIA   -    MD0100PA00X+115562Y+150684X0200Y         S0      
317GND              VIA   -    MD0100PA00X+114696Y+150251X0200Y         S0      
317GND              VIA   -    MD0100PA00X+114696Y+150724X0200Y         S0      
317GND              VIA   -    MD0100PA00X+116927Y+080080X0200Y    R090 S0      
317GND              VIA   -    MD0100PA00X+116052Y+080090X0200Y         S0      
317GND              VIA   -    MD0100PA00X+117370Y+079191X0200Y         S0      
317GND              VIA   -    MD0100PA00X+116129Y+079166X0200Y         S0      
327GND              R1042 -1          A18X+116020Y+079434X0198Y0197R270 S2      
317GND              VIA   -    MD0100PA00X+115798Y+079114X0200Y         S0      
327GND              U63   -10         A01X+115849Y+078629X0140Y0630R180 S1      
317GND              VIA   -    MD0100PA00X+116858Y+073381X0200Y    R090 S0      
317GND              VIA   -    MD0100PA00X+116375Y+071950X0200Y    R090 S0      
317GND              VIA   -    MD0100PA00X+117060Y+071528X0200Y    R090 S0      
317GND              VIA   -    MD0100PA00X+117294Y+149622X0200Y         S0      
317GND              VIA   -    MD0100PA00X+117294Y+148560X0200Y         S0      
317GND              VIA   -    MD0100PA00X+117294Y+149149X0200Y         S0      
317GND              VIA   -    MD0100PA00X+116428Y+149662X0200Y         S0      
317GND              VIA   -    MD0100PA00X+116428Y+149189X0200Y         S0      
317GND              VIA   -    MD0100PA00X+116428Y+148716X0200Y         S0      
317GND              VIA   -    MD0100PA00X+117294Y+147614X0200Y         S0      
317GND              VIA   -    MD0100PA00X+116428Y+148127X0200Y         S0      
317GND              VIA   -    MD0100PA00X+116428Y+147654X0200Y         S0      
317GND              VIA   -    MD0100PA00X+116428Y+147180X0200Y         S0      
317GND              VIA   -    MD0100PA00X+117294Y+148087X0200Y         S0      
317GND              VIA   -    MD0100PA00X+117294Y+147024X0200Y         S0      
317GND              VIA   -    MD0100PA00X+117294Y+146078X0200Y         S0      
317GND              VIA   -    MD0100PA00X+117294Y+146551X0200Y         S0      
317GND              VIA   -    MD0100PA00X+116428Y+146118X0200Y         S0      
317GND              VIA   -    MD0100PA00X+116428Y+145645X0200Y         S0      
317GND              VIA   -    MD0100PA00X+116428Y+146591X0200Y         S0      
317GND              VIA   -    MD0100PA00X+117294Y+158796X0200Y         S0      
317GND              VIA   -    MD0100PA00X+117294Y+159385X0200Y         S0      
317GND              VIA   -    MD0100PA00X+116428Y+159425X0200Y         S0      
317GND              VIA   -    MD0100PA00X+116428Y+158952X0200Y         S0      
317GND              VIA   -    MD0100PA00X+117294Y+158323X0200Y         S0      
317GND              VIA   -    MD0100PA00X+116428Y+158363X0200Y         S0      
317GND              VIA   -    MD0100PA00X+116428Y+156828X0200Y         S0      
317GND              VIA   -    MD0100PA00X+117294Y+157261X0200Y         S0      
317GND              VIA   -    MD0100PA00X+117294Y+157850X0200Y         S0      
317GND              VIA   -    MD0100PA00X+116428Y+157890X0200Y         S0      
317GND              VIA   -    MD0100PA00X+116428Y+157417X0200Y         S0      
317GND              VIA   -    MD0100PA00X+117294Y+156788X0200Y         S0      
317GND              VIA   -    MD0100PA00X+117294Y+156314X0200Y         S0      
317GND              VIA   -    MD0100PA00X+116428Y+156354X0200Y         S0      
317GND              VIA   -    MD0100PA00X+116428Y+155881X0200Y         S0      
317GND              VIA   -    MD0100PA00X+117294Y+151631X0200Y         S0      
317GND              VIA   -    MD0100PA00X+116428Y+151198X0200Y         S0      
317GND              VIA   -    MD0100PA00X+117294Y+151158X0200Y         S0      
317GND              VIA   -    MD0100PA00X+117294Y+150095X0200Y         S0      
317GND              VIA   -    MD0100PA00X+117294Y+150684X0200Y         S0      
317GND              VIA   -    MD0100PA00X+116428Y+150251X0200Y         S0      
317GND              VIA   -    MD0100PA00X+116428Y+150724X0200Y         S0      
317GND              VIA   -    MD0100PA00X+118720Y+096340X0200Y         S0      
327GND              U318  -4          A18X+118795Y+095960X0240Y0460R180 S2      
317GND              VIA   -    MD0100PA00X+118843Y+093657X0200Y    R090 S0      
317GND              VIA   -    MD0100PA00X+117800Y+093650X0200Y         S0      
327GND              R6174 -1          A18X+117719Y+093361X0198Y0197R090 S2      
317GND              VIA   -    MD0100PA00X+117848Y+091522X0200Y         S0      
317GND              VIA   -    MD0100PA00X+117658Y+088597X0200Y    R090 S0      
327GND              C2748 -1          A18X+117658Y+088890X0198Y0197R180 S2      
317GND              VIA   -    MD0100PA00X+117778Y+089405X0200Y         S0      
317GND              VIA   -    MD0100PA00X+118343Y+086834X0200Y         S0      
327GND              R6176 -1          A18X+118343Y+087124X0198Y0197R270 S2      
317GND              VIA   -    MD0100PA00X+118674Y+085547X0200Y         S0      
317GND              VIA   -    MD0100PA00X+118770Y+084973X0200Y         S0      
317GND              VIA   -    MD0100PA00X+119006Y+084438X0200Y         S0      
317GND              VIA   -    M      A01X+117757Y+077854X0200Y         S2      
017GND              VIA   -    M      A18X+117757Y+077854X0260Y         S2      
017GND                    -    MD0100PA00X+117757Y+077854                       
327GND              C2108 -1          A01X+118072Y+077889X0198Y0197R090 S1      
317GND              VIA   -    MD0100PA00X+117774Y+077174X0200Y         S0      
327GND              C2109 -1          A01X+117774Y+077443X0198Y0197R180 S1      
317GND              VIA   -    MD0100PA00X+117200Y+164498X0200Y         S0      
317GND              VIA   -    MD0100PA00X+117294Y+161867X0200Y         S0      
317GND              VIA   -    MD0100PA00X+117294Y+161394X0200Y         S0      
317GND              VIA   -    MD0100PA00X+116428Y+161434X0200Y         S0      
317GND              VIA   -    MD0100PA00X+117294Y+160921X0200Y         S0      
317GND              VIA   -    MD0100PA00X+116428Y+159898X0200Y         S0      
317GND              VIA   -    MD0100PA00X+116428Y+160488X0200Y         S0      
317GND              VIA   -    MD0100PA00X+116428Y+160961X0200Y         S0      
317GND              VIA   -    MD0100PA00X+117294Y+160332X0200Y         S0      
317GND              VIA   -    MD0100PA00X+117294Y+159858X0200Y         S0      
317GND              VIA   -    MD0100PA00X+118160Y+149662X0200Y         S0      
317GND              VIA   -    MD0100PA00X+118160Y+149189X0200Y         S0      
317GND              VIA   -    MD0100PA00X+118160Y+148716X0200Y         S0      
317GND              VIA   -    MD0100PA00X+118160Y+148127X0200Y         S0      
317GND              VIA   -    MD0100PA00X+118160Y+147654X0200Y         S0      
317GND              VIA   -    MD0100PA00X+118160Y+147180X0200Y         S0      
317GND              VIA   -    MD0100PA00X+118160Y+146118X0200Y         S0      
317GND              VIA   -    MD0100PA00X+118160Y+145645X0200Y         S0      
317GND              VIA   -    MD0100PA00X+118160Y+146591X0200Y         S0      
317GND              VIA   -    MD0100PA00X+118160Y+159425X0200Y         S0      
317GND              VIA   -    MD0100PA00X+118160Y+158952X0200Y         S0      
317GND              VIA   -    MD0100PA00X+118160Y+158363X0200Y         S0      
317GND              VIA   -    MD0100PA00X+118160Y+157890X0200Y         S0      
317GND              VIA   -    MD0100PA00X+118160Y+157417X0200Y         S0      
317GND              VIA   -    MD0100PA00X+118160Y+156828X0200Y         S0      
317GND              VIA   -    MD0100PA00X+118160Y+156354X0200Y         S0      
317GND              VIA   -    MD0100PA00X+118160Y+155881X0200Y         S0      
317GND              VIA   -    MD0100PA00X+118160Y+151198X0200Y         S0      
317GND              VIA   -    MD0100PA00X+118160Y+150251X0200Y         S0      
317GND              VIA   -    MD0100PA00X+118160Y+150724X0200Y         S0      
317GND              VIA   -    MD0100PA00X+120227Y+101355X0200Y         S0      
317GND              VIA   -    MD0100PA00X+120492Y+102186X0200Y         S0      
317GND              VIA   -    MD0100PA00X+119884Y+099850X0200Y         S0      
317GND              VIA   -    MD0100PA00X+120179Y+098529X0200Y    R270 S0      
327GND              C2780 -1          A18X+120129Y+098279X0198Y0197     S2      
317GND              VIA   -    MD0100PA00X+119962Y+095067X0200Y    R270 S0      
327GND              C2779 -1          A18X+120129Y+095379X0198Y0197     S2      
317GND              VIA   -    MD0100PA00X+119512Y+093630X0200Y    R090 S0      
327GND              R6175 -1          A18X+119512Y+093361X0198Y0197R090 S2      
317GND              VIA   -    MD0100PA00X+119299Y+091487X0200Y    R090 S0      
327GND              U309  -4          A18X+119299Y+091032X0140Y0520R180 S2      
317GND              VIA   -    MD0100PA00X+119900Y+079061X0200Y         S0      
317GND              VIA   -    MD0100PA00X+118160Y+161434X0200Y         S0      
317GND              VIA   -    MD0100PA00X+118160Y+160488X0200Y         S0      
317GND              VIA   -    MD0100PA00X+118160Y+160961X0200Y         S0      
317GND              VIA   -    MD0100PA00X+118160Y+159898X0200Y         S0      
317GND              VIA   -    MD0100PA00X+119893Y+156354X0200Y         S0      
317GND              VIA   -    MD0100PA00X+119027Y+156314X0200Y         S0      
317GND              VIA   -    MD0100PA00X+119893Y+155881X0200Y         S0      
317GND              VIA   -    MD0100PA00X+119027Y+151631X0200Y         S0      
317GND              VIA   -    MD0100PA00X+119893Y+151198X0200Y         S0      
317GND              VIA   -    MD0100PA00X+119893Y+150252X0200Y         S0      
317GND              VIA   -    MD0100PA00X+119893Y+150725X0200Y         S0      
317GND              VIA   -    MD0100PA00X+119027Y+151158X0200Y         S0      
317GND              VIA   -    MD0100PA00X+119027Y+150095X0200Y         S0      
317GND              VIA   -    MD0100PA00X+119027Y+150684X0200Y         S0      
317GND              VIA   -    MD0100PA00X+119027Y+149149X0200Y         S0      
317GND              VIA   -    MD0100PA00X+119893Y+149662X0200Y         S0      
317GND              VIA   -    MD0100PA00X+119893Y+148716X0200Y         S0      
317GND              VIA   -    MD0100PA00X+119893Y+149189X0200Y         S0      
317GND              VIA   -    MD0100PA00X+119027Y+149622X0200Y         S0      
317GND              VIA   -    MD0100PA00X+119027Y+148560X0200Y         S0      
317GND              VIA   -    MD0100PA00X+119893Y+147181X0200Y         S0      
317GND              VIA   -    MD0100PA00X+119893Y+147654X0200Y         S0      
317GND              VIA   -    MD0100PA00X+119027Y+148087X0200Y         S0      
317GND              VIA   -    MD0100PA00X+119027Y+147024X0200Y         S0      
317GND              VIA   -    MD0100PA00X+119027Y+147614X0200Y         S0      
317GND              VIA   -    MD0100PA00X+119893Y+148127X0200Y         S0      
317GND              VIA   -    MD0100PA00X+119893Y+146118X0200Y         S0      
317GND              VIA   -    MD0100PA00X+119893Y+145645X0200Y         S0      
317GND              VIA   -    MD0100PA00X+119893Y+146591X0200Y         S0      
317GND              VIA   -    MD0100PA00X+119027Y+146078X0200Y         S0      
317GND              VIA   -    MD0100PA00X+119027Y+146551X0200Y         S0      
317GND              VIA   -    MD0100PA00X+119200Y+164498X0200Y         S0      
317GND              VIA   -    MD0100PA00X+119893Y+161434X0200Y         S0      
317GND              VIA   -    MD0100PA00X+119027Y+161867X0200Y         S0      
317GND              VIA   -    MD0100PA00X+119027Y+161394X0200Y         S0      
317GND              VIA   -    MD0100PA00X+119893Y+160488X0200Y         S0      
317GND              VIA   -    MD0100PA00X+119893Y+159898X0200Y         S0      
317GND              VIA   -    MD0100PA00X+119893Y+160961X0200Y         S0      
317GND              VIA   -    MD0100PA00X+119027Y+160332X0200Y         S0      
317GND              VIA   -    MD0100PA00X+119027Y+159858X0200Y         S0      
317GND              VIA   -    MD0100PA00X+119027Y+160921X0200Y         S0      
317GND              VIA   -    MD0100PA00X+119893Y+158952X0200Y         S0      
317GND              VIA   -    MD0100PA00X+119893Y+159425X0200Y         S0      
317GND              VIA   -    MD0100PA00X+119027Y+158796X0200Y         S0      
317GND              VIA   -    MD0100PA00X+119027Y+159385X0200Y         S0      
317GND              VIA   -    MD0100PA00X+119893Y+158363X0200Y         S0      
317GND              VIA   -    MD0100PA00X+119027Y+158323X0200Y         S0      
317GND              VIA   -    MD0100PA00X+119893Y+157417X0200Y         S0      
317GND              VIA   -    MD0100PA00X+119893Y+157890X0200Y         S0      
317GND              VIA   -    MD0100PA00X+119027Y+157261X0200Y         S0      
317GND              VIA   -    MD0100PA00X+119027Y+157850X0200Y         S0      
317GND              VIA   -    MD0100PA00X+119893Y+156828X0200Y         S0      
317GND              VIA   -    MD0100PA00X+119027Y+156788X0200Y         S0      
327GND              R1380 -2          A18X+120562Y+118711X0198Y0197R270 S2      
327GND              R1381 -2          A18X+120562Y+117648X0198Y0197R090 S2      
317GND              VIA   -    MD0100PA00X+121200Y+164498X0200Y         S0      
317GND              VIA   -    MD0100PA00X+124872Y+102586X0200Y         S0      
317GND              VIA   -    MD0100PA00X+124920Y+101400X0200Y         S0      
317GND              VIA   -    MD0100PA00X+124680Y+100160X0200Y         S0      
317GND              VIA   -    MD0100PA00X+123200Y+164498X0200Y         S0      
317GND              VIA   -    MD0100PA00X+125874Y+118822X0200Y         S0      
317GND              VIA   -    MD0100PA00X+126457Y+119302X0200Y         S0      
327GND              R1383 -1          A01X+126457Y+119542X0198Y0197R090 S1      
317GND              VIA   -    MD0100PA00X+126857Y+119302X0200Y         S0      
327GND              R1384 -1          A01X+126857Y+119542X0198Y0197R090 S1      
317GND              VIA   -    MD0100PA00X+126671Y+116017X0200Y         S0      
317GND              VIA   -    MD0100PA00X+126988Y+113232X0200Y         S0      
317GND              VIA   -    MD0100PA00X+127052Y+090828X0200Y         S0      
327GND              Q113  -1          A01X+126779Y+090828X0240Y0240R270 S1      
317GND              VIA   -    M      A01X+127954Y+077658X0200Y         S2      
017GND              VIA   -    M      A18X+127954Y+077658X0260Y         S2      
017GND                    -    MD0100PA00X+127954Y+077658                       
327GND              R4245 -1          A01X+128194Y+077658X0198Y0197     S1      
317GND              VIA   -    MD0100PA00X+127954Y+077258X0200Y         S0      
327GND              R4244 -1          A01X+128194Y+077258X0198Y0197     S1      
317GND              VIA   -    MD0100PA00X+128420Y+121875X0200Y         S0      
327GND              R1382 -1          A01X+127888Y+122407X0198Y0197R135 S1      
317GND              VIA   -    M      A01X+127503Y+120959X0200Y         S2      
017GND              VIA   -    M      A18X+127503Y+120959X0260Y         S2      
017GND                    -    MD0100PA00X+127503Y+120959                       
317GND              VIA   -    MD0100PA00X+127940Y+121396X0200Y         S0      
317GND              VIA   -    MD0100PA00X+127711Y+121166X0200Y         S0      
317GND              VIA   -    MD0100PA00X+127257Y+119302X0200Y         S0      
327GND              R1386 -1          A01X+127257Y+119542X0198Y0197R090 S1      
317GND              VIA   -    MD0100PA00X+128057Y+119302X0200Y         S0      
327GND              R4182 -1          A01X+128057Y+119542X0198Y0197R090 S1      
317GND              VIA   -    MD0100PA00X+127657Y+119302X0200Y         S0      
327GND              R1389 -1          A01X+127657Y+119542X0198Y0197R090 S1      
317GND              VIA   -    MD0100PA00X+128031Y+116282X0200Y         S0      
327GND              C2782 -1          A01X+128031Y+116522X0198Y0197R090 S1      
317GND              VIA   -    MD0100PA00X+127212Y+115946X0200Y         S0      
317GND              VIA   -    MD0100PA00X+128283Y+114694X0200Y         S0      
317GND              VIA   -    MD0100PA00X+127386Y+113250X0200Y         S0      
317GND              VIA   -    MD0100PA00X+128402Y+094001X0200Y         S0      
317GND              VIA   -    MD0100PA00X+127704Y+091648X0200Y         S0      
327GND              C2841 -1          A01X+127792Y+091400X0198Y0197     S1      
317GND              VIA   -    MD0100PA00X+128549Y+089218X0200Y         S0      
327GND              R6178 -1          A01X+128792Y+088977X0198Y0197     S1      
327GND              R6177 -1          A01X+128466Y+089492X0198Y0197R090 S1      
317GND              VIA   -    M      A01X+130352Y+074840X0200Y         S2      
017GND              VIA   -    M      A18X+130352Y+074840X0260Y         S2      
017GND                    -    MD0100PA00X+130352Y+074840                       
327GND              U324  -12         A01X+129825Y+074801X0240Y0540R270 S1      
317GND              VIA   -    MD0100PA00X+129545Y+094095X0200Y         S0      
327GND              Q19   -4          A01X+129545Y+093804X0240Y0240     S1      
317GND              VIA   -    MD0100PA00X+129809Y+094085X0200Y         S0      
327GND              C2744 -2          A01X+130092Y+094250X0198Y0197R180 S1      
317GND              VIA   -    MD0100PA00X+128955Y+092805X0200Y         S0      
327GND              Q19   -1          A01X+128955Y+093096X0240Y0240     S1      
317GND              VIA   -    MD0100PA00X+129196Y+090130X0200Y         S0      
327GND              U336  -3          A01X+129106Y+090467X0160Y0360     S1      
317GND              VIA   -    MD0100PA00X+128232Y+088019X0200Y         S0      
317GND              VIA   -    MD0100PA00X+130009Y+085482X0200Y         S0      
327GND              C2078 -2          A18X+130277Y+085482X0164Y0164     S2      
317GND              VIA   -    MD0100PA00X+130010Y+085119X0200Y         S0      
327GND              C2077 -2          A18X+130278Y+085119X0164Y0164     S2      
317GND              VIA   -    MD0100PA00X+130020Y+085909X0200Y         S0      
327GND              C2082 -2          A18X+130288Y+085909X0164Y0164     S2      
317GND              VIA   -    MD0100PA00X+130050Y+083598X0200Y         S0      
327GND              C2053 -2          A18X+130318Y+083598X0164Y0164     S2      
317GND              VIA   -    MD0100PA00X+130052Y+083205X0200Y         S0      
317GND              VIA   -    MD0100PA00X+129007Y+080425X0200Y    R180 S0      
327GND              C2842 -2   M      A01X+129257Y+080425X0198Y0197R270 S1      
317GND              VIA   -    MD0100PA00X+131691Y+084247X0180Y         S0      
327GND              C2075 -2          A18X+131531Y+084092X0164Y0164     S2      
327GND              U6    -V2         A01X+131848Y+084404X0160Y         S1      
317GND              VIA   -    MD0100PA00X+131376Y+082987X0180Y         S0      
327GND              U6    -AB1        A01X+131533Y+083144X0160Y         S1      
317GND              VIA   -    MD0100PA00X+130513Y+081206X0200Y         S0      
317GND              VIA   -    MD0100PA00X+130541Y+079906X0200Y    R180 S0      
327GND              OSC1  -2   M      A01X+130541Y+080276X0400Y0480R090 S1      
317GND              VIA   -    MD0100PA00X+131900Y+072050X0200Y    R180 S0      
327GND              R4739 -2          A01X+132142Y+072050X0198Y0197R180 S1      
317GND              VIA   -    MD0100PA00X+131900Y+070450X0200Y    R180 S0      
327GND              R4740 -2          A01X+132142Y+070450X0198Y0197R180 S1      
317GND              VIA   -    MD0100PA00X+129200Y+164498X0200Y         S0      
317GND              VIA   -    MD0100PA00X+130287Y+161434X0200Y         S0      
317GND              VIA   -    MD0100PA00X+130287Y+160488X0200Y         S0      
317GND              VIA   -    MD0100PA00X+130287Y+159898X0200Y         S0      
317GND              VIA   -    MD0100PA00X+130287Y+160961X0200Y         S0      
317GND              VIA   -    MD0100PA00X+130287Y+158363X0200Y         S0      
317GND              VIA   -    MD0100PA00X+130287Y+158952X0200Y         S0      
317GND              VIA   -    MD0100PA00X+130287Y+159425X0200Y         S0      
317GND              VIA   -    MD0100PA00X+130287Y+156828X0200Y         S0      
317GND              VIA   -    MD0100PA00X+130287Y+157417X0200Y         S0      
317GND              VIA   -    MD0100PA00X+130287Y+157890X0200Y         S0      
317GND              VIA   -    MD0100PA00X+130287Y+156354X0200Y         S0      
317GND              VIA   -    MD0100PA00X+130287Y+155881X0200Y         S0      
317GND              VIA   -    MD0100PA00X+130287Y+151198X0200Y         S0      
317GND              VIA   -    MD0100PA00X+130287Y+150251X0200Y         S0      
317GND              VIA   -    MD0100PA00X+130287Y+150724X0200Y         S0      
317GND              VIA   -    MD0100PA00X+130287Y+149662X0200Y         S0      
317GND              VIA   -    MD0100PA00X+130287Y+148716X0200Y         S0      
317GND              VIA   -    MD0100PA00X+130287Y+149189X0200Y         S0      
317GND              VIA   -    MD0100PA00X+130287Y+148127X0200Y         S0      
317GND              VIA   -    MD0100PA00X+130287Y+147180X0200Y         S0      
317GND              VIA   -    MD0100PA00X+130287Y+147654X0200Y         S0      
317GND              VIA   -    MD0100PA00X+130287Y+146591X0200Y         S0      
317GND              VIA   -    MD0100PA00X+130287Y+145645X0200Y         S0      
317GND              VIA   -    MD0100PA00X+130287Y+146118X0200Y         S0      
317GND              VIA   -    MD0100PA00X+131818Y+120082X0200Y    R180 S0      
317GND              VIA   -    MD0100PA00X+131818Y+119832X0200Y    R180 S0      
317GND              VIA   -    MD0100PA00X+131744Y+115268X0200Y         S0      
327GND              PC147 -2   M      A01X+131744Y+115518X0198Y0197R270 S1      
317GND              VIA   -    MD0100PA00X+131933Y+104072X0200Y         S0      
317GND              VIA   -    MD0100PA00X+130994Y+103704X0200Y         S0      
317GND              VIA   -    MD0100PA00X+130466Y+102346X0200Y         S0      
317GND              VIA   -    MD0100PA00X+130758Y+099031X0200Y         S0      
327GND              J56   -3          A01X+129882Y+098963X0500Y1350R090 S1      
317GND              VIA   -    MD0100PA00X+130391Y+096009X0200Y         S0      
327GND              U143  -2          A01X+130391Y+095610X0140Y0440R180 S1      
317GND              VIA   -    MD0100PA00X+131838Y+094395X0200Y         S0      
327GND              U145  -2          A01X+131800Y+094806X0140Y0440     S1      
317GND              VIA   -    MD0100PA00X+131689Y+092560X0200Y         S0      
317GND              VIA   -    MD0100PA00X+131376Y+089916X0180Y    R270 S0      
327GND              U6    -A1         A01X+131533Y+089759X0160Y         S1      
317GND              VIA   -    MD0100PA00X+130576Y+089916X0180Y    R270 S0      
327GND              C2087 -2          A18X+130639Y+089658X0164Y0164R270 S2      
317GND              VIA   -    MD0100PA00X+130986Y+089916X0180Y    R270 S0      
327GND              C2088 -2          A18X+131048Y+089658X0164Y0164R270 S2      
317GND              VIA   -    MD0100PA00X+131691Y+089286X0180Y         S0      
327GND              U6    -C2         A01X+131848Y+089129X0160Y         S1      
317GND              VIA   -    MD0100PA00X+131691Y+088341X0180Y         S0      
327GND              C2085 -2          A18X+131533Y+088499X0164Y0164     S2      
327GND              U6    -F2         A01X+131848Y+088184X0160Y         S1      
317GND              VIA   -    MD0100PA00X+131691Y+086766X0180Y         S0      
327GND              U6    -L2         A01X+131848Y+086609X0160Y         S1      
327GND              C2084 -2          A18X+131456Y+086733X0164Y0164R270 S2      
317GND              VIA   -    MD0100PA00X+130886Y+083608X0200Y         S0      
317GND              VIA   -    MD0100PA00X+131153Y+147024X0200Y         S0      
317GND              VIA   -    MD0100PA00X+131153Y+147614X0200Y         S0      
317GND              VIA   -    MD0100PA00X+131153Y+148087X0200Y         S0      
317GND              VIA   -    MD0100PA00X+131153Y+146078X0200Y         S0      
317GND              VIA   -    MD0100PA00X+131153Y+146551X0200Y         S0      
317GND              VIA   -    MD0100PA00X+131153Y+157261X0200Y         S0      
317GND              VIA   -    MD0100PA00X+131153Y+157850X0200Y         S0      
317GND              VIA   -    MD0100PA00X+131153Y+156788X0200Y         S0      
317GND              VIA   -    MD0100PA00X+131153Y+156314X0200Y         S0      
317GND              VIA   -    MD0100PA00X+131153Y+151631X0200Y         S0      
317GND              VIA   -    MD0100PA00X+131153Y+151158X0200Y         S0      
317GND              VIA   -    MD0100PA00X+131153Y+150095X0200Y         S0      
317GND              VIA   -    MD0100PA00X+131153Y+150684X0200Y         S0      
317GND              VIA   -    MD0100PA00X+131153Y+149622X0200Y         S0      
317GND              VIA   -    MD0100PA00X+131153Y+148560X0200Y         S0      
317GND              VIA   -    MD0100PA00X+131153Y+149149X0200Y         S0      
317GND              VIA   -    MD0100PA00X+131200Y+164498X0200Y         S0      
317GND              VIA   -    MD0100PA00X+131153Y+161867X0200Y         S0      
317GND              VIA   -    MD0100PA00X+131153Y+161394X0200Y         S0      
317GND              VIA   -    MD0100PA00X+131153Y+160332X0200Y         S0      
317GND              VIA   -    MD0100PA00X+131153Y+159858X0200Y         S0      
317GND              VIA   -    MD0100PA00X+131153Y+160921X0200Y         S0      
317GND              VIA   -    MD0100PA00X+131153Y+158796X0200Y         S0      
317GND              VIA   -    MD0100PA00X+131153Y+159385X0200Y         S0      
317GND              VIA   -    MD0100PA00X+131153Y+158323X0200Y         S0      
317GND              VIA   -    M      A01X+133416Y+109852X0200Y         S2      
017GND              VIA   -    M      A18X+133416Y+109852X0260Y         S2      
017GND                    -    MD0100PA00X+133416Y+109852                       
317GND              VIA   -    MD0100PA00X+133136Y+109890X0200Y         S0      
317GND              VIA   -    MD0100PA00X+132110Y+096440X0200Y         S0      
327GND              C2746 -2          A01X+131850Y+096508X0198Y0197R090 S1      
317GND              VIA   -    MD0100PA00X+132846Y+095999X0200Y         S0      
327GND              U144  -2          A01X+132950Y+095594X0140Y0440R180 S1      
317GND              VIA   -    MD0100PA00X+133580Y+089601X0180Y    R180 S0      
327GND              U6    -B7         A01X+133423Y+089444X0160Y         S1      
327GND              C2029 -2          A18X+133423Y+089444X0164Y0164R270 S2      
317GND              VIA   -    M      A01X+132422Y+078060X0200Y         S2      
017GND              VIA   -    M      A18X+132422Y+078060X0260Y         S2      
017GND                    -    MD0100PA00X+132422Y+078060                       
327GND              C2146 -2          A01X+132758Y+078218X0198Y0197R090 S1      
317GND              VIA   -    MD0100PA00X+133479Y+121212X0200Y         S0      
317GND              VIA   -    MD0100PA00X+133479Y+120962X0200Y         S0      
317GND              VIA   -    MD0100PA00X+133479Y+120712X0200Y         S0      
317GND              VIA   -    MD0100PA00X+132049Y+120940X0200Y         S0      
317GND              VIA   -    MD0100PA00X+132049Y+121190X0200Y         S0      
317GND              VIA   -    MD0100PA00X+132049Y+120690X0200Y         S0      
317GND              VIA   -    MD0100PA00X+133164Y+119832X0200Y    R180 S0      
317GND              VIA   -    MD0100PA00X+133164Y+120082X0200Y    R180 S0      
317GND              VIA   -    MD0100PA00X+133479Y+120462X0200Y         S0      
317GND              VIA   -    MD0100PA00X+132049Y+120440X0200Y         S0      
317GND              VIA   -    MD0100PA00X+132627Y+115521X0200Y         S0      
317GND              VIA   -    MD0100PA00X+132627Y+115271X0200Y         S0      
317GND              VIA   -    MD0100PA00X+132028Y+114444X0200Y         S0      
317GND              VIA   -    MD0100PA00X+132028Y+114694X0200Y         S0      
317GND              VIA   -    MD0100PA00X+132028Y+114194X0200Y         S0      
317GND              VIA   -    MD0100PA00X+132340Y+112580X0200Y         S0      
317GND              VIA   -    MD0100PA00X+133180Y+112580X0200Y         S0      
317GND              VIA   -    MD0100PA00X+133430Y+112580X0200Y         S0      
317GND              VIA   -    MD0100PA00X+132180Y+112930X0200Y         S0      
317GND              VIA   -    MD0100PA00X+132430Y+112930X0200Y         S0      
317GND              VIA   -    MD0100PA00X+132680Y+112930X0200Y         S0      
317GND              VIA   -    MD0100PA00X+132930Y+112930X0200Y         S0      
317GND              VIA   -    MD0100PA00X+133180Y+112930X0200Y         S0      
317GND              VIA   -    MD0100PA00X+133430Y+112930X0200Y         S0      
317GND              VIA   -    MD0100PA00X+132028Y+113944X0200Y         S0      
317GND              VIA   -    MD0100PA00X+132028Y+113694X0200Y         S0      
317GND              VIA   -    MD0100PA00X+132028Y+113444X0200Y         S0      
317GND              VIA   -    MD0100PA00X+132028Y+113194X0200Y         S0      
317GND              VIA   -    MD0100PA00X+132340Y+112310X0200Y         S0      
317GND              VIA   -    MD0100PA00X+133140Y+112310X0200Y         S0      
317GND              VIA   -    MD0100PA00X+133390Y+112310X0200Y         S0      
317GND              VIA   -    MD0100PA00X+133484Y+111942X0193Y    R180 S0      
317GND              VIA   -    MD0100PA00X+133484Y+111382X0193Y    R180 S0      
317GND              VIA   -    MD0100PA00X+133236Y+111942X0193Y    R180 S0      
317GND              VIA   -    MD0100PA00X+133236Y+111382X0193Y    R180 S0      
317GND              VIA   -    MD0100PA00X+132019Y+147654X0200Y         S0      
317GND              VIA   -    MD0100PA00X+132019Y+147180X0200Y         S0      
317GND              VIA   -    MD0100PA00X+132885Y+148087X0200Y         S0      
317GND              VIA   -    MD0100PA00X+132019Y+148127X0200Y         S0      
317GND              VIA   -    MD0100PA00X+132885Y+147024X0200Y         S0      
317GND              VIA   -    MD0100PA00X+132885Y+147614X0200Y         S0      
317GND              VIA   -    MD0100PA00X+132019Y+146118X0200Y         S0      
317GND              VIA   -    MD0100PA00X+132019Y+145645X0200Y         S0      
317GND              VIA   -    MD0100PA00X+132019Y+146591X0200Y         S0      
317GND              VIA   -    MD0100PA00X+132885Y+146078X0200Y         S0      
317GND              VIA   -    MD0100PA00X+132885Y+146551X0200Y         S0      
317GND              VIA   -    MD0100PA00X+132019Y+156828X0200Y         S0      
317GND              VIA   -    MD0100PA00X+132885Y+157261X0200Y         S0      
317GND              VIA   -    MD0100PA00X+132885Y+157850X0200Y         S0      
317GND              VIA   -    MD0100PA00X+132019Y+157890X0200Y         S0      
317GND              VIA   -    MD0100PA00X+132019Y+157417X0200Y         S0      
317GND              VIA   -    MD0100PA00X+132885Y+156788X0200Y         S0      
317GND              VIA   -    MD0100PA00X+132885Y+156314X0200Y         S0      
317GND              VIA   -    MD0100PA00X+132019Y+156354X0200Y         S0      
317GND              VIA   -    MD0100PA00X+132019Y+155881X0200Y         S0      
317GND              VIA   -    MD0100PA00X+132885Y+151631X0200Y         S0      
317GND              VIA   -    MD0100PA00X+132019Y+150724X0200Y         S0      
317GND              VIA   -    MD0100PA00X+132019Y+151198X0200Y         S0      
317GND              VIA   -    MD0100PA00X+132885Y+151158X0200Y         S0      
317GND              VIA   -    MD0100PA00X+132885Y+150095X0200Y         S0      
317GND              VIA   -    MD0100PA00X+132885Y+150684X0200Y         S0      
317GND              VIA   -    MD0100PA00X+132019Y+150251X0200Y         S0      
317GND              VIA   -    MD0100PA00X+132019Y+149189X0200Y         S0      
317GND              VIA   -    MD0100PA00X+132019Y+148716X0200Y         S0      
317GND              VIA   -    MD0100PA00X+132885Y+149622X0200Y         S0      
317GND              VIA   -    MD0100PA00X+132019Y+149662X0200Y         S0      
317GND              VIA   -    MD0100PA00X+132885Y+148560X0200Y         S0      
317GND              VIA   -    MD0100PA00X+132885Y+149149X0200Y         S0      
317GND              VIA   -    MD0100PA00X+133200Y+164498X0200Y         S0      
317GND              VIA   -    MD0100PA00X+132019Y+161434X0200Y         S0      
317GND              VIA   -    MD0100PA00X+132885Y+161867X0200Y         S0      
317GND              VIA   -    MD0100PA00X+132885Y+161394X0200Y         S0      
317GND              VIA   -    MD0100PA00X+132885Y+159858X0200Y         S0      
317GND              VIA   -    MD0100PA00X+132885Y+160921X0200Y         S0      
317GND              VIA   -    MD0100PA00X+132019Y+159898X0200Y         S0      
317GND              VIA   -    MD0100PA00X+132019Y+160488X0200Y         S0      
317GND              VIA   -    MD0100PA00X+132019Y+160961X0200Y         S0      
317GND              VIA   -    MD0100PA00X+132885Y+160332X0200Y         S0      
317GND              VIA   -    MD0100PA00X+132019Y+158363X0200Y         S0      
317GND              VIA   -    MD0100PA00X+132885Y+158796X0200Y         S0      
317GND              VIA   -    MD0100PA00X+132885Y+159385X0200Y         S0      
317GND              VIA   -    MD0100PA00X+132019Y+159425X0200Y         S0      
317GND              VIA   -    MD0100PA00X+132019Y+158952X0200Y         S0      
317GND              VIA   -    MD0100PA00X+132885Y+158323X0200Y         S0      
317GND              VIA   -    MD0100PA00X+135241Y+113944X0200Y         S0      
317GND              VIA   -    MD0100PA00X+135241Y+113694X0200Y         S0      
317GND              VIA   -    MD0100PA00X+135241Y+113444X0200Y         S0      
317GND              VIA   -    MD0100PA00X+135241Y+113194X0200Y         S0      
317GND              VIA   -    MD0100PA00X+134991Y+113944X0200Y         S0      
317GND              VIA   -    MD0100PA00X+134991Y+113694X0200Y         S0      
317GND              VIA   -    MD0100PA00X+134991Y+113444X0200Y         S0      
317GND              VIA   -    MD0100PA00X+133732Y+111942X0193Y    R180 S0      
317GND              VIA   -    MD0100PA00X+133732Y+111382X0193Y    R180 S0      
327GND              PU12  -40  M      A01X+133483Y+111663X0690Y0770R180 S1      
317GND              VIA   -    MD0100PA00X+133935Y+109877X0200Y         S0      
317GND              VIA   -    MD0100PA00X+134742Y+120690X0200Y         S0      
317GND              VIA   -    MD0100PA00X+134742Y+121190X0200Y         S0      
317GND              VIA   -    MD0100PA00X+134742Y+120940X0200Y         S0      
317GND              VIA   -    MD0100PA00X+134511Y+119832X0200Y    R180 S0      
317GND              VIA   -    MD0100PA00X+134511Y+120082X0200Y    R180 S0      
317GND              VIA   -    MD0100PA00X+133711Y+119832X0200Y         S0      
317GND              VIA   -    MD0100PA00X+133711Y+120082X0200Y         S0      
317GND              VIA   -    MD0100PA00X+134742Y+120440X0200Y         S0      
317GND              VIA   -    MD0100PA00X+135140Y+115240X0200Y         S0      
317GND              VIA   -    MD0100PA00X+135140Y+115490X0200Y         S0      
317GND              VIA   -    MD0100PA00X+133667Y+115521X0200Y         S0      
317GND              VIA   -    MD0100PA00X+133667Y+115271X0200Y         S0      
317GND              VIA   -    MD0100PA00X+135241Y+114444X0200Y         S0      
317GND              VIA   -    MD0100PA00X+135241Y+114694X0200Y         S0      
317GND              VIA   -    MD0100PA00X+135241Y+114194X0200Y         S0      
317GND              VIA   -    MD0100PA00X+134991Y+114444X0200Y         S0      
317GND              VIA   -    MD0100PA00X+134991Y+114694X0200Y         S0      
317GND              VIA   -    MD0100PA00X+134991Y+114194X0200Y         S0      
317GND              VIA   -    MD0100PA00X+134350Y+114194X0200Y         S0      
317GND              VIA   -    MD0100PA00X+134350Y+114444X0200Y         S0      
317GND              VIA   -    MD0100PA00X+134350Y+114694X0200Y         S0      
317GND              VIA   -    MD0100PA00X+134991Y+113194X0200Y         S0      
317GND              VIA   -    MD0100PA00X+134350Y+113194X0200Y         S0      
317GND              VIA   -    MD0100PA00X+134350Y+113944X0200Y         S0      
317GND              VIA   -    MD0100PA00X+134350Y+113444X0200Y         S0      
317GND              VIA   -    MD0100PA00X+134350Y+113694X0200Y         S0      
317GND              VIA   -    MD0100PA00X+133680Y+112580X0200Y         S0      
317GND              VIA   -    MD0100PA00X+133930Y+112580X0200Y         S0      
317GND              VIA   -    MD0100PA00X+133680Y+112930X0200Y         S0      
317GND              VIA   -    MD0100PA00X+133930Y+112930X0200Y         S0      
327GND              PU12  -7_9-M      A01X+133138Y+112618X0827Y2126R270 S1      
317GND              VIA   -    MD0100PA00X+133751Y+147654X0200Y         S0      
317GND              VIA   -    MD0100PA00X+133751Y+147180X0200Y         S0      
317GND              VIA   -    MD0100PA00X+134617Y+148087X0200Y         S0      
317GND              VIA   -    MD0100PA00X+133751Y+148127X0200Y         S0      
317GND              VIA   -    MD0100PA00X+134617Y+147024X0200Y         S0      
317GND              VIA   -    MD0100PA00X+134617Y+147614X0200Y         S0      
317GND              VIA   -    MD0100PA00X+133751Y+145645X0200Y         S0      
317GND              VIA   -    MD0100PA00X+133751Y+146591X0200Y         S0      
317GND              VIA   -    MD0100PA00X+134617Y+146078X0200Y         S0      
317GND              VIA   -    MD0100PA00X+134617Y+146551X0200Y         S0      
317GND              VIA   -    MD0100PA00X+133751Y+146118X0200Y         S0      
317GND              VIA   -    MD0100PA00X+134617Y+156788X0200Y         S0      
317GND              VIA   -    MD0100PA00X+133751Y+156828X0200Y         S0      
317GND              VIA   -    MD0100PA00X+134617Y+157261X0200Y         S0      
317GND              VIA   -    MD0100PA00X+134617Y+157850X0200Y         S0      
317GND              VIA   -    MD0100PA00X+133751Y+157890X0200Y         S0      
317GND              VIA   -    MD0100PA00X+133751Y+157417X0200Y         S0      
317GND              VIA   -    MD0100PA00X+134617Y+156314X0200Y         S0      
317GND              VIA   -    MD0100PA00X+133751Y+156354X0200Y         S0      
317GND              VIA   -    MD0100PA00X+133751Y+155881X0200Y         S0      
317GND              VIA   -    MD0100PA00X+134617Y+151631X0200Y         S0      
317GND              VIA   -    MD0100PA00X+133751Y+151198X0200Y         S0      
317GND              VIA   -    MD0100PA00X+134617Y+151158X0200Y         S0      
317GND              VIA   -    MD0100PA00X+134617Y+150095X0200Y         S0      
317GND              VIA   -    MD0100PA00X+134617Y+150684X0200Y         S0      
317GND              VIA   -    MD0100PA00X+133751Y+150251X0200Y         S0      
317GND              VIA   -    MD0100PA00X+133751Y+150724X0200Y         S0      
317GND              VIA   -    MD0100PA00X+134617Y+149622X0200Y         S0      
317GND              VIA   -    MD0100PA00X+133751Y+149662X0200Y         S0      
317GND              VIA   -    MD0100PA00X+133751Y+149189X0200Y         S0      
317GND              VIA   -    MD0100PA00X+133751Y+148716X0200Y         S0      
317GND              VIA   -    MD0100PA00X+134617Y+149149X0200Y         S0      
317GND              VIA   -    MD0100PA00X+134617Y+148560X0200Y         S0      
317GND              VIA   -    MD0100PA00X+135200Y+164498X0200Y         S0      
317GND              VIA   -    MD0100PA00X+134617Y+161867X0200Y         S0      
317GND              VIA   -    MD0100PA00X+134617Y+161394X0200Y         S0      
317GND              VIA   -    MD0100PA00X+133751Y+161434X0200Y         S0      
317GND              VIA   -    MD0100PA00X+134617Y+160332X0200Y         S0      
317GND              VIA   -    MD0100PA00X+134617Y+159858X0200Y         S0      
317GND              VIA   -    MD0100PA00X+134617Y+160921X0200Y         S0      
317GND              VIA   -    MD0100PA00X+133751Y+159898X0200Y         S0      
317GND              VIA   -    MD0100PA00X+133751Y+160488X0200Y         S0      
317GND              VIA   -    MD0100PA00X+133751Y+160961X0200Y         S0      
317GND              VIA   -    MD0100PA00X+134617Y+158796X0200Y         S0      
317GND              VIA   -    MD0100PA00X+134617Y+159385X0200Y         S0      
317GND              VIA   -    MD0100PA00X+133751Y+159425X0200Y         S0      
317GND              VIA   -    MD0100PA00X+133751Y+158952X0200Y         S0      
317GND              VIA   -    MD0100PA00X+134617Y+158323X0200Y         S0      
317GND              VIA   -    MD0100PA00X+133751Y+158363X0200Y         S0      
317GND              VIA   -    MD0100PA00X+136404Y+120082X0200Y         S0      
317GND              VIA   -    MD0100PA00X+136404Y+119832X0200Y         S0      
317GND              VIA   -    MD0100PA00X+136172Y+120462X0200Y         S0      
317GND              VIA   -    MD0100PA00X+136680Y+115521X0200Y         S0      
317GND              VIA   -    MD0100PA00X+136680Y+115271X0200Y         S0      
317GND              VIA   -    MD0100PA00X+135740Y+115271X0200Y         S0      
317GND              VIA   -    MD0100PA00X+135740Y+115521X0200Y         S0      
317GND              VIA   -    MD0100PA00X+136393Y+112930X0200Y         S0      
317GND              VIA   -    MD0100PA00X+136143Y+112930X0200Y         S0      
317GND              VIA   -    MD0100PA00X+135893Y+112930X0200Y         S0      
317GND              VIA   -    MD0100PA00X+135643Y+112930X0200Y         S0      
317GND              VIA   -    MD0100PA00X+135393Y+112930X0200Y         S0      
317GND              VIA   -    MD0100PA00X+136643Y+112580X0200Y         S0      
317GND              VIA   -    MD0100PA00X+136393Y+112580X0200Y         S0      
317GND              VIA   -    MD0100PA00X+135553Y+112580X0200Y         S0      
317GND              VIA   -    MD0100PA00X+136643Y+112930X0200Y         S0      
317GND              VIA   -    MD0100PA00X+136603Y+112310X0200Y         S0      
317GND              VIA   -    MD0100PA00X+136353Y+112310X0200Y         S0      
317GND              VIA   -    MD0100PA00X+135553Y+112310X0200Y         S0      
317GND              VIA   -    MD0100PA00X+136448Y+111382X0193Y    R180 S0      
317GND              VIA   -    MD0100PA00X+136448Y+111942X0193Y    R180 S0      
317GND              VIA   -    MD0100PA00X+136696Y+111382X0193Y    R180 S0      
317GND              VIA   -    MD0100PA00X+136696Y+111942X0193Y    R180 S0      
317GND              VIA   -    MD0100PA00X+136104Y+109843X0200Y         S0      
317GND              VIA   -    M      A01X+136629Y+109852X0200Y         S2      
017GND              VIA   -    M      A18X+136629Y+109852X0260Y         S2      
017GND                    -    MD0100PA00X+136629Y+109852                       
317GND              VIA   -    MD0100PA00X+136442Y+109307X0200Y    R180 S0      
317GND              VIA   -    MD0100PA00X+136442Y+109057X0200Y    R180 S0      
317GND              VIA   -    MD0100PA00X+135726Y+103027X0200Y         S0      
317GND              VIA   -    MD0100PA00X+135726Y+102277X0200Y         S0      
327GND              PR141 -2          A01X+135969Y+102277X0198Y0197R180 S1      
317GND              VIA   -    MD0100PA00X+136788Y+101882X0200Y         S0      
327GND              PC136 -2          A01X+136788Y+101232X0198Y0197R180 S1      
327GND              PR143 -2   M      A01X+136788Y+101632X0198Y0197R180 S1      
327GND              PC134 -2          A18X+136476Y+101734X0198Y0197R270 S2      
317GND              VIA   -    MD0100PA00X+136649Y+100083X0200Y         S0      
317GND              VIA   -    MD0100PA00X+136390Y+100086X0200Y         S0      
317GND              VIA   -    MD0100PA00X+136317Y+099448X0200Y         S0      
317GND              VIA   -    MD0100PA00X+136415Y+089601X0180Y    R180 S0      
327GND              U6    -B16        A01X+136257Y+089444X0160Y         S1      
327GND              C2038 -2          A18X+136572Y+089444X0164Y0164R270 S2      
317GND              VIA   -    MD0100PA00X+136172Y+120712X0200Y         S0      
317GND              VIA   -    MD0100PA00X+136172Y+120962X0200Y         S0      
317GND              VIA   -    MD0100PA00X+136172Y+121212X0200Y         S0      
317GND              VIA   -    MD0100PA00X+135483Y+147654X0200Y         S0      
317GND              VIA   -    MD0100PA00X+135483Y+147180X0200Y         S0      
317GND              VIA   -    MD0100PA00X+136350Y+148087X0200Y         S0      
317GND              VIA   -    MD0100PA00X+136350Y+147024X0200Y         S0      
317GND              VIA   -    MD0100PA00X+136350Y+147614X0200Y         S0      
317GND              VIA   -    MD0100PA00X+135483Y+148127X0200Y         S0      
317GND              VIA   -    MD0100PA00X+136350Y+146078X0200Y         S0      
317GND              VIA   -    MD0100PA00X+136350Y+146551X0200Y         S0      
317GND              VIA   -    MD0100PA00X+135483Y+146118X0200Y         S0      
317GND              VIA   -    MD0100PA00X+135483Y+145645X0200Y         S0      
317GND              VIA   -    MD0100PA00X+135483Y+146591X0200Y         S0      
317GND              VIA   -    MD0100PA00X+136350Y+157850X0200Y         S0      
317GND              VIA   -    MD0100PA00X+136350Y+156788X0200Y         S0      
317GND              VIA   -    MD0100PA00X+135483Y+157890X0200Y         S0      
317GND              VIA   -    MD0100PA00X+135483Y+157417X0200Y         S0      
317GND              VIA   -    MD0100PA00X+135483Y+156828X0200Y         S0      
317GND              VIA   -    MD0100PA00X+136350Y+156314X0200Y         S0      
317GND              VIA   -    MD0100PA00X+135483Y+156354X0200Y         S0      
317GND              VIA   -    MD0100PA00X+135483Y+155881X0200Y         S0      
317GND              VIA   -    MD0100PA00X+136350Y+151631X0200Y         S0      
317GND              VIA   -    MD0100PA00X+135483Y+150724X0200Y         S0      
317GND              VIA   -    MD0100PA00X+136350Y+150095X0200Y         S0      
317GND              VIA   -    MD0100PA00X+136350Y+150684X0200Y         S0      
317GND              VIA   -    MD0100PA00X+136350Y+151158X0200Y         S0      
317GND              VIA   -    MD0100PA00X+135483Y+151198X0200Y         S0      
317GND              VIA   -    MD0100PA00X+135483Y+150251X0200Y         S0      
317GND              VIA   -    MD0100PA00X+135483Y+149189X0200Y         S0      
317GND              VIA   -    MD0100PA00X+136350Y+149622X0200Y         S0      
317GND              VIA   -    MD0100PA00X+136350Y+149149X0200Y         S0      
317GND              VIA   -    MD0100PA00X+136350Y+148560X0200Y         S0      
317GND              VIA   -    MD0100PA00X+135483Y+149662X0200Y         S0      
317GND              VIA   -    MD0100PA00X+135483Y+148716X0200Y         S0      
317GND              VIA   -    MD0100PA00X+136350Y+161867X0200Y         S0      
317GND              VIA   -    MD0100PA00X+136350Y+161394X0200Y         S0      
317GND              VIA   -    MD0100PA00X+135483Y+161434X0200Y         S0      
317GND              VIA   -    MD0100PA00X+136350Y+160332X0200Y         S0      
317GND              VIA   -    MD0100PA00X+136350Y+159858X0200Y         S0      
317GND              VIA   -    MD0100PA00X+136350Y+160921X0200Y         S0      
317GND              VIA   -    MD0100PA00X+135483Y+159898X0200Y         S0      
317GND              VIA   -    MD0100PA00X+135483Y+160488X0200Y         S0      
317GND              VIA   -    MD0100PA00X+135483Y+160961X0200Y         S0      
317GND              VIA   -    MD0100PA00X+136350Y+158796X0200Y         S0      
317GND              VIA   -    MD0100PA00X+136350Y+159385X0200Y         S0      
317GND              VIA   -    MD0100PA00X+136350Y+158323X0200Y         S0      
317GND              VIA   -    MD0100PA00X+135483Y+159425X0200Y         S0      
317GND              VIA   -    MD0100PA00X+135483Y+158952X0200Y         S0      
317GND              VIA   -    MD0100PA00X+135483Y+158363X0200Y         S0      
317GND              VIA   -    MD0100PA00X+136350Y+157261X0200Y         S0      
317GND              VIA   -    MD0100PA00X+137660Y+103022X0200Y         S0      
327GND              PC135 -2          A18X+137455Y+102677X0198Y0197R270 S2      
317GND              VIA   -    MD0100PA00X+138367Y+102330X0200Y    R090 S0      
317GND              VIA   -    MD0100PA00X+138367Y+101730X0200Y    R090 S0      
317GND              VIA   -    MD0100PA00X+138367Y+101130X0200Y    R090 S0      
317GND              VIA   -    MD0100PA00X+137038Y+100468X0200Y         S0      
327GND              PC126 -2          A01X+137038Y+100718X0198Y0197R180 S1      
327GND              PR147 -2          A18X+136876Y+100719X0198Y0197R090 S2      
317GND              VIA   -    MD0100PA00X+137138Y+098672X0200Y         S0      
317GND              VIA   -    MD0100PA00X+138305Y+089916X0180Y    R180 S0      
327GND              U6    -A22        A01X+138147Y+089759X0160Y         S1      
317GND              VIA   -    MD0100PA00X+137990Y+087081X0180Y    R180 S0      
327GND              U6    -K21        A01X+137832Y+086924X0160Y         S1      
317GND              VIA   -    MD0100PA00X+137990Y+085822X0180Y         S0      
327GND              U6    -N21        A01X+137832Y+085979X0160Y         S1      
317GND              VIA   -    MD0100PA00X+138305Y+082987X0180Y         S0      
327GND              U6    -AB22       A01X+138147Y+083144X0160Y         S1      
317GND              VIA   -    MD0100PA00X+138337Y+114444X0200Y         S0      
317GND              VIA   -    MD0100PA00X+138337Y+114694X0200Y         S0      
317GND              VIA   -    MD0100PA00X+138337Y+114194X0200Y         S0      
317GND              VIA   -    MD0100PA00X+137563Y+114194X0200Y         S0      
317GND              VIA   -    MD0100PA00X+137563Y+114444X0200Y         S0      
317GND              VIA   -    MD0100PA00X+137563Y+114694X0200Y         S0      
317GND              VIA   -    MD0100PA00X+137686Y+115268X0200Y         S0      
317GND              VIA   -    MD0100PA00X+138302Y+115268X0200Y         S0      
317GND              VIA   -    MD0100PA00X+137143Y+112930X0200Y         S0      
317GND              VIA   -    MD0100PA00X+136893Y+112930X0200Y         S0      
317GND              VIA   -    MD0100PA00X+137143Y+112580X0200Y         S0      
317GND              VIA   -    MD0100PA00X+136893Y+112580X0200Y         S0      
327GND              PU13  -7_9-M      A01X+136351Y+112618X0827Y2126R270 S1      
317GND              VIA   -    MD0100PA00X+138337Y+113944X0200Y         S0      
317GND              VIA   -    MD0100PA00X+138337Y+113694X0200Y         S0      
317GND              VIA   -    MD0100PA00X+138337Y+113444X0200Y         S0      
317GND              VIA   -    MD0100PA00X+138337Y+113194X0200Y         S0      
317GND              VIA   -    MD0100PA00X+137563Y+113194X0200Y         S0      
317GND              VIA   -    MD0100PA00X+137563Y+113944X0200Y         S0      
317GND              VIA   -    MD0100PA00X+137563Y+113444X0200Y         S0      
317GND              VIA   -    MD0100PA00X+137563Y+113694X0200Y         S0      
317GND              VIA   -    MD0100PA00X+136944Y+111382X0193Y    R180 S0      
317GND              VIA   -    MD0100PA00X+136944Y+111942X0193Y    R180 S0      
327GND              PU13  -40  M      A01X+136696Y+111663X0690Y0770R180 S1      
317GND              VIA   -    MD0100PA00X+137148Y+109877X0200Y         S0      
317GND              VIA   -    MD0100PA00X+137445Y+109307X0200Y         S0      
317GND              VIA   -    MD0100PA00X+137445Y+109057X0200Y         S0      
317GND              VIA   -    MD0100PA00X+139825Y+092626X0200Y         S0      
317GND              VIA   -    MD0100PA00X+139616Y+086860X0200Y         S0      
327GND              C2042 -2          A18X+139395Y+086662X0164Y0164R180 S2      
317GND              VIA   -    MD0100PA00X+139556Y+087620X0200Y         S0      
327GND              C2061 -2          A18X+139300Y+087102X0164Y0164R180 S2      
327GND              C2073 -2   M      A18X+139299Y+087620X0164Y0164R180 S2      
317GND              VIA   -    MD0100PA00X+139692Y+086283X0200Y         S0      
327GND              C2044 -2          A18X+139397Y+086283X0164Y0164R180 S2      
317GND              VIA   -    MD0100PA00X+137200Y+164498X0200Y         S0      
317GND              VIA   -    MD0100PA00X+137216Y+161434X0200Y         S0      
317GND              VIA   -    MD0100PA00X+137216Y+160961X0200Y         S0      
317GND              VIA   -    MD0100PA00X+137216Y+159898X0200Y         S0      
317GND              VIA   -    MD0100PA00X+137216Y+160488X0200Y         S0      
317GND              VIA   -    MD0100PA00X+137216Y+159425X0200Y         S0      
317GND              VIA   -    MD0100PA00X+137216Y+158952X0200Y         S0      
317GND              VIA   -    MD0100PA00X+137216Y+158363X0200Y         S0      
317GND              VIA   -    MD0100PA00X+137216Y+157890X0200Y         S0      
317GND              VIA   -    MD0100PA00X+137216Y+157417X0200Y         S0      
317GND              VIA   -    MD0100PA00X+137216Y+156828X0200Y         S0      
317GND              VIA   -    MD0100PA00X+137216Y+156354X0200Y         S0      
317GND              VIA   -    MD0100PA00X+137216Y+155881X0200Y         S0      
317GND              VIA   -    MD0100PA00X+137216Y+151198X0200Y         S0      
317GND              VIA   -    MD0100PA00X+137216Y+150725X0200Y         S0      
317GND              VIA   -    MD0100PA00X+137216Y+150252X0200Y         S0      
317GND              VIA   -    MD0100PA00X+137216Y+149662X0200Y         S0      
317GND              VIA   -    MD0100PA00X+137216Y+149189X0200Y         S0      
317GND              VIA   -    MD0100PA00X+137216Y+148716X0200Y         S0      
317GND              VIA   -    MD0100PA00X+137216Y+148127X0200Y         S0      
317GND              VIA   -    MD0100PA00X+137216Y+147654X0200Y         S0      
317GND              VIA   -    MD0100PA00X+137216Y+147181X0200Y         S0      
317GND              VIA   -    MD0100PA00X+137216Y+146591X0200Y         S0      
317GND              VIA   -    MD0100PA00X+137216Y+145645X0200Y         S0      
317GND              VIA   -    MD0100PA00X+137216Y+146118X0200Y         S0      
317GND              VIA   -    MD0100PA00X+139370Y+120940X0200Y         S0      
317GND              VIA   -    MD0100PA00X+139370Y+121190X0200Y         S0      
317GND              VIA   -    MD0100PA00X+139370Y+120690X0200Y         S0      
317GND              VIA   -    MD0100PA00X+139138Y+119832X0200Y    R180 S0      
317GND              VIA   -    MD0100PA00X+139138Y+120082X0200Y    R180 S0      
317GND              VIA   -    MD0100PA00X+139370Y+120440X0200Y         S0      
317GND              VIA   -    MD0100PA00X+138587Y+114444X0200Y         S0      
317GND              VIA   -    MD0100PA00X+138587Y+114694X0200Y         S0      
317GND              VIA   -    MD0100PA00X+138587Y+114194X0200Y         S0      
317GND              VIA   -    MD0100PA00X+139186Y+115271X0200Y         S0      
317GND              VIA   -    MD0100PA00X+139186Y+115521X0200Y         S0      
317GND              VIA   -    MD0100PA00X+139989Y+112930X0200Y         S0      
317GND              VIA   -    MD0100PA00X+139739Y+112930X0200Y         S0      
317GND              VIA   -    MD0100PA00X+139489Y+112930X0200Y         S0      
317GND              VIA   -    MD0100PA00X+139239Y+112930X0200Y         S0      
317GND              VIA   -    MD0100PA00X+138989Y+112930X0200Y         S0      
317GND              VIA   -    MD0100PA00X+138739Y+112930X0200Y         S0      
317GND              VIA   -    MD0100PA00X+139989Y+112580X0200Y         S0      
317GND              VIA   -    MD0100PA00X+139739Y+112580X0200Y         S0      
317GND              VIA   -    MD0100PA00X+138899Y+112580X0200Y         S0      
317GND              VIA   -    MD0100PA00X+138587Y+113944X0200Y         S0      
317GND              VIA   -    MD0100PA00X+138587Y+113694X0200Y         S0      
317GND              VIA   -    MD0100PA00X+138587Y+113444X0200Y         S0      
317GND              VIA   -    MD0100PA00X+138587Y+113194X0200Y         S0      
317GND              VIA   -    MD0100PA00X+139949Y+112310X0200Y         S0      
317GND              VIA   -    MD0100PA00X+139699Y+112310X0200Y         S0      
317GND              VIA   -    MD0100PA00X+138899Y+112310X0200Y         S0      
317GND              VIA   -    MD0100PA00X+139794Y+111382X0193Y    R180 S0      
317GND              VIA   -    MD0100PA00X+140042Y+111382X0193Y    R180 S0      
317GND              VIA   -    MD0100PA00X+140042Y+111942X0193Y    R180 S0      
317GND              VIA   -    MD0100PA00X+139794Y+111942X0193Y    R180 S0      
317GND              VIA   -    MD0100PA00X+139450Y+109843X0200Y         S0      
317GND              VIA   -    M      A01X+139975Y+109852X0200Y         S2      
017GND              VIA   -    M      A18X+139975Y+109852X0260Y         S2      
017GND                    -    MD0100PA00X+139975Y+109852                       
317GND              VIA   -    MD0100PA00X+138967Y+102330X0200Y    R090 S0      
317GND              VIA   -    MD0100PA00X+139567Y+102330X0200Y    R090 S0      
317GND              VIA   -    MD0100PA00X+139567Y+101730X0200Y    R090 S0      
317GND              VIA   -    MD0100PA00X+138967Y+101130X0200Y    R090 S0      
317GND              VIA   -    MD0100PA00X+139567Y+101130X0200Y    R090 S0      
327GND              PU11  -TH  M      A01X+138967Y+101730X1440Y1440R090 S1      
317GND              VIA   -    MD0100PA00X+139200Y+164498X0200Y         S0      
317GND              VIA   -    MD0100PA00X+140909Y+114444X0200Y         S0      
317GND              VIA   -    MD0100PA00X+140909Y+114694X0200Y         S0      
317GND              VIA   -    MD0100PA00X+141549Y+114194X0200Y         S0      
317GND              VIA   -    MD0100PA00X+141549Y+114694X0200Y         S0      
317GND              VIA   -    MD0100PA00X+141549Y+114444X0200Y         S0      
317GND              VIA   -    MD0100PA00X+140226Y+115271X0200Y         S0      
317GND              VIA   -    MD0100PA00X+140226Y+115521X0200Y         S0      
317GND              VIA   -    MD0100PA00X+141674Y+115521X0200Y         S0      
317GND              VIA   -    MD0100PA00X+141674Y+115271X0200Y         S0      
317GND              VIA   -    MD0100PA00X+140909Y+114194X0200Y         S0      
317GND              VIA   -    MD0100PA00X+140489Y+112930X0200Y         S0      
317GND              VIA   -    MD0100PA00X+140239Y+112930X0200Y         S0      
317GND              VIA   -    MD0100PA00X+140489Y+112580X0200Y         S0      
317GND              VIA   -    MD0100PA00X+140239Y+112580X0200Y         S0      
327GND              PU14  -7_9-M      A01X+139697Y+112618X0827Y2126R270 S1      
317GND              VIA   -    MD0100PA00X+140909Y+113194X0200Y         S0      
317GND              VIA   -    MD0100PA00X+140909Y+113944X0200Y         S0      
317GND              VIA   -    MD0100PA00X+140909Y+113444X0200Y         S0      
317GND              VIA   -    MD0100PA00X+140909Y+113694X0200Y         S0      
317GND              VIA   -    MD0100PA00X+141549Y+113194X0200Y         S0      
317GND              VIA   -    MD0100PA00X+141549Y+113444X0200Y         S0      
317GND              VIA   -    MD0100PA00X+141549Y+113694X0200Y         S0      
317GND              VIA   -    MD0100PA00X+141549Y+113944X0200Y         S0      
317GND              VIA   -    MD0100PA00X+140290Y+111382X0193Y    R180 S0      
317GND              VIA   -    MD0100PA00X+140290Y+111942X0193Y    R180 S0      
327GND              PU14  -40  M      A01X+140042Y+111663X0690Y0770R180 S1      
317GND              VIA   -    MD0100PA00X+140494Y+109877X0200Y         S0      
317GND              VIA   -    MD0100PA00X+140432Y+098944X0200Y         S0      
317GND              VIA   -    MD0100PA00X+141332Y+095891X0200Y         S0      
327GND              J55   -3          A01X+140403Y+095447X0500Y1350R090 S1      
317GND              VIA   -    MD0100PA00X+141358Y+091519X0200Y         S0      
327GND              R4297 -2          A01X+141089Y+091519X0198Y0197     S1      
317GND              VIA   -    MD0100PA00X+140469Y+091090X0200Y         S0      
317GND              VIA   -    MD0100PA00X+143339Y+134331X0200Y         S0      
317GND              VIA   -    MD0100PA00X+141435Y+130302X0200Y         S0      
317GND              VIA   -    MD0100PA00X+140800Y+121212X0200Y         S0      
317GND              VIA   -    MD0100PA00X+140800Y+120962X0200Y         S0      
317GND              VIA   -    MD0100PA00X+140800Y+120712X0200Y         S0      
317GND              VIA   -    MD0100PA00X+140484Y+120082X0200Y    R180 S0      
317GND              VIA   -    MD0100PA00X+140484Y+119832X0200Y    R180 S0      
317GND              VIA   -    MD0100PA00X+141031Y+119832X0200Y         S0      
317GND              VIA   -    MD0100PA00X+141031Y+120082X0200Y         S0      
317GND              VIA   -    MD0100PA00X+140800Y+120462X0200Y         S0      
317GND              VIA   -    MD0100PA00X+141200Y+164498X0200Y         S0      
317GND              VIA   -    MD0100PA00X+141952Y+112930X0200Y         S0      
317GND              VIA   -    MD0100PA00X+143202Y+112580X0200Y         S0      
317GND              VIA   -    MD0100PA00X+142952Y+112580X0200Y         S0      
317GND              VIA   -    MD0100PA00X+142112Y+112580X0200Y         S0      
317GND              VIA   -    MD0100PA00X+141799Y+113194X0200Y         S0      
317GND              VIA   -    MD0100PA00X+141799Y+113444X0200Y         S0      
317GND              VIA   -    MD0100PA00X+141799Y+113694X0200Y         S0      
317GND              VIA   -    MD0100PA00X+141799Y+113944X0200Y         S0      
317GND              VIA   -    MD0100PA00X+143162Y+112310X0200Y         S0      
317GND              VIA   -    MD0100PA00X+142912Y+112310X0200Y         S0      
317GND              VIA   -    MD0100PA00X+142112Y+112310X0200Y         S0      
317GND              VIA   -    MD0100PA00X+143007Y+111382X0193Y    R180 S0      
317GND              VIA   -    MD0100PA00X+143007Y+111942X0193Y    R180 S0      
317GND              VIA   -    MD0100PA00X+143255Y+111382X0193Y    R180 S0      
317GND              VIA   -    MD0100PA00X+143255Y+111942X0193Y    R180 S0      
317GND              VIA   -    MD0100PA00X+142662Y+109843X0200Y         S0      
317GND              VIA   -    MD0100PA00X+143188Y+109852X0200Y         S0      
317GND              VIA   -    MD0100PA00X+143000Y+109307X0200Y    R180 S0      
317GND              VIA   -    MD0100PA00X+143000Y+109057X0200Y    R180 S0      
317GND              VIA   -    MD0100PA00X+142074Y+103077X0200Y         S0      
327GND              C836  -1          A01X+141834Y+103077X0198Y0197R180 S1      
317GND              VIA   -    MD0100PA00X+142074Y+101627X0200Y         S0      
327GND              C837  -2   M      A01X+141834Y+101627X0198Y0197     S1      
317GND              VIA   -    MD0100PA00X+142074Y+100077X0200Y         S0      
327GND              C834  -2          A01X+141834Y+100077X0198Y0197     S1      
317GND              VIA   -    MD0100PA00X+142074Y+100477X0200Y         S0      
327GND              C835  -1          A01X+141834Y+100477X0198Y0197R180 S1      
317GND              VIA   -    MD0100PA00X+142755Y+093920X0200Y         S0      
317GND              VIA   -    MD0100PA00X+142413Y+090030X0200Y         S0      
327GND              JPEX3 -10  M      A01X+143025Y+090030X0200Y0600R090 S1      
327GND              U321  -10  M      A01X+142962Y+090030X0320Y0750R270 S1      
317GND              VIA   -    MD0100PA00X+142281Y+091006X0200Y         S0      
317GND              VIA   -    MD0100PA00X+142700Y+083450X0200Y    R180 S0      
327GND              R4611 -2          A01X+142942Y+083450X0198Y0197R180 S1      
317GND              VIA   -    MD0100PA00X+142700Y+081850X0200Y    R180 S0      
327GND              R4612 -2          A01X+142942Y+081850X0198Y0197R180 S1      
317GND              VIA   -    MD0100PA00X+142700Y+079050X0200Y    R180 S0      
327GND              R4674 -2          A01X+142942Y+079050X0198Y0197R180 S1      
317GND              VIA   -    MD0100PA00X+144129Y+133578X0200Y         S0      
317GND              VIA   -    MD0100PA00X+142062Y+120940X0200Y         S0      
317GND              VIA   -    MD0100PA00X+142062Y+120690X0200Y         S0      
317GND              VIA   -    MD0100PA00X+141831Y+120082X0200Y    R180 S0      
317GND              VIA   -    MD0100PA00X+141831Y+119832X0200Y    R180 S0      
317GND              VIA   -    MD0100PA00X+142062Y+120440X0200Y         S0      
317GND              VIA   -    MD0100PA00X+141799Y+114194X0200Y         S0      
317GND              VIA   -    MD0100PA00X+141799Y+114694X0200Y         S0      
317GND              VIA   -    MD0100PA00X+141799Y+114444X0200Y         S0      
317GND              VIA   -    MD0100PA00X+142298Y+115521X0200Y         S0      
317GND              VIA   -    MD0100PA00X+142298Y+115271X0200Y         S0      
317GND              VIA   -    MD0100PA00X+143238Y+115271X0200Y         S0      
317GND              VIA   -    MD0100PA00X+143238Y+115521X0200Y         S0      
317GND              VIA   -    MD0100PA00X+143202Y+112930X0200Y         S0      
317GND              VIA   -    MD0100PA00X+142952Y+112930X0200Y         S0      
317GND              VIA   -    MD0100PA00X+142702Y+112930X0200Y         S0      
317GND              VIA   -    MD0100PA00X+142452Y+112930X0200Y         S0      
317GND              VIA   -    MD0100PA00X+142202Y+112930X0200Y         S0      
317GND              VIA   -    MD0100PA00X+143200Y+164498X0200Y         S0      
317GND              VIA   -    MD0100PA00X+144245Y+115268X0200Y         S0      
317GND              VIA   -    MD0100PA00X+144122Y+114694X0200Y         S0      
317GND              VIA   -    MD0100PA00X+144122Y+114444X0200Y         S0      
317GND              VIA   -    MD0100PA00X+144122Y+114194X0200Y         S0      
317GND              VIA   -    MD0100PA00X+143702Y+112930X0200Y         S0      
317GND              VIA   -    MD0100PA00X+143452Y+112930X0200Y         S0      
317GND              VIA   -    MD0100PA00X+143702Y+112580X0200Y         S0      
317GND              VIA   -    MD0100PA00X+143452Y+112580X0200Y         S0      
327GND              PU15  -7_9-M      A01X+142910Y+112618X0827Y2126R270 S1      
317GND              VIA   -    MD0100PA00X+144122Y+113694X0200Y         S0      
317GND              VIA   -    MD0100PA00X+144122Y+113444X0200Y         S0      
317GND              VIA   -    MD0100PA00X+144122Y+113944X0200Y         S0      
317GND              VIA   -    MD0100PA00X+144122Y+113194X0200Y         S0      
317GND              VIA   -    MD0100PA00X+143503Y+111382X0193Y    R180 S0      
317GND              VIA   -    MD0100PA00X+143503Y+111942X0193Y    R180 S0      
327GND              PU15  -40  M      A01X+143254Y+111663X0690Y0770R180 S1      
317GND              VIA   -    MD0100PA00X+143706Y+109877X0200Y         S0      
317GND              VIA   -    MD0100PA00X+143527Y+103152X0200Y         S0      
327GND              C3657 -2          A01X+143798Y+103152X0198Y0197R090 S1      
317GND              VIA   -    MD0100PA00X+144061Y+102157X0200Y         S0      
327GND              U379  -3          A01X+144343Y+101440X0160Y0360     S1      
317GND              VIA   -    MD0100PA00X+143945Y+097901X0200Y         S0      
317GND              VIA   -    MD0100PA00X+143529Y+089750X0200Y         S0      
317GND              VIA   -    MD0100PA00X+144907Y+089258X0200Y         S0      
317GND              VIA   -    MD0100PA00X+143770Y+088007X0200Y         S0      
327GND              R3497 -2          A18X+143486Y+088007X0198Y0197R090 S2      
317GND              VIA   -    MD0100PA00X+144304Y+087368X0200Y    R090 S0      
327GND              C2503 -1          A18X+144304Y+087661X0198Y0197     S2      
317GND              VIA   -    MD0100PA00X+143819Y+086763X0200Y         S0      
317GND              VIA   -    MD0100PA00X+144300Y+083850X0200Y         S0      
327GND              R4635 -1          A01X+144058Y+083850X0198Y0197R180 S1      
317GND              VIA   -    MD0100PA00X+144300Y+084250X0200Y         S0      
327GND              R4636 -1          A01X+144058Y+084250X0198Y0197R180 S1      
317GND              VIA   -    MD0100PA00X+144300Y+079450X0200Y         S0      
327GND              R4698 -1          A01X+144058Y+079450X0198Y0197R180 S1      
317GND              VIA   -    MD0100PA00X+144300Y+079850X0200Y         S0      
327GND              R4699 -1          A01X+144058Y+079850X0198Y0197R180 S1      
317GND              VIA   -    MD0100PA00X+143492Y+121212X0200Y         S0      
317GND              VIA   -    MD0100PA00X+143492Y+120962X0200Y         S0      
317GND              VIA   -    MD0100PA00X+143492Y+120712X0200Y         S0      
317GND              VIA   -    MD0100PA00X+143724Y+119832X0200Y         S0      
317GND              VIA   -    MD0100PA00X+143724Y+120082X0200Y         S0      
317GND              VIA   -    MD0100PA00X+143492Y+120462X0200Y         S0      
317GND              VIA   -    MD0100PA00X+146608Y+097975X0200Y         S0      
317GND              VIA   -    MD0100PA00X+146066Y+096425X0200Y         S0      
317GND              VIA   -    MD0100PA00X+146200Y+096038X0200Y         S0      
327GND              U101  -2          A18X+146603Y+096038X0140Y0440R270 S2      
317GND              VIA   -    MD0100PA00X+146282Y+095000X0200Y         S0      
317GND              VIA   -    MD0100PA00X+145100Y+093185X0200Y         S0      
327GND              U97   -2          A18X+145481Y+093185X0240Y0440R270 S2      
317GND              VIA   -    MD0100PA00X+145942Y+089923X0200Y         S0      
327GND              U68   -8          A18X+145764Y+090483X0140Y0610R180 S2      
317GND              VIA   -    MD0100PA00X+146047Y+088598X0200Y         S0      
317GND              VIA   -    MD0100PA00X+146269Y+087786X0200Y         S0      
317GND              VIA   -    MD0100PA00X+146269Y+087486X0200Y         S0      
317GND              VIA   -    MD0100PA00X+146124Y+086748X0200Y         S0      
317GND              VIA   -    MD0100PA00X+145378Y+081303X0200Y         S0      
327GND              U343  -12         A01X+145898Y+081303X0240Y0540R270 S1      
327GND              U345  -12         A01X+145898Y+076903X0240Y0540R270 S1      
317GND              VIA   -    MD0100PA00X+146550Y+103023X0200Y         S0      
317GND              VIA   -    MD0100PA00X+145594Y+101837X0200Y         S0      
327GND              Q20   -1          A01X+145594Y+101517X0240Y0240R270 S1      
317GND              VIA   -    MD0100PA00X+146239Y+100656X0200Y         S0      
327GND              Q20   -4          A01X+146302Y+100926X0240Y0240R270 S1      
317GND              VIA   -    MD0100PA00X+147363Y+086434X0200Y         S0      
317GND              VIA   -    MD0100PA00X+145200Y+164498X0200Y         S0      
317GND              VIA   -    M      A01X+148068Y+120210X0200Y         S2      
017GND              VIA   -    M      A18X+148068Y+120210X0260Y         S2      
017GND                    -    MD0100PA00X+148068Y+120210                       
327GND              R1455 -1          A01X+148362Y+120505X0198Y0197R045 S1      
317GND              VIA   -    MD0100PA00X+147785Y+120493X0200Y    R315 S0      
327GND              R1418 -1          A01X+148080Y+120788X0198Y0197R045 S1      
317GND              VIA   -    MD0100PA00X+146837Y+103070X0200Y         S0      
317GND              VIA   -    MD0100PA00X+147962Y+103510X0200Y         S0      
327GND              C3593 -2          A01X+147737Y+103510X0120Y0150R090 S1      
317GND              VIA   -    M      A01X+147185Y+103509X0200Y         S2      
017GND              VIA   -    M      A18X+147185Y+103509X0260Y         S2      
017GND                    -    MD0100PA00X+147185Y+103509                       
327GND              C3594 -2   M      A01X+147426Y+103509X0120Y0150R090 S1      
317GND              VIA   -    MD0100PA00X+146710Y+099786X0200Y         S0      
317GND              VIA   -    MD0100PA00X+147510Y+099786X0200Y         S0      
317GND              VIA   -    MD0100PA00X+147110Y+099786X0200Y         S0      
317GND              VIA   -    MD0100PA00X+147910Y+099786X0200Y         S0      
317GND              VIA   -    MD0100PA00X+146850Y+097418X0200Y         S0      
327GND              U103  -2          A18X+146471Y+097418X0140Y0440R270 S2      
327GND              C2607 -1          A01X+147092Y+097200X0198Y0197     S1      
317GND              VIA   -    MD0100PA00X+147408Y+092058X0200Y         S0      
327GND              C2584 -2          A18X+147408Y+092350X0198Y0197R180 S2      
317GND              VIA   -    MD0100PA00X+147609Y+158952X0200Y         S0      
317GND              VIA   -    MD0100PA00X+147609Y+159425X0200Y         S0      
317GND              VIA   -    MD0100PA00X+147609Y+158363X0200Y         S0      
317GND              VIA   -    MD0100PA00X+147609Y+157417X0200Y         S0      
317GND              VIA   -    MD0100PA00X+147609Y+157890X0200Y         S0      
317GND              VIA   -    MD0100PA00X+147609Y+156828X0200Y         S0      
317GND              VIA   -    MD0100PA00X+147609Y+155881X0200Y         S0      
317GND              VIA   -    MD0100PA00X+147609Y+156354X0200Y         S0      
317GND              VIA   -    MD0100PA00X+147609Y+150724X0200Y         S0      
317GND              VIA   -    MD0100PA00X+147609Y+151198X0200Y         S0      
317GND              VIA   -    MD0100PA00X+147609Y+150251X0200Y         S0      
317GND              VIA   -    MD0100PA00X+147609Y+149662X0200Y         S0      
317GND              VIA   -    MD0100PA00X+147609Y+148716X0200Y         S0      
317GND              VIA   -    MD0100PA00X+147609Y+149189X0200Y         S0      
317GND              VIA   -    MD0100PA00X+147609Y+147654X0200Y         S0      
317GND              VIA   -    MD0100PA00X+147609Y+148127X0200Y         S0      
317GND              VIA   -    MD0100PA00X+147609Y+147180X0200Y         S0      
317GND              VIA   -    MD0100PA00X+147609Y+145645X0200Y         S0      
317GND              VIA   -    MD0100PA00X+147609Y+146118X0200Y         S0      
317GND              VIA   -    MD0100PA00X+147609Y+146591X0200Y         S0      
317GND              VIA   -    MD0100PA00X+149256Y+097465X0200Y         S0      
317GND              VIA   -    MD0100PA00X+148523Y+097389X0200Y         S0      
317GND              VIA   -    MD0100PA00X+148650Y+094700X0200Y         S0      
327GND              C2568 -2          A18X+149050Y+094842X0198Y0197R090 S2      
317GND              VIA   -    MD0100PA00X+148259Y+096191X0200Y         S0      
327GND              C2605 -1          A18X+148259Y+095901X0198Y0197     S2      
317GND              VIA   -    MD0100PA00X+149607Y+095004X0200Y         S0      
327GND              U70   -51         A01X+149166Y+095004X0110Y0540R090 S1      
327GND              C2573 -2          A18X+149900Y+094992X0198Y0197R090 S2      
317GND              VIA   -    MD0100PA00X+149642Y+094308X0200Y         S0      
327GND              C2565 -2          A18X+149350Y+094308X0198Y0197R270 S2      
317GND              VIA   -    MD0100PA00X+148510Y+094390X0200Y         S0      
327GND              C2564 -2          A18X+148850Y+094390X0280Y0320     S2      
317GND              VIA   -    MD0100PA00X+148708Y+092092X0200Y         S0      
327GND              C2575 -2          A18X+149000Y+092092X0198Y0197R090 S2      
317GND              VIA   -    MD0100PA00X+149600Y+092200X0200Y         S0      
327GND              C2583 -2          A18X+149706Y+092524X0280Y0320R090 S2      
317GND              VIA   -    MD0100PA00X+149650Y+091900X0200Y         S0      
327GND              C2582 -2          A18X+149892Y+092000X0198Y0197     S2      
317GND              VIA   -    MD0100PA00X+149721Y+090974X0200Y    R270 S0      
317GND              VIA   -    MD0100PA00X+149638Y+089802X0200Y         S0      
317GND              VIA   -    MD0100PA00X+149210Y+089486X0200Y         S0      
317GND              VIA   -    MD0100PA00X+149808Y+089482X0200Y         S0      
317GND              VIA   -    MD0100PA00X+149400Y+088400X0200Y         S0      
317GND              VIA   -    MD0100PA00X+149141Y+087538X0200Y         S0      
317GND              VIA   -    MD0100PA00X+149749Y+087384X0200Y         S0      
327GND              C2604 -1          A18X+149749Y+087634X0198Y0197R180 S2      
317GND              VIA   -    MD0100PA00X+148980Y+086639X0200Y         S0      
317GND              VIA   -    MD0100PA00X+148965Y+083698X0200Y         S0      
317GND              VIA   -    MD0100PA00X+149650Y+083600X0200Y    R180 S0      
327GND              R4637 -1          A01X+149892Y+083600X0198Y0197     S1      
317GND              VIA   -    MD0100PA00X+149142Y+084558X0200Y         S0      
327GND              C3597 -2          A01X+148850Y+084558X0198Y0197R090 S1      
317GND              VIA   -    MD0100PA00X+149684Y+081300X0200Y         S0      
327GND              R4615 -2          A01X+149942Y+081300X0198Y0197R180 S1      
317GND              VIA   -    MD0100PA00X+149142Y+080158X0200Y         S0      
327GND              C3600 -2          A01X+148850Y+080158X0198Y0197R090 S1      
317GND              VIA   -    MD0100PA00X+149650Y+079200X0200Y    R180 S0      
327GND              R4700 -1          A01X+149892Y+079200X0198Y0197     S1      
317GND              VIA   -    MD0100PA00X+149106Y+079300X0200Y         S0      
317GND              VIA   -    MD0100PA00X+147200Y+164498X0200Y         S0      
317GND              VIA   -    MD0100PA00X+147609Y+161434X0200Y         S0      
317GND              VIA   -    MD0100PA00X+147609Y+160488X0200Y         S0      
317GND              VIA   -    MD0100PA00X+147609Y+159898X0200Y         S0      
317GND              VIA   -    MD0100PA00X+147609Y+160961X0200Y         S0      
317GND              VIA   -    MD0100PA00X+148406Y+122375X0200Y         S0      
327GND              R1419 -1          A01X+148646Y+122615X0198Y0197R045 S1      
317GND              VIA   -    MD0100PA00X+149247Y+121520X0200Y         S0      
327GND              R1420 -1          A01X+149494Y+121767X0198Y0197R045 S1      
317GND              VIA   -    MD0100PA00X+149820Y+120961X0200Y         S0      
327GND              R1421 -1          A01X+150343Y+120918X0198Y0197R045 S1      
317GND              VIA   -    MD0100PA00X+148710Y+099786X0200Y         S0      
317GND              VIA   -    MD0100PA00X+149510Y+099786X0200Y         S0      
317GND              VIA   -    MD0100PA00X+148310Y+099786X0200Y         S0      
317GND              VIA   -    MD0100PA00X+149110Y+099786X0200Y         S0      
317GND              VIA   -    MD0100PA00X+148476Y+148087X0200Y         S0      
317GND              VIA   -    MD0100PA00X+148476Y+147024X0200Y         S0      
317GND              VIA   -    MD0100PA00X+149342Y+146118X0200Y         S0      
317GND              VIA   -    MD0100PA00X+149342Y+145645X0200Y         S0      
317GND              VIA   -    MD0100PA00X+149342Y+146591X0200Y         S0      
317GND              VIA   -    MD0100PA00X+148476Y+146078X0200Y         S0      
317GND              VIA   -    MD0100PA00X+148476Y+146551X0200Y         S0      
317GND              VIA   -    MD0100PA00X+149342Y+156354X0200Y         S0      
317GND              VIA   -    MD0100PA00X+149342Y+155881X0200Y         S0      
317GND              VIA   -    MD0100PA00X+148476Y+156314X0200Y         S0      
317GND              VIA   -    MD0100PA00X+148476Y+151631X0200Y         S0      
317GND              VIA   -    MD0100PA00X+149342Y+151198X0200Y         S0      
317GND              VIA   -    MD0100PA00X+149342Y+150251X0200Y         S0      
317GND              VIA   -    MD0100PA00X+149342Y+150724X0200Y         S0      
317GND              VIA   -    MD0100PA00X+148476Y+151158X0200Y         S0      
317GND              VIA   -    MD0100PA00X+148476Y+150095X0200Y         S0      
317GND              VIA   -    MD0100PA00X+148476Y+150684X0200Y         S0      
317GND              VIA   -    MD0100PA00X+148476Y+148560X0200Y         S0      
317GND              VIA   -    MD0100PA00X+148476Y+149149X0200Y         S0      
317GND              VIA   -    MD0100PA00X+149342Y+149662X0200Y         S0      
317GND              VIA   -    MD0100PA00X+149342Y+149189X0200Y         S0      
317GND              VIA   -    MD0100PA00X+149342Y+148716X0200Y         S0      
317GND              VIA   -    MD0100PA00X+148476Y+149622X0200Y         S0      
317GND              VIA   -    MD0100PA00X+148476Y+147614X0200Y         S0      
317GND              VIA   -    MD0100PA00X+149342Y+148127X0200Y         S0      
317GND              VIA   -    MD0100PA00X+149342Y+147654X0200Y         S0      
317GND              VIA   -    MD0100PA00X+149342Y+147180X0200Y         S0      
317GND              VIA   -    MD0100PA00X+149200Y+164498X0200Y         S0      
317GND              VIA   -    MD0100PA00X+149342Y+161434X0200Y         S0      
317GND              VIA   -    MD0100PA00X+148476Y+161867X0200Y         S0      
317GND              VIA   -    MD0100PA00X+148476Y+161394X0200Y         S0      
317GND              VIA   -    MD0100PA00X+149342Y+159898X0200Y         S0      
317GND              VIA   -    MD0100PA00X+149342Y+160488X0200Y         S0      
317GND              VIA   -    MD0100PA00X+149342Y+160961X0200Y         S0      
317GND              VIA   -    MD0100PA00X+148476Y+160332X0200Y         S0      
317GND              VIA   -    MD0100PA00X+148476Y+159858X0200Y         S0      
317GND              VIA   -    MD0100PA00X+148476Y+160921X0200Y         S0      
317GND              VIA   -    MD0100PA00X+149342Y+159425X0200Y         S0      
317GND              VIA   -    MD0100PA00X+149342Y+158952X0200Y         S0      
317GND              VIA   -    MD0100PA00X+149342Y+158363X0200Y         S0      
317GND              VIA   -    MD0100PA00X+148476Y+158796X0200Y         S0      
317GND              VIA   -    MD0100PA00X+148476Y+159385X0200Y         S0      
317GND              VIA   -    MD0100PA00X+148476Y+158323X0200Y         S0      
317GND              VIA   -    MD0100PA00X+149342Y+157417X0200Y         S0      
317GND              VIA   -    MD0100PA00X+149342Y+156828X0200Y         S0      
317GND              VIA   -    MD0100PA00X+148476Y+157261X0200Y         S0      
317GND              VIA   -    MD0100PA00X+148476Y+157850X0200Y         S0      
317GND              VIA   -    MD0100PA00X+148476Y+156788X0200Y         S0      
317GND              VIA   -    MD0100PA00X+149342Y+157890X0200Y         S0      
327GND              PEX3  -BA1        A01X+151634Y+110512X0180Y         S1      
317GND              VIA   -    MD0100PA00X+149910Y+099786X0200Y         S0      
317GND              VIA   -    MD0100PA00X+151110Y+099786X0200Y         S0      
317GND              VIA   -    MD0100PA00X+150310Y+099786X0200Y         S0      
317GND              VIA   -    MD0100PA00X+150710Y+099786X0200Y         S0      
317GND              VIA   -    MD0100PA00X+151074Y+097374X0200Y         S0      
327GND              C2577 -2          A01X+151406Y+097374X0280Y0320R090 S1      
317GND              VIA   -    MD0100PA00X+151400Y+096874X0200Y         S0      
327GND              C2574 -2          A01X+151731Y+096874X0198Y0197R180 S1      
317GND              VIA   -    MD0100PA00X+150140Y+096600X0200Y    R270 S0      
327GND              U70   -47         A01X+150140Y+096176X0110Y0540     S1      
317GND              VIA   -    MD0100PA00X+150589Y+096596X0200Y         S0      
327GND              C2563 -2          A18X+150589Y+095824X0198Y0197     S2      
327GND              C2567 -2   M      A18X+150589Y+096274X0198Y0197     S2      
317GND              VIA   -    MD0100PA00X+151396Y+095040X0200Y         S0      
317GND              VIA   -    MD0100PA00X+151050Y+093150X0200Y         S0      
327GND              R908  -2          A18X+151050Y+092908X0198Y0197R270 S2      
317GND              VIA   -    MD0100PA00X+151435Y+093881X0200Y         S0      
317GND              VIA   -    MD0100PA00X+150730Y+091226X0200Y    R270 S0      
317GND              VIA   -    MD0100PA00X+149845Y+091237X0200Y    R270 S0      
317GND              VIA   -    MD0100PA00X+150736Y+090974X0200Y    R270 S0      
317GND              VIA   -    MD0100PA00X+150703Y+088813X0200Y    R270 S0      
317GND              VIA   -    MD0100PA00X+151074Y+146118X0200Y         S0      
317GND              VIA   -    MD0100PA00X+151074Y+145645X0200Y         S0      
317GND              VIA   -    MD0100PA00X+151074Y+146591X0200Y         S0      
317GND              VIA   -    MD0100PA00X+150208Y+146078X0200Y         S0      
317GND              VIA   -    MD0100PA00X+150208Y+146551X0200Y         S0      
317GND              VIA   -    MD0100PA00X+150208Y+151631X0200Y         S0      
317GND              VIA   -    MD0100PA00X+150208Y+151158X0200Y         S0      
317GND              VIA   -    MD0100PA00X+150208Y+150095X0200Y         S0      
317GND              VIA   -    MD0100PA00X+150208Y+150684X0200Y         S0      
317GND              VIA   -    MD0100PA00X+151074Y+151198X0200Y         S0      
317GND              VIA   -    MD0100PA00X+151074Y+150251X0200Y         S0      
317GND              VIA   -    MD0100PA00X+151074Y+150724X0200Y         S0      
317GND              VIA   -    MD0100PA00X+151074Y+149662X0200Y         S0      
317GND              VIA   -    MD0100PA00X+151074Y+149189X0200Y         S0      
317GND              VIA   -    MD0100PA00X+151074Y+148716X0200Y         S0      
317GND              VIA   -    MD0100PA00X+150208Y+149622X0200Y         S0      
317GND              VIA   -    MD0100PA00X+150208Y+148560X0200Y         S0      
317GND              VIA   -    MD0100PA00X+150208Y+149149X0200Y         S0      
317GND              VIA   -    MD0100PA00X+150208Y+147614X0200Y         S0      
317GND              VIA   -    MD0100PA00X+151074Y+148127X0200Y         S0      
317GND              VIA   -    MD0100PA00X+151074Y+147654X0200Y         S0      
317GND              VIA   -    MD0100PA00X+151074Y+147180X0200Y         S0      
317GND              VIA   -    MD0100PA00X+150208Y+148087X0200Y         S0      
317GND              VIA   -    MD0100PA00X+150208Y+147024X0200Y         S0      
317GND              VIA   -    MD0100PA00X+151074Y+159898X0200Y         S0      
317GND              VIA   -    MD0100PA00X+151074Y+160488X0200Y         S0      
317GND              VIA   -    MD0100PA00X+151074Y+160961X0200Y         S0      
317GND              VIA   -    MD0100PA00X+150208Y+160332X0200Y         S0      
317GND              VIA   -    MD0100PA00X+150208Y+159858X0200Y         S0      
317GND              VIA   -    MD0100PA00X+150208Y+160921X0200Y         S0      
317GND              VIA   -    MD0100PA00X+151074Y+159425X0200Y         S0      
317GND              VIA   -    MD0100PA00X+151074Y+158952X0200Y         S0      
317GND              VIA   -    MD0100PA00X+151074Y+158363X0200Y         S0      
317GND              VIA   -    MD0100PA00X+150208Y+158796X0200Y         S0      
317GND              VIA   -    MD0100PA00X+150208Y+159385X0200Y         S0      
317GND              VIA   -    MD0100PA00X+150208Y+158323X0200Y         S0      
317GND              VIA   -    MD0100PA00X+151074Y+157417X0200Y         S0      
317GND              VIA   -    MD0100PA00X+151074Y+156828X0200Y         S0      
317GND              VIA   -    MD0100PA00X+150208Y+157261X0200Y         S0      
317GND              VIA   -    MD0100PA00X+150208Y+157850X0200Y         S0      
317GND              VIA   -    MD0100PA00X+150208Y+156788X0200Y         S0      
317GND              VIA   -    MD0100PA00X+151074Y+157890X0200Y         S0      
317GND              VIA   -    MD0100PA00X+151074Y+155881X0200Y         S0      
317GND              VIA   -    MD0100PA00X+150208Y+156314X0200Y         S0      
317GND              VIA   -    MD0100PA00X+151074Y+156354X0200Y         S0      
327GND              PEX3  -BA5        A01X+153130Y+110512X0180Y         S1      
327GND              PEX3  -BB3        A01X+152382Y+110138X0180Y         S1      
327GND              PEX3  -BB5        A01X+153130Y+110138X0180Y         S1      
327GND              PEX3  -BC2        A01X+152008Y+109764X0180Y         S1      
327GND              PEX3  -BC4        A01X+152756Y+109764X0180Y         S1      
327GND              PEX3  -AY3        A01X+152382Y+110886X0180Y         S1      
327GND              PEX3  -AY4        A01X+152756Y+110886X0180Y         S1      
327GND              PEX3  -AY5        A01X+153130Y+110886X0180Y         S1      
327GND              PEX3  -BA2        A01X+152008Y+110512X0180Y         S1      
327GND              PEX3  -BE3        A01X+152382Y+109016X0180Y         S1      
327GND              PEX3  -BE4        A01X+152756Y+109016X0180Y         S1      
327GND              PEX3  -BE5        A01X+153130Y+109016X0180Y         S1      
327GND              PEX3  -BF2        A01X+152008Y+108642X0180Y         S1      
327GND              PEX3  -BF3        A01X+152382Y+108642X0180Y         S1      
327GND              PEX3  -BF5        A01X+153130Y+108642X0180Y         S1      
327GND              PEX3  -BG3        A01X+152382Y+108268X0180Y         S1      
327GND              PEX3  -BG5        A01X+153130Y+108268X0180Y         S1      
327GND              PEX3  -BH1        A01X+151634Y+107894X0180Y         S1      
327GND              PEX3  -BH2        A01X+152008Y+107894X0180Y         S1      
327GND              PEX3  -BH4        A01X+152756Y+107894X0180Y         S1      
327GND              PEX3  -BJ2        A01X+152008Y+107520X0180Y         S1      
327GND              PEX3  -BJ4        A01X+152756Y+107520X0180Y         S1      
317GND              VIA   -    MD0100PA00X+152310Y+099786X0200Y         S0      
317GND              VIA   -    MD0100PA00X+151910Y+099786X0200Y         S0      
317GND              VIA   -    MD0100PA00X+153110Y+099786X0200Y         S0      
317GND              VIA   -    MD0100PA00X+151510Y+099786X0200Y         S0      
317GND              VIA   -    MD0100PA00X+152397Y+098028X0200Y         S0      
317GND              VIA   -    MD0100PA00X+152552Y+097108X0200Y         S0      
327GND              C2606 -1          A18X+152300Y+097108X0198Y0197R090 S2      
317GND              VIA   -    MD0100PA00X+153017Y+095699X0200Y         S0      
327GND              C2572 -2          A18X+153500Y+095508X0198Y0197R270 S2      
317GND              VIA   -    MD0100PA00X+152502Y+095734X0200Y    R270 S0      
327GND              U70   -35         A01X+152502Y+096176X0110Y0540     S1      
317GND              VIA   -    MD0100PA00X+152450Y+094950X0200Y         S0      
327GND              U102  -2          A18X+152300Y+095356X0140Y0440     S2      
317GND              VIA   -    MD0100PA00X+152809Y+093639X0200Y         S0      
317GND              VIA   -    MD0100PA00X+152788Y+093944X0200Y    R180 S0      
327GND              U70   -25         A01X+153673Y+094020X0110Y0540R090 S1      
317GND              VIA   -    MD0100PA00X+152574Y+092874X0200Y         S0      
317GND              VIA   -    MD0100PA00X+152661Y+092144X0200Y         S0      
327GND              U70   -15         A01X+152699Y+091668X0110Y0540     S1      
317GND              VIA   -    MD0100PA00X+152300Y+092374X0200Y         S0      
317GND              VIA   -    MD0100PA00X+152305Y+091226X0200Y    R270 S0      
327GND              C2576 -2          A18X+152093Y+091519X0198Y0197R090 S2      
327GND              U70   -13         A01X+152305Y+091668X0110Y0540     S1      
317GND              VIA   -    MD0100PA00X+151912Y+091224X0200Y    R270 S0      
327GND              U70   -11         A01X+151912Y+091668X0110Y0540     S1      
317GND              VIA   -    MD0100PA00X+151628Y+091224X0200Y    R270 S0      
327GND              U70   -10         A01X+151715Y+091668X0110Y0540     S1      
317GND              VIA   -    MD0100PA00X+151715Y+090837X0200Y         S0      
317GND              VIA   -    MD0100PA00X+151734Y+090318X0200Y         S0      
317GND              VIA   -    MD0100PA00X+151574Y+088813X0200Y         S0      
327GND              Y3    -2   M      A01X+151136Y+088813X0480Y0560R090 S1      
317GND              VIA   -    MD0100PA00X+151734Y+089700X0200Y         S0      
317GND              VIA   -    MD0100PA00X+151906Y+087634X0200Y         S0      
327GND              U100  -2          A18X+151450Y+087634X0140Y0440R090 S2      
317GND              VIA   -    MD0100PA00X+151200Y+164498X0200Y         S0      
317GND              VIA   -    MD0100PA00X+151074Y+161434X0200Y         S0      
317GND              VIA   -    MD0100PA00X+150208Y+161867X0200Y         S0      
317GND              VIA   -    MD0100PA00X+150208Y+161394X0200Y         S0      
327GND              PEX3  -AD1 M      A01X+151634Y+116870X0180Y         S1      
327GND              PEX3  -AD2        A01X+152008Y+116870X0180Y         S1      
327GND              PEX3  -AD3        A01X+152382Y+116870X0180Y         S1      
327GND              PEX3  -AE3        A01X+152382Y+116496X0180Y         S1      
327GND              PEX3  -AE5        A01X+153130Y+116496X0180Y         S1      
327GND              PEX3  -AE4 M      A01X+152756Y+116496X0180Y         S1      
327GND              PEX3  -AF2        A01X+152008Y+116122X0180Y         S1      
327GND              PEX3  -AF3        A01X+152382Y+116122X0180Y         S1      
327GND              PEX3  -AG3        A01X+152382Y+115748X0180Y         S1      
327GND              PEX3  -AG4        A01X+152756Y+115748X0180Y         S1      
327GND              PEX3  -AG5        A01X+153130Y+115748X0180Y         S1      
327GND              PEX3  -AH2        A01X+152008Y+115374X0180Y         S1      
327GND              PEX3  -AH3        A01X+152382Y+115374X0180Y         S1      
327GND              PEX3  -AJ3        A01X+152382Y+115000X0180Y         S1      
327GND              PEX3  -AJ4        A01X+152756Y+115000X0180Y         S1      
327GND              PEX3  -AJ5        A01X+153130Y+115000X0180Y         S1      
327GND              PEX3  -AK2        A01X+152008Y+114626X0180Y         S1      
327GND              PEX3  -AK3        A01X+152382Y+114626X0180Y         S1      
327GND              PEX3  -AM3        A01X+152382Y+113878X0180Y         S1      
327GND              PEX3  -AN2        A01X+152008Y+113504X0180Y         S1      
327GND              PEX3  -AP3        A01X+152382Y+113130X0180Y         S1      
327GND              PEX3  -AP4        A01X+152756Y+113130X0180Y         S1      
327GND              PEX3  -AP5        A01X+153130Y+113130X0180Y         S1      
327GND              PEX3  -AR2        A01X+152008Y+112756X0180Y         S1      
327GND              PEX3  -AR5        A01X+153130Y+112756X0180Y         S1      
327GND              PEX3  -AT3        A01X+152382Y+112382X0180Y         S1      
327GND              PEX3  -AT4        A01X+152756Y+112382X0180Y         S1      
327GND              PEX3  -AT5        A01X+153130Y+112382X0180Y         S1      
327GND              PEX3  -AU2        A01X+152008Y+112008X0180Y         S1      
327GND              PEX3  -AU5        A01X+153130Y+112008X0180Y         S1      
327GND              PEX3  -AV3        A01X+152382Y+111634X0180Y         S1      
327GND              PEX3  -AV4        A01X+152756Y+111634X0180Y         S1      
327GND              PEX3  -AV5        A01X+153130Y+111634X0180Y         S1      
327GND              PEX3  -AW2        A01X+152008Y+111260X0180Y         S1      
327GND              PEX3  -AW5        A01X+153130Y+111260X0180Y         S1      
327GND              PEX3  -BA3        A01X+152382Y+110512X0180Y         S1      
317GND              VIA   -    MD0100PA00X+152806Y+149662X0200Y         S0      
317GND              VIA   -    MD0100PA00X+152806Y+149189X0200Y         S0      
317GND              VIA   -    MD0100PA00X+152806Y+148716X0200Y         S0      
317GND              VIA   -    MD0100PA00X+151940Y+149622X0200Y         S0      
317GND              VIA   -    MD0100PA00X+151940Y+148560X0200Y         S0      
317GND              VIA   -    MD0100PA00X+151940Y+149149X0200Y         S0      
317GND              VIA   -    MD0100PA00X+152806Y+147654X0200Y         S0      
317GND              VIA   -    MD0100PA00X+152806Y+147180X0200Y         S0      
317GND              VIA   -    MD0100PA00X+151940Y+148087X0200Y         S0      
317GND              VIA   -    MD0100PA00X+151940Y+147024X0200Y         S0      
317GND              VIA   -    MD0100PA00X+151940Y+147614X0200Y         S0      
317GND              VIA   -    MD0100PA00X+152806Y+148127X0200Y         S0      
317GND              VIA   -    MD0100PA00X+152806Y+146118X0200Y         S0      
317GND              VIA   -    MD0100PA00X+152806Y+145645X0200Y         S0      
317GND              VIA   -    MD0100PA00X+152806Y+146591X0200Y         S0      
317GND              VIA   -    MD0100PA00X+151940Y+146078X0200Y         S0      
317GND              VIA   -    MD0100PA00X+151940Y+146551X0200Y         S0      
317GND              VIA   -    MD0100PA00X+151940Y+159385X0200Y         S0      
317GND              VIA   -    MD0100PA00X+151940Y+158323X0200Y         S0      
317GND              VIA   -    MD0100PA00X+152806Y+159425X0200Y         S0      
317GND              VIA   -    MD0100PA00X+152806Y+158952X0200Y         S0      
317GND              VIA   -    MD0100PA00X+152806Y+158363X0200Y         S0      
317GND              VIA   -    MD0100PA00X+151940Y+158796X0200Y         S0      
317GND              VIA   -    MD0100PA00X+152806Y+157417X0200Y         S0      
317GND              VIA   -    MD0100PA00X+152806Y+156828X0200Y         S0      
317GND              VIA   -    MD0100PA00X+151940Y+157261X0200Y         S0      
317GND              VIA   -    MD0100PA00X+151940Y+157850X0200Y         S0      
317GND              VIA   -    MD0100PA00X+151940Y+156788X0200Y         S0      
317GND              VIA   -    MD0100PA00X+152806Y+157890X0200Y         S0      
317GND              VIA   -    MD0100PA00X+152806Y+156354X0200Y         S0      
317GND              VIA   -    MD0100PA00X+152806Y+155881X0200Y         S0      
317GND              VIA   -    MD0100PA00X+151940Y+156314X0200Y         S0      
317GND              VIA   -    MD0100PA00X+151940Y+151631X0200Y         S0      
317GND              VIA   -    MD0100PA00X+152806Y+151198X0200Y         S0      
317GND              VIA   -    MD0100PA00X+152806Y+150251X0200Y         S0      
317GND              VIA   -    MD0100PA00X+152806Y+150724X0200Y         S0      
317GND              VIA   -    MD0100PA00X+151940Y+151158X0200Y         S0      
317GND              VIA   -    MD0100PA00X+151940Y+150095X0200Y         S0      
317GND              VIA   -    MD0100PA00X+151940Y+150684X0200Y         S0      
327GND              PEX3  -AV6        A01X+153504Y+111634X0180Y         S1      
327GND              PEX3  -AV7        A01X+153878Y+111634X0180Y         S1      
327GND              PEX3  -AW8        A01X+154252Y+111260X0180Y         S1      
327GND              PEX3  -AW9        A01X+154626Y+111260X0180Y         S1      
327GND              PEX3  -AY6        A01X+153504Y+110886X0180Y         S1      
327GND              PEX3  -AY7        A01X+153878Y+110886X0180Y         S1      
327GND              PEX3  -AY8        A01X+154252Y+110886X0180Y         S1      
327GND              PEX3  -BA7        A01X+153878Y+110512X0180Y         S1      
327GND              PEX3  -BB7        A01X+153878Y+110138X0180Y         S1      
327GND              PEX3  -BC6        A01X+153504Y+109764X0180Y         S1      
327GND              PEX3  -BE6        A01X+153504Y+109016X0180Y         S1      
327GND              PEX3  -BE7        A01X+153878Y+109016X0180Y         S1      
327GND              PEX3  -BG7        A01X+153878Y+108268X0180Y         S1      
327GND              PEX3  -BH6        A01X+153504Y+107894X0180Y         S1      
327GND              PEX3  -BJ6        A01X+153504Y+107520X0180Y         S1      
317GND              VIA   -    MD0100PA00X+152806Y+161434X0200Y         S0      
317GND              VIA   -    MD0100PA00X+151940Y+161867X0200Y         S0      
317GND              VIA   -    MD0100PA00X+151940Y+161394X0200Y         S0      
317GND              VIA   -    MD0100PA00X+152806Y+159898X0200Y         S0      
317GND              VIA   -    MD0100PA00X+152806Y+160488X0200Y         S0      
317GND              VIA   -    MD0100PA00X+152806Y+160961X0200Y         S0      
317GND              VIA   -    MD0100PA00X+151940Y+160332X0200Y         S0      
317GND              VIA   -    MD0100PA00X+151940Y+159858X0200Y         S0      
317GND              VIA   -    MD0100PA00X+151940Y+160921X0200Y         S0      
327GND              PEX3  -AF9        A01X+154626Y+116122X0180Y         S1      
327GND              PEX3  -AD6        A01X+153504Y+116870X0180Y         S1      
327GND              PEX3  -AE6        A01X+153504Y+116496X0180Y         S1      
327GND              PEX3  -AF6        A01X+153504Y+116122X0180Y         S1      
327GND              PEX3  -AH9        A01X+154626Y+115374X0180Y         S1      
327GND              PEX3  -AG9        A01X+154626Y+115748X0180Y         S1      
327GND              PEX3  -AJ9        A01X+154626Y+115000X0180Y         S1      
327GND              PEX3  -AG6        A01X+153504Y+115748X0180Y         S1      
327GND              PEX3  -AH6        A01X+153504Y+115374X0180Y         S1      
327GND              PEX3  -AJ6        A01X+153504Y+115000X0180Y         S1      
327GND              PEX3  -AK6        A01X+153504Y+114626X0180Y         S1      
327GND              PEX3  -AK8        A01X+154252Y+114626X0180Y         S1      
327GND              PEX3  -AK9        A01X+154626Y+114626X0180Y         S1      
327GND              PEX3  -AN8        A01X+154252Y+113504X0180Y         S1      
327GND              PEX3  -AN5        A01X+153130Y+113504X0180Y         S1      
327GND              PEX3  -AN9        A01X+154626Y+113504X0180Y         S1      
327GND              PEX3  -AP6        A01X+153504Y+113130X0180Y         S1      
327GND              PEX3  -AP7        A01X+153878Y+113130X0180Y         S1      
327GND              PEX3  -AR8        A01X+154252Y+112756X0180Y         S1      
327GND              PEX3  -AR9        A01X+154626Y+112756X0180Y         S1      
327GND              PEX3  -AT6        A01X+153504Y+112382X0180Y         S1      
327GND              PEX3  -AT7        A01X+153878Y+112382X0180Y         S1      
327GND              PEX3  -AU8        A01X+154252Y+112008X0180Y         S1      
327GND              PEX3  -AU9        A01X+154626Y+112008X0180Y         S1      
317GND              VIA   -    MD0100PA00X+154538Y+148127X0200Y         S0      
317GND              VIA   -    MD0100PA00X+154538Y+147181X0200Y         S0      
317GND              VIA   -    MD0100PA00X+154538Y+147654X0200Y         S0      
317GND              VIA   -    MD0100PA00X+153672Y+148087X0200Y         S0      
317GND              VIA   -    MD0100PA00X+153672Y+147024X0200Y         S0      
317GND              VIA   -    MD0100PA00X+153672Y+147614X0200Y         S0      
317GND              VIA   -    MD0100PA00X+154538Y+145645X0200Y         S0      
317GND              VIA   -    MD0100PA00X+154538Y+146591X0200Y         S0      
317GND              VIA   -    MD0100PA00X+153672Y+146078X0200Y         S0      
317GND              VIA   -    MD0100PA00X+153672Y+146551X0200Y         S0      
317GND              VIA   -    MD0100PA00X+154538Y+146118X0200Y         S0      
317GND              VIA   -    MD0100PA00X+153672Y+158796X0200Y         S0      
317GND              VIA   -    MD0100PA00X+153672Y+159385X0200Y         S0      
317GND              VIA   -    MD0100PA00X+154538Y+158363X0200Y         S0      
317GND              VIA   -    MD0100PA00X+153672Y+158323X0200Y         S0      
317GND              VIA   -    MD0100PA00X+154538Y+157417X0200Y         S0      
317GND              VIA   -    MD0100PA00X+154538Y+157890X0200Y         S0      
317GND              VIA   -    MD0100PA00X+153672Y+157261X0200Y         S0      
317GND              VIA   -    MD0100PA00X+153672Y+157850X0200Y         S0      
317GND              VIA   -    MD0100PA00X+154538Y+156828X0200Y         S0      
317GND              VIA   -    MD0100PA00X+153672Y+156788X0200Y         S0      
317GND              VIA   -    MD0100PA00X+153672Y+156314X0200Y         S0      
317GND              VIA   -    MD0100PA00X+154538Y+155881X0200Y         S0      
317GND              VIA   -    MD0100PA00X+154538Y+156354X0200Y         S0      
317GND              VIA   -    MD0100PA00X+153672Y+151631X0200Y         S0      
317GND              VIA   -    MD0100PA00X+154538Y+151198X0200Y         S0      
317GND              VIA   -    MD0100PA00X+154538Y+150252X0200Y         S0      
317GND              VIA   -    MD0100PA00X+154538Y+150725X0200Y         S0      
317GND              VIA   -    MD0100PA00X+153672Y+151158X0200Y         S0      
317GND              VIA   -    MD0100PA00X+153672Y+150095X0200Y         S0      
317GND              VIA   -    MD0100PA00X+153672Y+150684X0200Y         S0      
317GND              VIA   -    MD0100PA00X+154538Y+149662X0200Y         S0      
317GND              VIA   -    MD0100PA00X+154538Y+148716X0200Y         S0      
317GND              VIA   -    MD0100PA00X+154538Y+149189X0200Y         S0      
317GND              VIA   -    MD0100PA00X+153672Y+149622X0200Y         S0      
317GND              VIA   -    MD0100PA00X+153672Y+148560X0200Y         S0      
317GND              VIA   -    MD0100PA00X+153672Y+149149X0200Y         S0      
317GND              VIA   -    MD0100PA00X+154781Y+090658X0200Y         S0      
317GND              VIA   -    MD0100PA00X+153200Y+164498X0200Y         S0      
317GND              VIA   -    MD0100PA00X+153672Y+161867X0200Y         S0      
317GND              VIA   -    MD0100PA00X+153672Y+161394X0200Y         S0      
317GND              VIA   -    MD0100PA00X+154538Y+161434X0200Y         S0      
317GND              VIA   -    MD0100PA00X+154538Y+160488X0200Y         S0      
317GND              VIA   -    MD0100PA00X+154538Y+159898X0200Y         S0      
317GND              VIA   -    MD0100PA00X+154538Y+160961X0200Y         S0      
317GND              VIA   -    MD0100PA00X+153672Y+160332X0200Y         S0      
317GND              VIA   -    MD0100PA00X+153672Y+159858X0200Y         S0      
317GND              VIA   -    MD0100PA00X+153672Y+160921X0200Y         S0      
317GND              VIA   -    MD0100PA00X+154538Y+158952X0200Y         S0      
317GND              VIA   -    MD0100PA00X+154538Y+159425X0200Y         S0      
327GND              PEX3  -AT10       A01X+155000Y+112382X0180Y         S1      
327GND              PEX3  -AT11       A01X+155374Y+112382X0180Y         S1      
327GND              PEX3  -AT12       A01X+155748Y+112382X0180Y         S1      
327GND              PEX3  -AT13       A01X+156122Y+112382X0180Y         S1      
327GND              PEX3  -AU10       A01X+155000Y+112008X0180Y         S1      
327GND              PEX3  -AU11       A01X+155374Y+112008X0180Y         S1      
327GND              PEX3  -AU12       A01X+155748Y+112008X0180Y         S1      
327GND              PEX3  -AU13       A01X+156122Y+112008X0180Y         S1      
327GND              PEX3  -AV10       A01X+155000Y+111634X0180Y         S1      
327GND              PEX3  -AV11       A01X+155374Y+111634X0180Y         S1      
327GND              PEX3  -AF11       A01X+155374Y+116122X0180Y         S1      
327GND              PEX3  -AG10       A01X+155000Y+115748X0180Y         S1      
327GND              PEX3  -AF13       A01X+156122Y+116122X0180Y         S1      
327GND              PEX3  -AJ11       A01X+155374Y+115000X0180Y         S1      
327GND              PEX3  -AK11       A01X+155374Y+114626X0180Y         S1      
327GND              PEX3  -AK13       A01X+156122Y+114626X0180Y         S1      
327GND              PEX3  -AH11       A01X+155374Y+115374X0180Y         S1      
327GND              PEX3  -AG11       A01X+155374Y+115748X0180Y         S1      
327GND              PEX3  -AM10       A01X+155000Y+113878X0180Y         S1      
327GND              PEX3  -AM11       A01X+155374Y+113878X0180Y         S1      
327GND              PEX3  -AM13       A01X+156122Y+113878X0180Y         S1      
327GND              PEX3  -AN10M      A01X+155000Y+113504X0180Y         S1      
327GND              PEX3  -AN11       A01X+155374Y+113504X0180Y         S1      
327GND              PEX3  -AN12       A01X+155748Y+113504X0180Y         S1      
327GND              PEX3  -AN13       A01X+156122Y+113504X0180Y         S1      
327GND              PEX3  -AP10       A01X+155000Y+113130X0180Y         S1      
327GND              PEX3  -AP11       A01X+155374Y+113130X0180Y         S1      
327GND              PEX3  -AP12       A01X+155748Y+113130X0180Y         S1      
327GND              PEX3  -AP13       A01X+156122Y+113130X0180Y         S1      
327GND              PEX3  -AR10       A01X+155000Y+112756X0180Y         S1      
327GND              PEX3  -AR11       A01X+155374Y+112756X0180Y         S1      
327GND              PEX3  -AR12       A01X+155748Y+112756X0180Y         S1      
327GND              PEX3  -AR13       A01X+156122Y+112756X0180Y         S1      
317GND              VIA   -    MD0100PA00X+155200Y+164498X0200Y         S0      
327GND              PEX3  -AT16       A01X+157244Y+112382X0180Y         S1      
327GND              PEX3  -AU15       A01X+156870Y+112008X0180Y         S1      
327GND              PEX3  -AU16       A01X+157244Y+112008X0180Y         S1      
327GND              PEX3  -AG14M      A01X+156496Y+115748X0180Y         S1      
327GND              PEX3  -AF15       A01X+156870Y+116122X0180Y         S1      
327GND              PEX3  -AH13M      A01X+156122Y+115374X0180Y         S1      
327GND              PEX3  -AJ14M      A01X+156496Y+115000X0180Y         S1      
327GND              PEX3  -AH15M      A01X+156870Y+115374X0180Y         S1      
327GND              PEX3  -AG16M      A01X+157244Y+115748X0180Y         S1      
327GND              PEX3  -AF17       A01X+157618Y+116122X0180Y         S1      
327GND              PEX3  -AR16       A01X+157244Y+112756X0180Y         S1      
327GND              PEX3  -AT15       A01X+156870Y+112382X0180Y         S1      
317GND              VIA   -    MD0100PA00X+157200Y+164498X0200Y         S0      
327GND              PEX3  -M21        A01X+159114Y+121358X0180Y         S1      
327GND              PEX3  -AF19       A01X+158366Y+116122X0180Y         S1      
327GND              PEX3  -AG18M      A01X+157992Y+115748X0180Y         S1      
327GND              PEX3  -AE20       A01X+158740Y+116496X0180Y         S1      
327GND              PEX3  -AD19M      A01X+158366Y+116870X0180Y         S1      
327GND              PEX3  -AC18M      A01X+157992Y+117244X0180Y         S1      
327GND              PEX3  -AD21M      A01X+159114Y+116870X0180Y         S1      
327GND              PEX3  -AC20M      A01X+158740Y+117244X0180Y         S1      
327GND              PEX3  -AE22       A01X+159488Y+116496X0180Y         S1      
327GND              PEX3  -AG20M      A01X+158740Y+115748X0180Y         S1      
327GND              PEX3  -AF21       A01X+159114Y+116122X0180Y         S1      
317GND              VIA   -    MD0100PA00X+159159Y+150513X0200Y         S0      
327GND              C3997 -1          A01X+159431Y+150513X0198Y0197R270 S1      
317GND              VIA   -    MD0100PA00X+159161Y+146994X0200Y         S0      
327GND              C3996 -1          A01X+159426Y+146994X0198Y0197R090 S1      
327GND              PEX3  -AL17M      A01X+157618Y+114252X0180Y         S1      
327GND              PEX3  -AL16M      A01X+157244Y+114252X0180Y         S1      
327GND              PEX3  -AL22M      A01X+159488Y+114252X0180Y         S1      
327GND              PEX3  -AL23M      A01X+159862Y+114252X0180Y         S1      
327GND              PEX3  -AL24       A01X+160236Y+114252X0180Y         S1      
327GND              PEX3  -AL18M      A01X+157992Y+114252X0180Y         S1      
327GND              PEX3  -AL19M      A01X+158366Y+114252X0180Y         S1      
327GND              PEX3  -AL20M      A01X+158740Y+114252X0180Y         S1      
327GND              PEX3  -AL21M      A01X+159114Y+114252X0180Y         S1      
327GND              PEX3  -AR15M      A01X+156870Y+112756X0180Y         S1      
327GND              PEX3  -AP15M      A01X+156870Y+113130X0180Y         S1      
327GND              PEX3  -AM15       A01X+156870Y+113878X0180Y         S1      
327GND              PEX3  -AN15M      A01X+156870Y+113504X0180Y         S1      
327GND              PEX3  -AN16M      A01X+157244Y+113504X0180Y         S1      
327GND              PEX3  -AN17M      A01X+157618Y+113504X0180Y         S1      
327GND              PEX3  -AN18M      A01X+157992Y+113504X0180Y         S1      
327GND              PEX3  -AN19M      A01X+158366Y+113504X0180Y         S1      
327GND              PEX3  -AN20M      A01X+158740Y+113504X0180Y         S1      
327GND              PEX3  -AN21M      A01X+159114Y+113504X0180Y         S1      
327GND              PEX3  -AN23M      A01X+159862Y+113504X0180Y         S1      
327GND              PEX3  -AN24       A01X+160236Y+113504X0180Y         S1      
327GND              PEX3  -AN22M      A01X+159488Y+113504X0180Y         S1      
327GND              R1459 -2          A18X+159521Y+121703X0198Y0197R270 S2      
327GND              PEX3  -AC24       A01X+160236Y+117244X0180Y         S1      
327GND              PEX3  -AD25       A01X+160610Y+116870X0180Y         S1      
327GND              PEX3  -AC26M      A01X+160984Y+117244X0180Y         S1      
327GND              PEX3  -AG22M      A01X+159488Y+115748X0180Y         S1      
327GND              PEX3  -AF23       A01X+159862Y+116122X0180Y         S1      
327GND              PEX3  -AE24       A01X+160236Y+116496X0180Y         S1      
327GND              PEX3  -AD23M      A01X+159862Y+116870X0180Y         S1      
327GND              PEX3  -AC22M      A01X+159488Y+117244X0180Y         S1      
327GND              PEX3  -AF25       A01X+160610Y+116122X0180Y         S1      
327GND              PEX3  -AG26M      A01X+160984Y+115748X0180Y         S1      
327GND              PEX3  -AG24       A01X+160236Y+115748X0180Y         S1      
327GND              PEX3  -AK15M      A01X+156870Y+114626X0180Y         S1      
327GND              PEX3  -AJ17M      A01X+157618Y+115000X0180Y         S1      
327GND              PEX3  -AJ16M      A01X+157244Y+115000X0180Y         S1      
327GND              PEX3  -AJ18M      A01X+157992Y+115000X0180Y         S1      
327GND              PEX3  -AJ19M      A01X+158366Y+115000X0180Y         S1      
327GND              PEX3  -AJ20M      A01X+158740Y+115000X0180Y         S1      
327GND              PEX3  -AJ21M      A01X+159114Y+115000X0180Y         S1      
327GND              PEX3  -AJ24       A01X+160236Y+115000X0180Y         S1      
327GND              PEX3  -AJ23M      A01X+159862Y+115000X0180Y         S1      
327GND              PEX3  -AJ22M      A01X+159488Y+115000X0180Y         S1      
317GND              VIA   -    MD0100PA00X+161986Y+083952X0200Y         S0      
317GND              VIA   -    MD0100PA00X+160400Y+151600X0200Y         S0      
317GND              VIA   -    MD0100PA00X+159800Y+148600X0200Y         S0      
317GND              VIA   -    MD0100PA00X+160258Y+148311X0200Y         S0      
327GND              U422  -4          A01X+160258Y+147919X0240Y0460R180 S1      
317GND              VIA   -    MD0100PA00X+159850Y+147250X0200Y         S0      
327GND              PEX3  -AE28       A01X+161732Y+116496X0180Y         S1      
327GND              PEX3  -AD29M      A01X+162106Y+116870X0180Y         S1      
327GND              PEX3  -AC30M      A01X+162480Y+117244X0180Y         S1      
327GND              PEX3  -AE26       A01X+160984Y+116496X0180Y         S1      
327GND              PEX3  -AC28M      A01X+161732Y+117244X0180Y         S1      
327GND              PEX3  -AD27M      A01X+161358Y+116870X0180Y         S1      
327GND              PEX3  -AG30M      A01X+162480Y+115748X0180Y         S1      
327GND              PEX3  -AF29       A01X+162106Y+116122X0180Y         S1      
327GND              PEX3  -AG28M      A01X+161732Y+115748X0180Y         S1      
327GND              PEX3  -AF27       A01X+161358Y+116122X0180Y         S1      
327GND              PEX3  -AE32       A01X+163228Y+116496X0180Y         S1      
327GND              PEX3  -AF31       A01X+162854Y+116122X0180Y         S1      
327GND              PEX3  -AG32M      A01X+163228Y+115748X0180Y         S1      
327GND              PEX3  -AN25       A01X+160610Y+113504X0180Y         S1      
327GND              PEX3  -AN27M      A01X+161358Y+113504X0180Y         S1      
327GND              PEX3  -AN28M      A01X+161732Y+113504X0180Y         S1      
327GND              PEX3  -AN29M      A01X+162106Y+113504X0180Y         S1      
327GND              PEX3  -AN30M      A01X+162480Y+113504X0180Y         S1      
327GND              PEX3  -AN31M      A01X+162854Y+113504X0180Y         S1      
327GND              PEX3  -AN32M      A01X+163228Y+113504X0180Y         S1      
327GND              PEX3  -AN33M      A01X+163602Y+113504X0180Y         S1      
327GND              PEX3  -AN34M      A01X+163976Y+113504X0180Y         S1      
327GND              PEX3  -AM34       A01X+163976Y+113878X0180Y         S1      
327GND              PEX3  -AN35M      A01X+164350Y+113504X0180Y         S1      
327GND              PEX3  -AN26M      A01X+160984Y+113504X0180Y         S1      
327GND              PEX3  -AA26M      A01X+160984Y+117992X0180Y         S1      
327GND              PEX3  -AA28M      A01X+161732Y+117992X0180Y         S1      
327GND              PEX3  -AA27M      A01X+161358Y+117992X0180Y         S1      
327GND              PEX3  -AA29M      A01X+162106Y+117992X0180Y         S1      
327GND              PEX3  -AA30M      A01X+162480Y+117992X0180Y         S1      
327GND              PEX3  -Y34 M      A01X+163976Y+118366X0180Y         S1      
327GND              PEX3  -AA33M      A01X+163602Y+117992X0180Y         S1      
327GND              PEX3  -AA32M      A01X+163228Y+117992X0180Y         S1      
327GND              PEX3  -AA31M      A01X+162854Y+117992X0180Y         S1      
327GND              PEX3  -AA25       A01X+160610Y+117992X0180Y         S1      
327GND              PEX3  -AD31M      A01X+162854Y+116870X0180Y         S1      
327GND              PEX3  -AC32M      A01X+163228Y+117244X0180Y         S1      
327GND              PEX3  -AE30       A01X+162480Y+116496X0180Y         S1      
317GND              VIA   -    MD0100PA00X+164957Y+098386X0200Y         S0      
317GND              VIA   -    MD0100PA00X+165709Y+099082X0200Y         S0      
327GND              PEX3  -W38        A01X+165472Y+118740X0180Y         S1      
327GND              PEX3  -AF37       A01X+165098Y+116122X0180Y         S1      
327GND              PEX3  -AG37       A01X+165098Y+115748X0180Y         S1      
317GND              VIA   -    MD0100PA00X+165798Y+148087X0200Y         S0      
317GND              VIA   -    MD0100PA00X+164932Y+148127X0200Y         S0      
317GND              VIA   -    MD0100PA00X+164932Y+147180X0200Y         S0      
317GND              VIA   -    MD0100PA00X+165798Y+147024X0200Y         S0      
317GND              VIA   -    MD0100PA00X+165798Y+147614X0200Y         S0      
317GND              VIA   -    MD0100PA00X+164932Y+147654X0200Y         S0      
317GND              VIA   -    MD0100PA00X+164932Y+146118X0200Y         S0      
317GND              VIA   -    MD0100PA00X+165798Y+146551X0200Y         S0      
317GND              VIA   -    MD0100PA00X+164932Y+146591X0200Y         S0      
317GND              VIA   -    MD0100PA00X+164932Y+145645X0200Y         S0      
317GND              VIA   -    MD0100PA00X+165798Y+146078X0200Y         S0      
317GND              VIA   -    MD0100PA00X+165798Y+156314X0200Y         S0      
317GND              VIA   -    MD0100PA00X+164932Y+156354X0200Y         S0      
317GND              VIA   -    MD0100PA00X+164932Y+155881X0200Y         S0      
317GND              VIA   -    MD0100PA00X+165798Y+151631X0200Y         S0      
317GND              VIA   -    MD0100PA00X+165798Y+150684X0200Y         S0      
317GND              VIA   -    MD0100PA00X+164932Y+150724X0200Y         S0      
317GND              VIA   -    MD0100PA00X+164932Y+151198X0200Y         S0      
317GND              VIA   -    MD0100PA00X+165798Y+151158X0200Y         S0      
317GND              VIA   -    MD0100PA00X+164932Y+150251X0200Y         S0      
317GND              VIA   -    MD0100PA00X+165798Y+150095X0200Y         S0      
317GND              VIA   -    MD0100PA00X+165798Y+148560X0200Y         S0      
317GND              VIA   -    MD0100PA00X+165798Y+149149X0200Y         S0      
317GND              VIA   -    MD0100PA00X+164932Y+149189X0200Y         S0      
317GND              VIA   -    MD0100PA00X+165798Y+149622X0200Y         S0      
317GND              VIA   -    MD0100PA00X+164932Y+149662X0200Y         S0      
317GND              VIA   -    MD0100PA00X+164932Y+148716X0200Y         S0      
317GND              VIA   -    MD0100PA00X+165798Y+161867X0200Y         S0      
317GND              VIA   -    MD0100PA00X+165798Y+161394X0200Y         S0      
317GND              VIA   -    MD0100PA00X+164932Y+161434X0200Y         S0      
317GND              VIA   -    MD0100PA00X+164932Y+160488X0200Y         S0      
317GND              VIA   -    MD0100PA00X+165798Y+160332X0200Y         S0      
317GND              VIA   -    MD0100PA00X+165798Y+159858X0200Y         S0      
317GND              VIA   -    MD0100PA00X+164932Y+159898X0200Y         S0      
317GND              VIA   -    MD0100PA00X+165798Y+160921X0200Y         S0      
317GND              VIA   -    MD0100PA00X+164932Y+160961X0200Y         S0      
317GND              VIA   -    MD0100PA00X+164932Y+158952X0200Y         S0      
317GND              VIA   -    MD0100PA00X+165798Y+158796X0200Y         S0      
317GND              VIA   -    MD0100PA00X+165798Y+159385X0200Y         S0      
317GND              VIA   -    MD0100PA00X+164932Y+159425X0200Y         S0      
317GND              VIA   -    MD0100PA00X+165798Y+158323X0200Y         S0      
317GND              VIA   -    MD0100PA00X+164932Y+158363X0200Y         S0      
317GND              VIA   -    MD0100PA00X+165798Y+157850X0200Y         S0      
317GND              VIA   -    MD0100PA00X+164932Y+157890X0200Y         S0      
317GND              VIA   -    MD0100PA00X+165798Y+156788X0200Y         S0      
317GND              VIA   -    MD0100PA00X+164932Y+156828X0200Y         S0      
317GND              VIA   -    MD0100PA00X+164932Y+157417X0200Y         S0      
317GND              VIA   -    MD0100PA00X+165798Y+157261X0200Y         S0      
317GND              VIA   -    MD0100PA00X+165200Y+164498X0200Y         S0      
327GND              R1448 -2          A18X+166270Y+117648X0198Y0197R090 S2      
327GND              R1447 -2          A18X+166270Y+118711X0198Y0197R270 S2      
317GND              VIA   -    MD0100PA00X+167531Y+150095X0200Y         S0      
317GND              VIA   -    MD0100PA00X+167531Y+149622X0200Y         S0      
317GND              VIA   -    MD0100PA00X+167531Y+148560X0200Y         S0      
317GND              VIA   -    MD0100PA00X+167531Y+149149X0200Y         S0      
317GND              VIA   -    MD0100PA00X+166664Y+149662X0200Y         S0      
317GND              VIA   -    MD0100PA00X+166664Y+149189X0200Y         S0      
317GND              VIA   -    MD0100PA00X+166664Y+148716X0200Y         S0      
317GND              VIA   -    MD0100PA00X+167531Y+148087X0200Y         S0      
317GND              VIA   -    MD0100PA00X+167531Y+147024X0200Y         S0      
317GND              VIA   -    MD0100PA00X+167531Y+147614X0200Y         S0      
317GND              VIA   -    MD0100PA00X+166664Y+148127X0200Y         S0      
317GND              VIA   -    MD0100PA00X+166664Y+147654X0200Y         S0      
317GND              VIA   -    MD0100PA00X+166664Y+147180X0200Y         S0      
317GND              VIA   -    MD0100PA00X+167531Y+146078X0200Y         S0      
317GND              VIA   -    MD0100PA00X+167531Y+146551X0200Y         S0      
317GND              VIA   -    MD0100PA00X+166664Y+146118X0200Y         S0      
317GND              VIA   -    MD0100PA00X+166664Y+145645X0200Y         S0      
317GND              VIA   -    MD0100PA00X+166664Y+146591X0200Y         S0      
317GND              VIA   -    MD0100PA00X+167531Y+161867X0200Y         S0      
317GND              VIA   -    MD0100PA00X+167531Y+161394X0200Y         S0      
317GND              VIA   -    MD0100PA00X+166664Y+161434X0200Y         S0      
317GND              VIA   -    MD0100PA00X+166664Y+160961X0200Y         S0      
317GND              VIA   -    MD0100PA00X+167531Y+160332X0200Y         S0      
317GND              VIA   -    MD0100PA00X+167531Y+159858X0200Y         S0      
317GND              VIA   -    MD0100PA00X+167531Y+160921X0200Y         S0      
317GND              VIA   -    MD0100PA00X+166664Y+159898X0200Y         S0      
317GND              VIA   -    MD0100PA00X+166664Y+160488X0200Y         S0      
317GND              VIA   -    MD0100PA00X+167531Y+158796X0200Y         S0      
317GND              VIA   -    MD0100PA00X+167531Y+159385X0200Y         S0      
317GND              VIA   -    MD0100PA00X+166664Y+159425X0200Y         S0      
317GND              VIA   -    MD0100PA00X+166664Y+158952X0200Y         S0      
317GND              VIA   -    MD0100PA00X+167531Y+158323X0200Y         S0      
317GND              VIA   -    MD0100PA00X+166664Y+158363X0200Y         S0      
317GND              VIA   -    MD0100PA00X+166664Y+157890X0200Y         S0      
317GND              VIA   -    MD0100PA00X+166664Y+157417X0200Y         S0      
317GND              VIA   -    MD0100PA00X+167531Y+156788X0200Y         S0      
317GND              VIA   -    MD0100PA00X+166664Y+156828X0200Y         S0      
317GND              VIA   -    MD0100PA00X+167531Y+157261X0200Y         S0      
317GND              VIA   -    MD0100PA00X+167531Y+157850X0200Y         S0      
317GND              VIA   -    MD0100PA00X+167531Y+156314X0200Y         S0      
317GND              VIA   -    MD0100PA00X+166664Y+156354X0200Y         S0      
317GND              VIA   -    MD0100PA00X+166664Y+155881X0200Y         S0      
317GND              VIA   -    MD0100PA00X+167531Y+151631X0200Y         S0      
317GND              VIA   -    MD0100PA00X+167531Y+150684X0200Y         S0      
317GND              VIA   -    MD0100PA00X+166664Y+150251X0200Y         S0      
317GND              VIA   -    MD0100PA00X+166664Y+150724X0200Y         S0      
317GND              VIA   -    MD0100PA00X+166664Y+151198X0200Y         S0      
317GND              VIA   -    MD0100PA00X+167531Y+151158X0200Y         S0      
317GND              VIA   -    MD0100PA00X+167200Y+164498X0200Y         S0      
327GND              PEX3  -AF44       A01X+167716Y+116122X0180Y         S1      
317GND              VIA   -    MD0100PA00X+169263Y+148087X0200Y         S0      
317GND              VIA   -    MD0100PA00X+169263Y+147024X0200Y         S0      
317GND              VIA   -    MD0100PA00X+169263Y+147614X0200Y         S0      
317GND              VIA   -    MD0100PA00X+168397Y+148127X0200Y         S0      
317GND              VIA   -    MD0100PA00X+168397Y+147654X0200Y         S0      
317GND              VIA   -    MD0100PA00X+168397Y+147180X0200Y         S0      
317GND              VIA   -    MD0100PA00X+169263Y+146078X0200Y         S0      
317GND              VIA   -    MD0100PA00X+169263Y+146551X0200Y         S0      
317GND              VIA   -    MD0100PA00X+168397Y+146118X0200Y         S0      
317GND              VIA   -    MD0100PA00X+168397Y+145645X0200Y         S0      
317GND              VIA   -    MD0100PA00X+168397Y+146591X0200Y         S0      
317GND              VIA   -    MD0100PA00X+169263Y+157850X0200Y         S0      
317GND              VIA   -    MD0100PA00X+169263Y+156788X0200Y         S0      
317GND              VIA   -    MD0100PA00X+168397Y+157890X0200Y         S0      
317GND              VIA   -    MD0100PA00X+168397Y+157417X0200Y         S0      
317GND              VIA   -    MD0100PA00X+168397Y+156828X0200Y         S0      
317GND              VIA   -    MD0100PA00X+169263Y+157261X0200Y         S0      
317GND              VIA   -    MD0100PA00X+169263Y+156314X0200Y         S0      
317GND              VIA   -    MD0100PA00X+168397Y+156354X0200Y         S0      
317GND              VIA   -    MD0100PA00X+168397Y+155881X0200Y         S0      
317GND              VIA   -    MD0100PA00X+169263Y+151631X0200Y         S0      
317GND              VIA   -    MD0100PA00X+168397Y+150724X0200Y         S0      
317GND              VIA   -    MD0100PA00X+169263Y+151158X0200Y         S0      
317GND              VIA   -    MD0100PA00X+169263Y+150095X0200Y         S0      
317GND              VIA   -    MD0100PA00X+169263Y+150684X0200Y         S0      
317GND              VIA   -    MD0100PA00X+168397Y+151198X0200Y         S0      
317GND              VIA   -    MD0100PA00X+168397Y+150251X0200Y         S0      
317GND              VIA   -    MD0100PA00X+169263Y+149622X0200Y         S0      
317GND              VIA   -    MD0100PA00X+169263Y+148560X0200Y         S0      
317GND              VIA   -    MD0100PA00X+169263Y+149149X0200Y         S0      
317GND              VIA   -    MD0100PA00X+168397Y+149662X0200Y         S0      
317GND              VIA   -    MD0100PA00X+168397Y+149189X0200Y         S0      
317GND              VIA   -    MD0100PA00X+168397Y+148716X0200Y         S0      
317GND              VIA   -    MD0100PA00X+169200Y+164498X0200Y         S0      
317GND              VIA   -    MD0100PA00X+169263Y+161867X0200Y         S0      
317GND              VIA   -    MD0100PA00X+169263Y+161394X0200Y         S0      
317GND              VIA   -    MD0100PA00X+168397Y+161434X0200Y         S0      
317GND              VIA   -    MD0100PA00X+168397Y+160488X0200Y         S0      
317GND              VIA   -    MD0100PA00X+168397Y+160961X0200Y         S0      
317GND              VIA   -    MD0100PA00X+169263Y+160332X0200Y         S0      
317GND              VIA   -    MD0100PA00X+169263Y+159858X0200Y         S0      
317GND              VIA   -    MD0100PA00X+169263Y+160921X0200Y         S0      
317GND              VIA   -    MD0100PA00X+168397Y+159898X0200Y         S0      
317GND              VIA   -    MD0100PA00X+169263Y+158796X0200Y         S0      
317GND              VIA   -    MD0100PA00X+169263Y+159385X0200Y         S0      
317GND              VIA   -    MD0100PA00X+169263Y+158323X0200Y         S0      
317GND              VIA   -    MD0100PA00X+168397Y+159425X0200Y         S0      
317GND              VIA   -    MD0100PA00X+168397Y+158952X0200Y         S0      
317GND              VIA   -    MD0100PA00X+168397Y+158363X0200Y         S0      
317GND              VIA   -    MD0100PA00X+171178Y+119385X0200Y         S0      
317GND              VIA   -    MD0100PA00X+170129Y+148127X0200Y         S0      
317GND              VIA   -    MD0100PA00X+170129Y+147654X0200Y         S0      
317GND              VIA   -    MD0100PA00X+170129Y+147180X0200Y         S0      
317GND              VIA   -    MD0100PA00X+170129Y+146118X0200Y         S0      
317GND              VIA   -    MD0100PA00X+170129Y+145645X0200Y         S0      
317GND              VIA   -    MD0100PA00X+170129Y+146591X0200Y         S0      
317GND              VIA   -    MD0100PA00X+170129Y+157890X0200Y         S0      
317GND              VIA   -    MD0100PA00X+170129Y+157417X0200Y         S0      
317GND              VIA   -    MD0100PA00X+170129Y+156828X0200Y         S0      
317GND              VIA   -    MD0100PA00X+170129Y+156354X0200Y         S0      
317GND              VIA   -    MD0100PA00X+170129Y+155881X0200Y         S0      
317GND              VIA   -    MD0100PA00X+170129Y+151198X0200Y         S0      
317GND              VIA   -    MD0100PA00X+170129Y+150251X0200Y         S0      
317GND              VIA   -    MD0100PA00X+170129Y+150724X0200Y         S0      
317GND              VIA   -    MD0100PA00X+170129Y+149662X0200Y         S0      
317GND              VIA   -    MD0100PA00X+170129Y+149189X0200Y         S0      
317GND              VIA   -    MD0100PA00X+170129Y+148716X0200Y         S0      
317GND              VIA   -    MD0100PA00X+172166Y+119302X0200Y         S0      
327GND              R1450 -1          A01X+172166Y+119542X0198Y0197R090 S1      
317GND              VIA   -    MD0100PA00X+172566Y+119302X0200Y         S0      
317GND              VIA   -    MD0100PA00X+172380Y+116017X0200Y         S0      
317GND              VIA   -    MD0100PA00X+170129Y+161434X0200Y         S0      
317GND              VIA   -    MD0100PA00X+170129Y+159898X0200Y         S0      
317GND              VIA   -    MD0100PA00X+170129Y+160488X0200Y         S0      
317GND              VIA   -    MD0100PA00X+170129Y+160961X0200Y         S0      
317GND              VIA   -    MD0100PA00X+170129Y+159425X0200Y         S0      
317GND              VIA   -    MD0100PA00X+170129Y+158952X0200Y         S0      
317GND              VIA   -    MD0100PA00X+170129Y+158363X0200Y         S0      
317GND              VIA   -    MD0100PA00X+171861Y+150725X0200Y         S0      
317GND              VIA   -    MD0100PA00X+170995Y+151158X0200Y         S0      
317GND              VIA   -    MD0100PA00X+170995Y+150095X0200Y         S0      
317GND              VIA   -    MD0100PA00X+170995Y+150684X0200Y         S0      
317GND              VIA   -    MD0100PA00X+171861Y+149662X0200Y         S0      
317GND              VIA   -    MD0100PA00X+171861Y+148716X0200Y         S0      
317GND              VIA   -    MD0100PA00X+171861Y+149189X0200Y         S0      
317GND              VIA   -    MD0100PA00X+170995Y+149622X0200Y         S0      
317GND              VIA   -    MD0100PA00X+170995Y+148560X0200Y         S0      
317GND              VIA   -    MD0100PA00X+170995Y+149149X0200Y         S0      
317GND              VIA   -    MD0100PA00X+170995Y+148087X0200Y         S0      
317GND              VIA   -    MD0100PA00X+170995Y+147024X0200Y         S0      
317GND              VIA   -    MD0100PA00X+170995Y+147614X0200Y         S0      
317GND              VIA   -    MD0100PA00X+171861Y+148127X0200Y         S0      
317GND              VIA   -    MD0100PA00X+171861Y+147181X0200Y         S0      
317GND              VIA   -    MD0100PA00X+171861Y+147654X0200Y         S0      
317GND              VIA   -    MD0100PA00X+171861Y+146118X0200Y         S0      
317GND              VIA   -    MD0100PA00X+171861Y+145645X0200Y         S0      
317GND              VIA   -    MD0100PA00X+171861Y+146591X0200Y         S0      
317GND              VIA   -    MD0100PA00X+170995Y+146078X0200Y         S0      
317GND              VIA   -    MD0100PA00X+170995Y+146551X0200Y         S0      
317GND              VIA   -    MD0100PA00X+171200Y+164498X0200Y         S0      
317GND              VIA   -    MD0100PA00X+170995Y+161394X0200Y         S0      
317GND              VIA   -    MD0100PA00X+171861Y+161434X0200Y         S0      
317GND              VIA   -    MD0100PA00X+170995Y+161867X0200Y         S0      
317GND              VIA   -    MD0100PA00X+170995Y+160332X0200Y         S0      
317GND              VIA   -    MD0100PA00X+170995Y+159858X0200Y         S0      
317GND              VIA   -    MD0100PA00X+170995Y+160921X0200Y         S0      
317GND              VIA   -    MD0100PA00X+171861Y+160488X0200Y         S0      
317GND              VIA   -    MD0100PA00X+171861Y+159898X0200Y         S0      
317GND              VIA   -    MD0100PA00X+171861Y+160961X0200Y         S0      
317GND              VIA   -    MD0100PA00X+171861Y+159425X0200Y         S0      
317GND              VIA   -    MD0100PA00X+170995Y+158796X0200Y         S0      
317GND              VIA   -    MD0100PA00X+170995Y+159385X0200Y         S0      
317GND              VIA   -    MD0100PA00X+171861Y+158363X0200Y         S0      
317GND              VIA   -    MD0100PA00X+170995Y+158323X0200Y         S0      
317GND              VIA   -    MD0100PA00X+171861Y+158952X0200Y         S0      
317GND              VIA   -    MD0100PA00X+171861Y+157417X0200Y         S0      
317GND              VIA   -    MD0100PA00X+171861Y+157890X0200Y         S0      
317GND              VIA   -    MD0100PA00X+170995Y+157261X0200Y         S0      
317GND              VIA   -    MD0100PA00X+170995Y+157850X0200Y         S0      
317GND              VIA   -    MD0100PA00X+171861Y+156828X0200Y         S0      
317GND              VIA   -    MD0100PA00X+170995Y+156788X0200Y         S0      
317GND              VIA   -    MD0100PA00X+171861Y+155881X0200Y         S0      
317GND              VIA   -    MD0100PA00X+171861Y+156354X0200Y         S0      
317GND              VIA   -    MD0100PA00X+170995Y+156314X0200Y         S0      
317GND              VIA   -    MD0100PA00X+170995Y+151631X0200Y         S0      
317GND              VIA   -    MD0100PA00X+171861Y+151198X0200Y         S0      
317GND              VIA   -    MD0100PA00X+171861Y+150252X0200Y         S0      
317GND              VIA   -    MD0100PA00X+174078Y+121925X0200Y         S0      
327GND              R1449 -1          A01X+173597Y+122407X0198Y0197R135 S1      
317GND              VIA   -    M      A01X+173162Y+121009X0200Y         S2      
017GND              VIA   -    M      A18X+173162Y+121009X0260Y         S2      
017GND                    -    MD0100PA00X+173162Y+121009                       
317GND              VIA   -    MD0100PA00X+173599Y+121446X0200Y         S0      
317GND              VIA   -    MD0100PA00X+173370Y+121216X0200Y         S0      
317GND              VIA   -    MD0100PA00X+173766Y+119302X0200Y         S0      
327GND              R4184 -1          A01X+173766Y+119542X0198Y0197R090 S1      
317GND              VIA   -    MD0100PA00X+172966Y+119302X0200Y         S0      
327GND              R1453 -1          A01X+172966Y+119542X0198Y0197R090 S1      
317GND              VIA   -    MD0100PA00X+173366Y+119302X0200Y         S0      
327GND              R1456 -1          A01X+173366Y+119542X0198Y0197R090 S1      
317GND              VIA   -    MD0100PA00X+173739Y+116282X0200Y         S0      
327GND              C2761 -1          A01X+173739Y+116522X0198Y0197R090 S1      
317GND              VIA   -    MD0100PA00X+172921Y+115946X0200Y         S0      
317GND              VIA   -    M      A01X+173992Y+114694X0200Y         S2      
017GND              VIA   -    M      A18X+173992Y+114694X0260Y         S2      
017GND                    -    MD0100PA00X+173992Y+114694                       
317GND              VIA   -    MD0100PA00X+172696Y+113232X0200Y         S0      
317GND              VIA   -    MD0100PA00X+173068Y+113236X0200Y         S0      
317GND              VIA   -    MD0100PA00X+174322Y+111906X0200Y         S0      
317GND              VIA   -    MD0100PA00X+175619Y+099613X0200Y         S0      
317GND              VIA   -    MD0100PA00X+174808Y+098438X0200Y         S0      
317GND              VIA   -    MD0100PA00X+175740Y+082016X0200Y         S0      
317GND              VIA   -    MD0100PA00X+175740Y+082511X0200Y         S0      
317GND              VIA   -    MD0100PA00X+173200Y+164498X0200Y         S0      
317GND              VIA   -    MD0100PA00X+176960Y+113082X0200Y         S0      
317GND              VIA   -    MD0100PA00X+177220Y+113082X0200Y         S0      
317GND              VIA   -    MD0100PA00X+176700Y+113082X0200Y         S0      
317GND              VIA   -    MD0100PA00X+177480Y+112112X0200Y         S0      
317GND              VIA   -    MD0100PA00X+177210Y+112112X0200Y         S0      
317GND              VIA   -    MD0100PA00X+176950Y+112112X0200Y         S0      
317GND              VIA   -    MD0100PA00X+176690Y+112112X0200Y         S0      
317GND              VIA   -    MD0100PA00X+176290Y+099288X0200Y         S0      
317GND              VIA   -    MD0100PA00X+177260Y+099305X0200Y         S0      
317GND              VIA   -    MD0100PA00X+176195Y+086516X0200Y         S0      
317GND              VIA   -    MD0100PA00X+177277Y+081870X0200Y    R090 S0      
317GND              VIA   -    MD0100PA00X+175200Y+164498X0200Y         S0      
317GND              VIA   -    MD0100PA00X+178040Y+123497X0200Y    R180 S0      
317GND              VIA   -    MD0100PA00X+178596Y+122489X0200Y         S0      
317GND              VIA   -    MD0100PA00X+178258Y+122500X0200Y    R270 S0      
317GND              VIA   -    MD0100PA00X+177958Y+122500X0200Y    R270 S0      
317GND              VIA   -    MD0100PA00X+178258Y+121380X0200Y    R270 S0      
317GND              VIA   -    MD0100PA00X+178258Y+121660X0200Y    R270 S0      
317GND              VIA   -    MD0100PA00X+178258Y+121940X0200Y    R270 S0      
317GND              VIA   -    MD0100PA00X+178258Y+122220X0200Y    R270 S0      
317GND              VIA   -    MD0100PA00X+177958Y+121380X0200Y    R270 S0      
317GND              VIA   -    MD0100PA00X+177958Y+121660X0200Y    R270 S0      
317GND              VIA   -    MD0100PA00X+177958Y+121940X0200Y    R270 S0      
317GND              VIA   -    MD0100PA00X+177958Y+122220X0200Y    R270 S0      
317GND              VIA   -    MD0100PA00X+177740Y+113982X0200Y         S0      
317GND              VIA   -    MD0100PA00X+177490Y+113982X0200Y         S0      
317GND              VIA   -    MD0100PA00X+177490Y+113082X0200Y         S0      
317GND              VIA   -    MD0100PA00X+179286Y+110325X0200Y         S0      
317GND              VIA   -    MD0100PA00X+177880Y+083647X0200Y    R090 S0      
317GND              VIA   -    MD0100PA00X+177200Y+164498X0200Y         S0      
317GND              VIA   -    MD0100PA00X+176714Y+158822X0200Y    R180 S0      
317GND              VIA   -    MD0100PA00X+175909Y+158814X0200Y    R180 S0      
317GND              VIA   -    MD0100PA00X+179200Y+164498X0200Y         S0      
317GND              VIA   -    MD0100PA00X+180284Y+122770X0200Y         S0      
317GND              VIA   -    MD0100PA00X+180115Y+120856X0200Y         S0      
327GND              PC281 -2          A01X+180935Y+120516X0198Y0197R270 S1      
327GND              PR182 -2   M      A01X+180538Y+120632X0198Y0197R270 S1      
317GND              VIA   -    MD0100PA00X+180128Y+121337X0200Y    R270 S0      
317GND              VIA   -    M      A01X+179661Y+120011X0200Y    R270 S2      
017GND              VIA   -    M      A18X+179661Y+120011X0260Y    R270 S2      
017GND                    -    MD0100PA00X+179661Y+120011                       
327GND              PC270 -2          A01X+179661Y+120276X0198Y0197     S1      
317GND              VIA   -    MD0100PA00X+180501Y+109647X0200Y         S0      
317GND              VIA   -    MD0100PA00X+179901Y+109589X0200Y         S0      
327GND              U95   -10         A01X+180184Y+109514X0090Y0240R090 S1      
317GND              VIA   -    MD0100PA00X+179285Y+109921X0200Y         S0      
327GND              C827  -2          A01X+179535Y+109921X0198Y0197R090 S1      
317GND              VIA   -    MD0100PA00X+180501Y+109188X0200Y         S0      
317GND              VIA   -    MD0100PA00X+179130Y+082903X0200Y    R090 S0      
317GND              VIA   -    M      A01X+179110Y+126042X0200Y         S2      
017GND              VIA   -    M      A18X+179110Y+126042X0260Y         S2      
017GND                    -    MD0100PA00X+179110Y+126042                       
317GND              VIA   -    MD0100PA00X+178040Y+124437X0200Y    R180 S0      
317GND              VIA   -    MD0100PA00X+178040Y+124187X0200Y    R180 S0      
317GND              VIA   -    MD0100PA00X+178040Y+122807X0200Y    R180 S0      
317GND              VIA   -    MD0100PA00X+178040Y+123057X0200Y    R180 S0      
317GND              VIA   -    MD0100PA00X+178040Y+123747X0200Y    R180 S0      
317GND              VIA   -    MD0100PA00X+183794Y+133324X0200Y    R270 S0      
317GND              VIA   -    MD0100PA00X+183794Y+131324X0200Y    R270 S0      
317GND              VIA   -    MD0100PA00X+183794Y+129324X0200Y    R270 S0      
317GND              VIA   -    MD0100PA00X+183794Y+127324X0200Y    R270 S0      
317GND              VIA   -    MD0100PA00X+183794Y+125324X0200Y    R270 S0      
317GND              VIA   -    MD0100PA00X+183794Y+121324X0200Y    R270 S0      
317GND              VIA   -    MD0100PA00X+183794Y+119324X0200Y    R270 S0      
317GND              VIA   -    MD0100PA00X+183794Y+117324X0200Y    R270 S0      
317GND              VIA   -    MD0100PA00X+183794Y+115324X0200Y    R270 S0      
317GND              VIA   -    MD0100PA00X+183794Y+113324X0200Y    R270 S0      
317GND              VIA   -    MD0100PA00X+183794Y+111324X0200Y    R270 S0      
317GND              VIA   -    MD0100PA00X+183794Y+109324X0200Y    R270 S0      
317GND              VIA   -    MD0100PA00X+182473Y+110283X0200Y    R270 S0      
317GND              VIA   -    MD0100PA00X+182471Y+108914X0200Y         S0      
327GND              R807  -2          A01X+182231Y+108914X0198Y0197     S1      
317GND              VIA   -    MD0100PA00X+182471Y+108114X0200Y         S0      
327GND              R806  -2          A01X+182231Y+108114X0198Y0197     S1      
317GND              VIA   -    MD0100PA00X+183794Y+107324X0200Y    R270 S0      
317GND              VIA   -    MD0100PA00X+183794Y+105324X0200Y    R270 S0      
317GND              VIA   -    MD0100PA00X+183794Y+103324X0200Y    R270 S0      
317GND              VIA   -    MD0100PA00X+183794Y+101324X0200Y    R270 S0      
317GND              VIA   -    MD0100PA00X+183794Y+099324X0200Y    R270 S0      
317GND              VIA   -    MD0100PA00X+183794Y+097324X0200Y    R270 S0      
317GND              VIA   -    MD0100PA00X+183047Y+096097X0200Y    R270 S0      
317GND              VIA   -    MD0100PA00X+181200Y+164498X0200Y         S0      
317GND              VIA   -    MD0100PA00X+180990Y+124668X0200Y         S0      
317GND              VIA   -    MD0100PA00X+180990Y+124418X0200Y         S0      
317GND              VIA   -    MD0100PA00X+180990Y+123978X0200Y         S0      
317GND              VIA   -    MD0100PA00X+180990Y+123288X0200Y         S0      
317GND              VIA   -    MD0100PA00X+180990Y+123038X0200Y         S0      
317GND              VIA   -    MD0100PA00X+180990Y+123728X0200Y         S0      
317GND              VIA   -    MD0100PA00X+182259Y+121105X0200Y         S0      
327GND              PJ16  -2          A01X+182018Y+121105X0180Y0200R180 S1      
317GND              VIA   -    MD0100PA00X+181586Y+113336X0200Y         S0      
317GND              VIA   -    MD0100PA00X+181388Y+113691X0200Y    R090 S0      
317GND              VIA   -    MD0100PA00X+181763Y+111459X0200Y         S0      
317GND              VIA   -    MD0100PA00X+181503Y+111459X0200Y         S0      
317GND              VIA   -    MD0100PA00X+182023Y+111459X0200Y         S0      
317GND              VIA   -    MD0100PA00X+182293Y+111459X0200Y         S0      
317GND              VIA   -    MD0100PA00X+182033Y+112429X0200Y         S0      
317GND              VIA   -    MD0100PA00X+181513Y+112429X0200Y         S0      
317GND              VIA   -    MD0100PA00X+181773Y+112429X0200Y         S0      
317GND              VIA   -    MD0100PA00X+182303Y+112429X0200Y         S0      
317GND              VIA   -    MD0100PA00X+180965Y+109643X0200Y         S0      
317GND              VIA   -    MD0100PA00X+180970Y+109183X0200Y         S0      
327GND              U95   -TH  M      A01X+180735Y+109416X0670Y0670R180 S1      
317GND              VIA   -    MD0100PA00X+182298Y+094605X0200Y    R270 S0      
317GND              VIA   -    MD0100PA00X+182298Y+092605X0200Y    R270 S0      
317GND              VIA   -    MD0100PA00X+182298Y+090605X0200Y    R270 S0      
317GND              VIA   -    MD0100PA00X+182298Y+088605X0200Y    R270 S0      
317GND              VIA   -    MD0100PA00X+182298Y+086605X0200Y    R270 S0      
317GND              VIA   -    MD0100PA00X+182298Y+084605X0200Y    R270 S0      
317GND              VIA   -    MD0100PA00X+182298Y+082605X0200Y    R270 S0      
317GND              VIA   -    MD0100PA00X+182298Y+080605X0200Y    R270 S0      
317GND              VIA   -    MD0100PA00X+183200Y+164498X0200Y         S0      
317GND              VIA   -    MD0100PA00X+183793Y+163617X0200Y         S0      
317GND              VIA   -    MD0100PA00X+183794Y+157324X0200Y    R270 S0      
317GND              VIA   -    MD0100PA00X+183794Y+155324X0200Y    R270 S0      
317GND              VIA   -    MD0100PA00X+183794Y+153324X0200Y    R270 S0      
317GND              VIA   -    MD0100PA00X+183794Y+151324X0200Y    R270 S0      
317GND              VIA   -    MD0100PA00X+183794Y+149324X0200Y    R270 S0      
317GND              VIA   -    MD0100PA00X+183794Y+147324X0200Y    R270 S0      
317GND              VIA   -    MD0100PA00X+183794Y+145324X0200Y    R270 S0      
317GND              VIA   -    MD0100PA00X+183794Y+143324X0200Y    R270 S0      
317GND              VIA   -    MD0100PA00X+183794Y+139324X0200Y    R270 S0      
317GND              VIA   -    MD0100PA00X+183794Y+137324X0200Y    R270 S0      
317GND              VIA   -    MD0100PA00X+183794Y+135324X0200Y    R270 S0      
317GND              VIA   -    MD0100PA00X+181638Y+114491X0200Y    R090 S0      
317GND              VIA   -    MD0100PA00X+181388Y+114491X0200Y    R090 S0      
317GND              VIA   -    MD0100PA00X+181638Y+113691X0200Y    R090 S0      
317GND              VIA   -    MD0100PA00X+177490Y+114782X0200Y         S0      
317GND              VIA   -    MD0100PA00X+177740Y+114782X0200Y         S0      
317GND              VIA   -    MD0100PA00X+136394Y+104705X0200Y         S0      
317GND              VIA   -    MD0100PA00X+136424Y+104314X0200Y         S0      
317GND              VIA   -    MD0100PA00X+127442Y+086196X0200Y         S0      
327GND              C2086 -2          A18X+133423Y+087869X0164Y0164R270 S2      
327GND              C2080 -2          A18X+132169Y+086313X0164Y0164R180 S2      
327GND              C2076 -2          A18X+133423Y+085034X0164Y0164R090 S2      
327GND              C2052 -2          A18X+133108Y+083459X0164Y0164R090 S2      
327GND              C2033 -2          A18X+135312Y+087239X0164Y0164R090 S2      
327GND              C2032 -2          A18X+134997Y+087239X0164Y0164R090 S2      
327GND              C2030 -2          A18X+134368Y+087239X0164Y0164R090 S2      
327GND              U6    -H10        A01X+134368Y+087554X0160Y         S1      
327GND              C2036 -2          A18X+134682Y+087239X0164Y0164R090 S2      
327GND              C2083 -2   M      A18X+133738Y+086924X0164Y0164R270 S2      
327GND              C2031 -2          A18X+133738Y+087869X0164Y0164     S2      
327GND              C2089 -2   M      A18X+133738Y+087554X0164Y0164R270 S2      
327GND              C2037 -2   M      A18X+134053Y+087239X0164Y0164R090 S2      
327GND              C2060 -2          A18X+134998Y+085664X0164Y0164R270 S2      
327GND              C2054 -2          A18X+134683Y+085664X0164Y0164R270 S2      
327GND              C2059 -2          A18X+134368Y+085664X0164Y0164R270 S2      
327GND              C2079 -2          A18X+133738Y+085349X0164Y0164R090 S2      
327GND              C2057 -2          A18X+134053Y+085664X0164Y0164R270 S2      
327GND              C2051 -2          A18X+134998Y+084089X0164Y0164R180 S2      
327GND              C2028 -2          A18X+134683Y+089129X0164Y0164     S2      
327GND              C2055 -2          A18X+135628Y+085664X0164Y0164R270 S2      
327GND              C2050 -2          A18X+136257Y+083774X0164Y0164R090 S2      
327GND              C2046 -2   M      A18X+135942Y+086609X0164Y0164R090 S2      
327GND              C2065 -2   M      A18X+135627Y+086609X0164Y0164R090 S2      
327GND              C2035 -2   M      A18X+135627Y+087239X0164Y0164R090 S2      
327GND              C2034 -2          A18X+135942Y+087869X0164Y0164R180 S2      
327GND              C2043 -2          A18X+136257Y+087554X0164Y0164R270 S2      
327GND              C2048 -2          A18X+135942Y+087239X0164Y0164R090 S2      
327GND              U6    -H13        A01X+135312Y+087554X0160Y         S1      
327GND              C2049 -2          A18X+136257Y+085349X0164Y0164R090 S2      
327GND              C2056 -2          A18X+135313Y+085664X0164Y0164R270 S2      
327GND              C2045 -2   M      A18X+135942Y+085664X0164Y0164R270 S2      
327GND              C2040 -2          A18X+137202Y+086924X0164Y0164R270 S2      
327GND              C2580 -2          A18X+152004Y+092374X0198Y0197R180 S2      
317GND              J7    -Z9  MD0197PA00X+120114Y+145350X0357Y    R180 S3      
317GND              J7    -Y10 MD0197PA00X+120980Y+145784X0357Y    R180 S3      
317GND              J7    -W9  MD0197PA00X+120114Y+146886X0357Y    R180 S3      
317GND              J7    -V10 MD0197PA00X+120980Y+147319X0357Y    R180 S3      
317GND              J7    -T9  MD0197PA00X+120114Y+148421X0357Y    R180 S3      
317GND              J7    -S10 MD0197PA00X+120980Y+148854X0357Y    R180 S3      
317GND              J7    -Q9  MD0197PA00X+120114Y+149957X0357Y    R180 S3      
317GND              J7    -P10 MD0197PA00X+120980Y+150390X0357Y    R180 S3      
317GND              J7    -N2_9MD0197PA00X+120114Y+151492X0357Y    R180 S3      
317GND              J7    -N1_9MD0197PA00X+120114Y+155587X0357Y    R180 S3      
317GND              J7    -M2_1MD0197PA00X+120980Y+151925X0357Y    R180 S3      
317GND              J7    -M1_1MD0197PA00X+120980Y+156020X0357Y    R180 S3      
317GND              J7    -K9  MD0197PA00X+120114Y+157122X0357Y    R180 S3      
317GND              J7    -J10 MD0197PA00X+120980Y+157555X0357Y    R180 S3      
317GND              J7    -H9  MD0197PA00X+120114Y+158658X0357Y    R180 S3      
317GND              J7    -G10 MD0197PA00X+120980Y+159091X0357Y    R180 S3      
317GND              J7    -E9  MD0197PA00X+120114Y+160193X0357Y    R180 S3      
317GND              J7    -D10 MD0197PA00X+120980Y+160626X0357Y    R180 S3      
317GND              J7    -B9  MD0197PA00X+120114Y+161728X0357Y    R180 S3      
317GND              J7    -A10 MD0197PA00X+120980Y+162162X0357Y    R180 S3      
317GND              J7    -Z7  MD0197PA00X+118382Y+145350X0357Y    R180 S3      
317GND              J7    -Y8  MD0197PA00X+119248Y+145784X0357Y    R180 S3      
317GND              J7    -W7  MD0197PA00X+118382Y+146886X0357Y    R180 S3      
317GND              J7    -V8  MD0197PA00X+119248Y+147319X0357Y    R180 S3      
317GND              J7    -T7  MD0197PA00X+118382Y+148421X0357Y    R180 S3      
317GND              J7    -S8  MD0197PA00X+119248Y+148854X0357Y    R180 S3      
317GND              J7    -Q7  MD0197PA00X+118382Y+149957X0357Y    R180 S3      
317GND              J7    -P8  MD0197PA00X+119248Y+150390X0357Y    R180 S3      
317GND              J7    -N2_7MD0197PA00X+118382Y+151492X0357Y    R180 S3      
317GND              J7    -N1_7MD0197PA00X+118382Y+155587X0357Y    R180 S3      
317GND              J7    -M2_8MD0197PA00X+119248Y+151925X0357Y    R180 S3      
317GND              J7    -M1_8MD0197PA00X+119248Y+156020X0357Y    R180 S3      
317GND              J7    -K7  MD0197PA00X+118382Y+157122X0357Y    R180 S3      
317GND              J7    -J8  MD0197PA00X+119248Y+157555X0357Y    R180 S3      
317GND              J7    -H7  MD0197PA00X+118382Y+158658X0357Y    R180 S3      
317GND              J7    -G8  MD0197PA00X+119248Y+159091X0357Y    R180 S3      
317GND              J7    -E7  MD0197PA00X+118382Y+160193X0357Y    R180 S3      
317GND              J7    -D8  MD0197PA00X+119248Y+160626X0357Y    R180 S3      
317GND              J7    -B7  MD0197PA00X+118382Y+161728X0357Y    R180 S3      
317GND              J7    -A8  MD0197PA00X+119248Y+162162X0357Y    R180 S3      
317GND              J7    -Z5  MD0197PA00X+116650Y+145350X0357Y    R180 S3      
317GND              J7    -Y6  MD0197PA00X+117516Y+145784X0357Y    R180 S3      
317GND              J7    -W5  MD0197PA00X+116650Y+146886X0357Y    R180 S3      
317GND              J7    -V6  MD0197PA00X+117516Y+147319X0357Y    R180 S3      
317GND              J7    -T5  MD0197PA00X+116650Y+148421X0357Y    R180 S3      
317GND              J7    -S6  MD0197PA00X+117516Y+148854X0357Y    R180 S3      
317GND              J7    -Q5  MD0197PA00X+116650Y+149957X0357Y    R180 S3      
317GND              J7    -P6  MD0197PA00X+117516Y+150390X0357Y    R180 S3      
317GND              J7    -N2_5MD0197PA00X+116650Y+151492X0357Y    R180 S3      
317GND              J7    -N1_5MD0197PA00X+116650Y+155587X0357Y    R180 S3      
317GND              J7    -M2_6MD0197PA00X+117516Y+151925X0357Y    R180 S3      
317GND              J7    -M1_6MD0197PA00X+117516Y+156020X0357Y    R180 S3      
317GND              J7    -K5  MD0197PA00X+116650Y+157122X0357Y    R180 S3      
317GND              J7    -J6  MD0197PA00X+117516Y+157555X0357Y    R180 S3      
317GND              J7    -H5  MD0197PA00X+116650Y+158658X0357Y    R180 S3      
317GND              J7    -G6  MD0197PA00X+117516Y+159091X0357Y    R180 S3      
317GND              J7    -E5  MD0197PA00X+116650Y+160193X0357Y    R180 S3      
317GND              J7    -D6  MD0197PA00X+117516Y+160626X0357Y    R180 S3      
317GND              J7    -B5  MD0197PA00X+116650Y+161728X0357Y    R180 S3      
317GND              J7    -A6  MD0197PA00X+117516Y+162162X0357Y    R180 S3      
317GND              J7    -Z3  MD0197PA00X+114917Y+145350X0357Y    R180 S3      
317GND              J7    -Y4  MD0197PA00X+115783Y+145784X0357Y    R180 S3      
317GND              J7    -W3  MD0197PA00X+114917Y+146886X0357Y    R180 S3      
317GND              J7    -V4  MD0197PA00X+115783Y+147319X0357Y    R180 S3      
317GND              J7    -T3  MD0197PA00X+114917Y+148421X0357Y    R180 S3      
317GND              J7    -S4  MD0197PA00X+115783Y+148854X0357Y    R180 S3      
317GND              J7    -Q3  MD0197PA00X+114917Y+149957X0357Y    R180 S3      
317GND              J7    -P4  MD0197PA00X+115783Y+150390X0357Y    R180 S3      
317GND              J7    -N2_3MD0197PA00X+114917Y+151492X0357Y    R180 S3      
317GND              J7    -N1_3MD0197PA00X+114917Y+155587X0357Y    R180 S3      
317GND              J7    -M2_4MD0197PA00X+115783Y+151925X0357Y    R180 S3      
317GND              J7    -M1_4MD0197PA00X+115783Y+156020X0357Y    R180 S3      
317GND              J7    -K3  MD0197PA00X+114917Y+157122X0357Y    R180 S3      
317GND              J7    -J4  MD0197PA00X+115783Y+157555X0357Y    R180 S3      
317GND              J7    -H3  MD0197PA00X+114917Y+158658X0357Y    R180 S3      
317GND              J7    -G4  MD0197PA00X+115783Y+159091X0357Y    R180 S3      
317GND              J7    -E3  MD0197PA00X+114917Y+160193X0357Y    R180 S3      
317GND              J7    -D4  MD0197PA00X+115783Y+160626X0357Y    R180 S3      
317GND              J7    -B3  MD0197PA00X+114917Y+161728X0357Y    R180 S3      
317GND              J7    -A4  MD0197PA00X+115783Y+162162X0357Y    R180 S3      
317GND              J7    -Z1  MD0197PA00X+113185Y+145350X0357Y    R180 S3      
317GND              J7    -Y2  MD0197PA00X+114051Y+145784X0357Y    R180 S3      
317GND              J7    -W1  MD0197PA00X+113185Y+146886X0357Y    R180 S3      
317GND              J7    -V2  MD0197PA00X+114051Y+147319X0357Y    R180 S3      
317GND              J7    -T1  MD0197PA00X+113185Y+148421X0357Y    R180 S3      
317GND              J7    -S2  MD0197PA00X+114051Y+148854X0357Y    R180 S3      
317GND              J7    -Q1  MD0197PA00X+113185Y+149957X0357Y    R180 S3      
317GND              J7    -P2  MD0197PA00X+114051Y+150390X0357Y    R180 S3      
317GND              J7    -N2_1MD0197PA00X+113185Y+151492X0357Y    R180 S3      
317GND              J7    -N1_1MD0197PA00X+113185Y+155587X0357Y    R180 S3      
317GND              J7    -M2_2MD0197PA00X+114051Y+151925X0357Y    R180 S3      
317GND              J7    -M1_2MD0197PA00X+114051Y+156020X0357Y    R180 S3      
317GND              J7    -K1  MD0197PA00X+113185Y+157122X0357Y    R180 S3      
317GND              J7    -J2  MD0197PA00X+114051Y+157555X0357Y    R180 S3      
317GND              J7    -H1  MD0197PA00X+113185Y+158658X0357Y    R180 S3      
317GND              J7    -G2  MD0197PA00X+114051Y+159091X0357Y    R180 S3      
317GND              J7    -E1  MD0197PA00X+113185Y+160193X0357Y    R180 S3      
317GND              J7    -D2  MD0197PA00X+114051Y+160626X0357Y    R180 S3      
317GND              J7    -B1  MD0197PA00X+113185Y+161728X0357Y    R180 S3      
317GND              J7    -A2  MD0197PA00X+114051Y+162162X0357Y    R180 S3      
317GND              H90   -9   MD0220PA00X+127724Y+125327X0300Y         S3      
317GND              H90   -8   MD0220PA00X+126712Y+124909X0300Y         S3      
317GND              H90   -7   MD0220PA00X+125701Y+125327X0300Y         S3      
317GND              H90   -6   MD0220PA00X+125282Y+126339X0300Y         S3      
317GND              H90   -5   MD0220PA00X+125701Y+127350X0300Y         S3      
317GND              H90   -4   MD0220PA00X+126712Y+127769X0300Y         S3      
317GND              H90   -3   MD0220PA00X+127724Y+127350X0300Y         S3      
317GND              H90   -2   MD0220PA00X+128142Y+126339X0300Y         S3      
317GND              H86   -9   MD0220PA00X+127724Y+105642X0300Y         S3      
317GND              H86   -8   MD0220PA00X+126712Y+105224X0300Y         S3      
317GND              H86   -7   MD0220PA00X+125701Y+105642X0300Y         S3      
317GND              H86   -6   MD0220PA00X+125282Y+106654X0300Y         S3      
317GND              H86   -5   MD0220PA00X+125701Y+107665X0300Y         S3      
317GND              H86   -4   MD0220PA00X+126712Y+108084X0300Y         S3      
317GND              H86   -3   MD0220PA00X+127724Y+107665X0300Y         S3      
317GND              H86   -2   MD0220PA00X+128142Y+106654X0300Y         S3      
327GND              U6    -R15        A01X+135942Y+085349X0160Y         S1      
327GND              U6    -P14        A01X+135628Y+085664X0160Y         S1      
327GND              U6    -N14        A01X+135628Y+085979X0160Y         S1      
327GND              U6    -M13        A01X+135312Y+086294X0160Y         S1      
327GND              U6    -M14        A01X+135628Y+086294X0160Y         S1      
327GND              U6    -L13        A01X+135312Y+086609X0160Y         S1      
327GND              U6    -L14        A01X+135628Y+086609X0160Y         S1      
327GND              U6    -L18        A01X+136887Y+086609X0160Y         S1      
327GND              U6    -K14        A01X+135628Y+086924X0160Y         S1      
327GND              U6    -H8         A01X+133738Y+087554X0160Y         S1      
327GND              U6    -J9         A01X+134053Y+087239X0160Y         S1      
327GND              U6    -J10        A01X+134368Y+087239X0160Y         S1      
327GND              U6    -J11        A01X+134683Y+087239X0160Y         S1      
327GND              U6    -C11        A01X+134683Y+089129X0160Y         S1      
327GND              U6    -J12        A01X+134998Y+087239X0160Y         S1      
327GND              U6    -J13        A01X+135312Y+087239X0160Y         S1      
327GND              U6    -J14        A01X+135628Y+087239X0160Y         S1      
327GND              U6    -H15        A01X+135942Y+087554X0160Y         S1      
327GND              U6    -R8         A01X+133738Y+085349X0160Y         S1      
327GND              U6    -P9         A01X+134053Y+085664X0160Y         S1      
327GND              U6    -N9         A01X+134053Y+085979X0160Y         S1      
327GND              U6    -M4         A01X+132478Y+086294X0160Y         S1      
327GND              U6    -M9         A01X+134053Y+086294X0160Y         S1      
327GND              U6    -M10        A01X+134368Y+086294X0160Y         S1      
327GND              U6    -L9         A01X+134053Y+086609X0160Y         S1      
327GND              U6    -L10        A01X+134368Y+086609X0160Y         S1      
327GND              U6    -K9         A01X+134053Y+086924X0160Y         S1      
327GND              U6    -Y7         A01X+133423Y+083774X0160Y         S1      
327GND              U6    -P10        A01X+134368Y+085664X0160Y         S1      
327GND              U6    -P11        A01X+134683Y+085664X0160Y         S1      
327GND              U6    -P12        A01X+134998Y+085664X0160Y         S1      
327GND              U6    -W12        A01X+134998Y+084089X0160Y         S1      
327GND              U6    -P13        A01X+135312Y+085664X0160Y         S1      
327GND              U6    -Y16        A01X+136257Y+083774X0160Y         S1      
317GND              VIA   -    MD0100PA00X+136100Y+085192X0180Y         S0      
317GND              VIA   -    MD0100PA00X+135785Y+085507X0180Y         S0      
317GND              VIA   -    MD0100PA00X+135785Y+085822X0180Y         S0      
317GND              VIA   -    MD0100PA00X+135470Y+086137X0180Y         S0      
317GND              VIA   -    MD0100PA00X+135785Y+086137X0180Y         S0      
317GND              VIA   -    MD0100PA00X+135470Y+086766X0180Y         S0      
317GND              VIA   -    MD0100PA00X+135785Y+086766X0180Y         S0      
317GND              VIA   -    MD0100PA00X+137045Y+086766X0180Y         S0      
317GND              VIA   -    MD0100PA00X+135785Y+087081X0180Y         S0      
317GND              VIA   -    MD0100PA00X+133580Y+087711X0180Y         S0      
317GND              VIA   -    MD0100PA00X+133895Y+087396X0180Y         S0      
317GND              VIA   -    MD0100PA00X+134210Y+087396X0180Y         S0      
317GND              VIA   -    MD0100PA00X+134525Y+087396X0180Y         S0      
317GND              VIA   -    MD0100PA00X+134525Y+089286X0180Y         S0      
317GND              VIA   -    MD0100PA00X+135155Y+087396X0180Y         S0      
317GND              VIA   -    MD0100PA00X+135470Y+087396X0180Y         S0      
317GND              VIA   -    MD0100PA00X+135785Y+087396X0180Y         S0      
317GND              VIA   -    MD0100PA00X+136100Y+087711X0180Y         S0      
317GND              VIA   -    MD0100PA00X+133580Y+085192X0180Y         S0      
317GND              VIA   -    MD0100PA00X+133895Y+085507X0180Y         S0      
317GND              VIA   -    MD0100PA00X+133895Y+085822X0180Y         S0      
317GND              VIA   -    MD0100PA00X+132320Y+086137X0180Y         S0      
317GND              VIA   -    MD0100PA00X+133895Y+086137X0180Y         S0      
317GND              VIA   -    MD0100PA00X+134210Y+086137X0180Y         S0      
317GND              VIA   -    MD0100PA00X+133895Y+086766X0180Y         S0      
317GND              VIA   -    MD0100PA00X+134210Y+086766X0180Y         S0      
317GND              VIA   -    MD0100PA00X+133895Y+087081X0180Y         S0      
317GND              VIA   -    MD0100PA00X+133265Y+083617X0180Y         S0      
317GND              VIA   -    MD0100PA00X+134210Y+085507X0180Y         S0      
317GND              VIA   -    MD0100PA00X+134525Y+085507X0180Y         S0      
317GND              VIA   -    MD0100PA00X+135155Y+085507X0180Y         S0      
317GND              VIA   -    MD0100PA00X+135155Y+083932X0180Y         S0      
317GND              VIA   -    MD0100PA00X+135470Y+085507X0180Y         S0      
317GND              VIA   -    MD0100PA00X+136415Y+083617X0180Y         S0      
317GND              H140  -1   MD1260PA00X+130453Y+114102X2560Y         S3      
317GND              J13   -Z9  MD0197PA00X+137437Y+145350X0357Y    R180 S3      
317GND              J13   -Y10 MD0197PA00X+138303Y+145784X0357Y    R180 S3      
317GND              J13   -W9  MD0197PA00X+137437Y+146886X0357Y    R180 S3      
317GND              J13   -V10 MD0197PA00X+138303Y+147319X0357Y    R180 S3      
317GND              J13   -T9  MD0197PA00X+137437Y+148421X0357Y    R180 S3      
317GND              J13   -S10 MD0197PA00X+138303Y+148854X0357Y    R180 S3      
317GND              J13   -Q9  MD0197PA00X+137437Y+149957X0357Y    R180 S3      
317GND              J13   -P10 MD0197PA00X+138303Y+150390X0357Y    R180 S3      
317GND              J13   -N2_9MD0197PA00X+137437Y+151492X0357Y    R180 S3      
317GND              J13   -N1_9MD0197PA00X+137437Y+155587X0357Y    R180 S3      
317GND              J13   -M2_1MD0197PA00X+138303Y+151925X0357Y    R180 S3      
317GND              J13   -M1_1MD0197PA00X+138303Y+156020X0357Y    R180 S3      
317GND              J13   -K9  MD0197PA00X+137437Y+157122X0357Y    R180 S3      
317GND              J13   -J10 MD0197PA00X+138303Y+157555X0357Y    R180 S3      
317GND              J13   -H9  MD0197PA00X+137437Y+158658X0357Y    R180 S3      
317GND              J13   -G10 MD0197PA00X+138303Y+159091X0357Y    R180 S3      
317GND              J13   -E9  MD0197PA00X+137437Y+160193X0357Y    R180 S3      
317GND              J13   -D10 MD0197PA00X+138303Y+160626X0357Y    R180 S3      
317GND              J13   -B9  MD0197PA00X+137437Y+161728X0357Y    R180 S3      
317GND              J13   -A10 MD0197PA00X+138303Y+162162X0357Y    R180 S3      
317GND              J13   -Z7  MD0197PA00X+135705Y+145350X0357Y    R180 S3      
317GND              J13   -Y8  MD0197PA00X+136571Y+145784X0357Y    R180 S3      
317GND              J13   -W7  MD0197PA00X+135705Y+146886X0357Y    R180 S3      
317GND              J13   -V8  MD0197PA00X+136571Y+147319X0357Y    R180 S3      
317GND              J13   -T7  MD0197PA00X+135705Y+148421X0357Y    R180 S3      
317GND              J13   -S8  MD0197PA00X+136571Y+148854X0357Y    R180 S3      
317GND              J13   -Q7  MD0197PA00X+135705Y+149957X0357Y    R180 S3      
317GND              J13   -P8  MD0197PA00X+136571Y+150390X0357Y    R180 S3      
317GND              J13   -N2_7MD0197PA00X+135705Y+151492X0357Y    R180 S3      
317GND              J13   -N1_7MD0197PA00X+135705Y+155587X0357Y    R180 S3      
317GND              J13   -M2_8MD0197PA00X+136571Y+151925X0357Y    R180 S3      
317GND              J13   -M1_8MD0197PA00X+136571Y+156020X0357Y    R180 S3      
317GND              J13   -K7  MD0197PA00X+135705Y+157122X0357Y    R180 S3      
317GND              J13   -J8  MD0197PA00X+136571Y+157555X0357Y    R180 S3      
317GND              J13   -H7  MD0197PA00X+135705Y+158658X0357Y    R180 S3      
317GND              J13   -G8  MD0197PA00X+136571Y+159091X0357Y    R180 S3      
317GND              J13   -E7  MD0197PA00X+135705Y+160193X0357Y    R180 S3      
317GND              J13   -D8  MD0197PA00X+136571Y+160626X0357Y    R180 S3      
317GND              J13   -B7  MD0197PA00X+135705Y+161728X0357Y    R180 S3      
317GND              J13   -A8  MD0197PA00X+136571Y+162162X0357Y    R180 S3      
317GND              J13   -Z5  MD0197PA00X+133972Y+145350X0357Y    R180 S3      
317GND              J13   -Y6  MD0197PA00X+134839Y+145784X0357Y    R180 S3      
317GND              J13   -W5  MD0197PA00X+133972Y+146886X0357Y    R180 S3      
317GND              J13   -V6  MD0197PA00X+134839Y+147319X0357Y    R180 S3      
317GND              J13   -T5  MD0197PA00X+133972Y+148421X0357Y    R180 S3      
317GND              J13   -S6  MD0197PA00X+134839Y+148854X0357Y    R180 S3      
317GND              J13   -Q5  MD0197PA00X+133972Y+149957X0357Y    R180 S3      
317GND              J13   -P6  MD0197PA00X+134839Y+150390X0357Y    R180 S3      
317GND              J13   -N2_5MD0197PA00X+133972Y+151492X0357Y    R180 S3      
317GND              J13   -N1_5MD0197PA00X+133972Y+155587X0357Y    R180 S3      
317GND              J13   -M2_6MD0197PA00X+134839Y+151925X0357Y    R180 S3      
317GND              J13   -M1_6MD0197PA00X+134839Y+156020X0357Y    R180 S3      
317GND              J13   -K5  MD0197PA00X+133972Y+157122X0357Y    R180 S3      
317GND              J13   -J6  MD0197PA00X+134839Y+157555X0357Y    R180 S3      
317GND              J13   -H5  MD0197PA00X+133972Y+158658X0357Y    R180 S3      
317GND              J13   -G6  MD0197PA00X+134839Y+159091X0357Y    R180 S3      
317GND              J13   -E5  MD0197PA00X+133972Y+160193X0357Y    R180 S3      
317GND              J13   -D6  MD0197PA00X+134839Y+160626X0357Y    R180 S3      
317GND              J13   -B5  MD0197PA00X+133972Y+161728X0357Y    R180 S3      
317GND              J13   -A6  MD0197PA00X+134839Y+162162X0357Y    R180 S3      
317GND              J13   -Z3  MD0197PA00X+132240Y+145350X0357Y    R180 S3      
317GND              J13   -Y4  MD0197PA00X+133106Y+145784X0357Y    R180 S3      
317GND              J13   -W3  MD0197PA00X+132240Y+146886X0357Y    R180 S3      
317GND              J13   -V4  MD0197PA00X+133106Y+147319X0357Y    R180 S3      
317GND              J13   -T3  MD0197PA00X+132240Y+148421X0357Y    R180 S3      
317GND              J13   -S4  MD0197PA00X+133106Y+148854X0357Y    R180 S3      
317GND              J13   -Q3  MD0197PA00X+132240Y+149957X0357Y    R180 S3      
317GND              J13   -P4  MD0197PA00X+133106Y+150390X0357Y    R180 S3      
317GND              J13   -N2_3MD0197PA00X+132240Y+151492X0357Y    R180 S3      
317GND              J13   -N1_3MD0197PA00X+132240Y+155587X0357Y    R180 S3      
317GND              J13   -M2_4MD0197PA00X+133106Y+151925X0357Y    R180 S3      
317GND              J13   -M1_4MD0197PA00X+133106Y+156020X0357Y    R180 S3      
317GND              J13   -K3  MD0197PA00X+132240Y+157122X0357Y    R180 S3      
317GND              J13   -J4  MD0197PA00X+133106Y+157555X0357Y    R180 S3      
317GND              J13   -H3  MD0197PA00X+132240Y+158658X0357Y    R180 S3      
317GND              J13   -G4  MD0197PA00X+133106Y+159091X0357Y    R180 S3      
317GND              J13   -E3  MD0197PA00X+132240Y+160193X0357Y    R180 S3      
317GND              J13   -D4  MD0197PA00X+133106Y+160626X0357Y    R180 S3      
317GND              J13   -B3  MD0197PA00X+132240Y+161728X0357Y    R180 S3      
317GND              J13   -A4  MD0197PA00X+133106Y+162162X0357Y    R180 S3      
317GND              J13   -Z1  MD0197PA00X+130508Y+145350X0357Y    R180 S3      
317GND              J13   -Y2  MD0197PA00X+131374Y+145784X0357Y    R180 S3      
317GND              J13   -W1  MD0197PA00X+130508Y+146886X0357Y    R180 S3      
317GND              J13   -V2  MD0197PA00X+131374Y+147319X0357Y    R180 S3      
317GND              J13   -T1  MD0197PA00X+130508Y+148421X0357Y    R180 S3      
317GND              J13   -S2  MD0197PA00X+131374Y+148854X0357Y    R180 S3      
317GND              J13   -Q1  MD0197PA00X+130508Y+149957X0357Y    R180 S3      
317GND              J13   -P2  MD0197PA00X+131374Y+150390X0357Y    R180 S3      
317GND              J13   -N2_1MD0197PA00X+130508Y+151492X0357Y    R180 S3      
317GND              J13   -N1_1MD0197PA00X+130508Y+155587X0357Y    R180 S3      
317GND              J13   -M2_2MD0197PA00X+131374Y+151925X0357Y    R180 S3      
317GND              J13   -M1_2MD0197PA00X+131374Y+156020X0357Y    R180 S3      
317GND              J13   -K1  MD0197PA00X+130508Y+157122X0357Y    R180 S3      
317GND              J13   -J2  MD0197PA00X+131374Y+157555X0357Y    R180 S3      
317GND              J13   -H1  MD0197PA00X+130508Y+158658X0357Y    R180 S3      
317GND              J13   -G2  MD0197PA00X+131374Y+159091X0357Y    R180 S3      
317GND              J13   -E1  MD0197PA00X+130508Y+160193X0357Y    R180 S3      
317GND              J13   -D2  MD0197PA00X+131374Y+160626X0357Y    R180 S3      
317GND              J13   -B1  MD0197PA00X+130508Y+161728X0357Y    R180 S3      
317GND              J13   -A2  MD0197PA00X+131374Y+162162X0357Y    R180 S3      
317GND              H139  -1   MD1260PA00X+145059Y+108665X2560Y         S3      
317GND              H95   -9   MD0220PA00X+149810Y+125327X0300Y         S3      
317GND              H95   -8   MD0220PA00X+148799Y+124909X0300Y         S3      
317GND              H95   -7   MD0220PA00X+147788Y+125327X0300Y         S3      
317GND              H95   -6   MD0220PA00X+147369Y+126339X0300Y         S3      
317GND              H95   -5   MD0220PA00X+147788Y+127350X0300Y         S3      
317GND              H95   -4   MD0220PA00X+148799Y+127769X0300Y         S3      
317GND              H95   -3   MD0220PA00X+149810Y+127350X0300Y         S3      
317GND              H95   -2   MD0220PA00X+150229Y+126339X0300Y         S3      
317GND              H97   -9   MD0220PA00X+149810Y+105642X0300Y         S3      
317GND              H97   -8   MD0220PA00X+148799Y+105224X0300Y         S3      
317GND              H97   -7   MD0220PA00X+147788Y+105642X0300Y         S3      
317GND              H97   -6   MD0220PA00X+147369Y+106654X0300Y         S3      
317GND              H97   -5   MD0220PA00X+147788Y+107665X0300Y         S3      
317GND              H97   -4   MD0220PA00X+148799Y+108084X0300Y         S3      
317GND              H97   -3   MD0220PA00X+149810Y+107665X0300Y         S3      
317GND              H97   -2   MD0220PA00X+150229Y+106654X0300Y         S3      
327GND              R1434 -1          A01X+146710Y+099511X0198Y0197R270 S1      
317GND              J14   -Z9  MD0197PA00X+154760Y+145350X0357Y    R180 S3      
317GND              J14   -Y10 MD0197PA00X+155626Y+145784X0357Y    R180 S3      
317GND              J14   -W9  MD0197PA00X+154760Y+146886X0357Y    R180 S3      
317GND              J14   -V10 MD0197PA00X+155626Y+147319X0357Y    R180 S3      
317GND              J14   -T9  MD0197PA00X+154760Y+148421X0357Y    R180 S3      
317GND              J14   -S10 MD0197PA00X+155626Y+148854X0357Y    R180 S3      
317GND              J14   -Q9  MD0197PA00X+154760Y+149957X0357Y    R180 S3      
317GND              J14   -P10 MD0197PA00X+155626Y+150390X0357Y    R180 S3      
317GND              J14   -N2_9MD0197PA00X+154760Y+151492X0357Y    R180 S3      
317GND              J14   -N1_9MD0197PA00X+154760Y+155587X0357Y    R180 S3      
317GND              J14   -M2_1MD0197PA00X+155626Y+151925X0357Y    R180 S3      
317GND              J14   -M1_1MD0197PA00X+155626Y+156020X0357Y    R180 S3      
317GND              J14   -K9  MD0197PA00X+154760Y+157122X0357Y    R180 S3      
317GND              J14   -J10 MD0197PA00X+155626Y+157555X0357Y    R180 S3      
317GND              J14   -H9  MD0197PA00X+154760Y+158658X0357Y    R180 S3      
317GND              J14   -G10 MD0197PA00X+155626Y+159091X0357Y    R180 S3      
317GND              J14   -E9  MD0197PA00X+154760Y+160193X0357Y    R180 S3      
317GND              J14   -D10 MD0197PA00X+155626Y+160626X0357Y    R180 S3      
317GND              J14   -B9  MD0197PA00X+154760Y+161728X0357Y    R180 S3      
317GND              J14   -A10 MD0197PA00X+155626Y+162162X0357Y    R180 S3      
317GND              J14   -Z7  MD0197PA00X+153028Y+145350X0357Y    R180 S3      
317GND              J14   -Y8  MD0197PA00X+153894Y+145784X0357Y    R180 S3      
317GND              J14   -W7  MD0197PA00X+153028Y+146886X0357Y    R180 S3      
317GND              J14   -V8  MD0197PA00X+153894Y+147319X0357Y    R180 S3      
317GND              J14   -T7  MD0197PA00X+153028Y+148421X0357Y    R180 S3      
317GND              J14   -S8  MD0197PA00X+153894Y+148854X0357Y    R180 S3      
317GND              J14   -Q7  MD0197PA00X+153028Y+149957X0357Y    R180 S3      
317GND              J14   -P8  MD0197PA00X+153894Y+150390X0357Y    R180 S3      
317GND              J14   -N2_7MD0197PA00X+153028Y+151492X0357Y    R180 S3      
317GND              J14   -N1_7MD0197PA00X+153028Y+155587X0357Y    R180 S3      
317GND              J14   -M2_8MD0197PA00X+153894Y+151925X0357Y    R180 S3      
317GND              J14   -M1_8MD0197PA00X+153894Y+156020X0357Y    R180 S3      
317GND              J14   -K7  MD0197PA00X+153028Y+157122X0357Y    R180 S3      
317GND              J14   -J8  MD0197PA00X+153894Y+157555X0357Y    R180 S3      
317GND              J14   -H7  MD0197PA00X+153028Y+158658X0357Y    R180 S3      
317GND              J14   -G8  MD0197PA00X+153894Y+159091X0357Y    R180 S3      
317GND              J14   -E7  MD0197PA00X+153028Y+160193X0357Y    R180 S3      
317GND              J14   -D8  MD0197PA00X+153894Y+160626X0357Y    R180 S3      
317GND              J14   -B7  MD0197PA00X+153028Y+161728X0357Y    R180 S3      
317GND              J14   -A8  MD0197PA00X+153894Y+162162X0357Y    R180 S3      
317GND              J14   -Z5  MD0197PA00X+151295Y+145350X0357Y    R180 S3      
317GND              J14   -Y6  MD0197PA00X+152161Y+145784X0357Y    R180 S3      
317GND              J14   -W5  MD0197PA00X+151295Y+146886X0357Y    R180 S3      
317GND              J14   -V6  MD0197PA00X+152161Y+147319X0357Y    R180 S3      
317GND              J14   -T5  MD0197PA00X+151295Y+148421X0357Y    R180 S3      
317GND              J14   -S6  MD0197PA00X+152161Y+148854X0357Y    R180 S3      
317GND              J14   -Q5  MD0197PA00X+151295Y+149957X0357Y    R180 S3      
317GND              J14   -P6  MD0197PA00X+152161Y+150390X0357Y    R180 S3      
317GND              J14   -N2_5MD0197PA00X+151295Y+151492X0357Y    R180 S3      
317GND              J14   -N1_5MD0197PA00X+151295Y+155587X0357Y    R180 S3      
317GND              J14   -M2_6MD0197PA00X+152161Y+151925X0357Y    R180 S3      
317GND              J14   -M1_6MD0197PA00X+152161Y+156020X0357Y    R180 S3      
317GND              J14   -K5  MD0197PA00X+151295Y+157122X0357Y    R180 S3      
317GND              J14   -J6  MD0197PA00X+152161Y+157555X0357Y    R180 S3      
317GND              J14   -H5  MD0197PA00X+151295Y+158658X0357Y    R180 S3      
317GND              J14   -G6  MD0197PA00X+152161Y+159091X0357Y    R180 S3      
317GND              J14   -E5  MD0197PA00X+151295Y+160193X0357Y    R180 S3      
317GND              J14   -D6  MD0197PA00X+152161Y+160626X0357Y    R180 S3      
317GND              J14   -B5  MD0197PA00X+151295Y+161728X0357Y    R180 S3      
317GND              J14   -A6  MD0197PA00X+152161Y+162162X0357Y    R180 S3      
317GND              J14   -Z3  MD0197PA00X+149563Y+145350X0357Y    R180 S3      
317GND              J14   -Y4  MD0197PA00X+150429Y+145784X0357Y    R180 S3      
317GND              J14   -W3  MD0197PA00X+149563Y+146886X0357Y    R180 S3      
317GND              J14   -V4  MD0197PA00X+150429Y+147319X0357Y    R180 S3      
317GND              J14   -T3  MD0197PA00X+149563Y+148421X0357Y    R180 S3      
317GND              J14   -S4  MD0197PA00X+150429Y+148854X0357Y    R180 S3      
317GND              J14   -Q3  MD0197PA00X+149563Y+149957X0357Y    R180 S3      
317GND              J14   -P4  MD0197PA00X+150429Y+150390X0357Y    R180 S3      
317GND              J14   -N2_3MD0197PA00X+149563Y+151492X0357Y    R180 S3      
317GND              J14   -N1_3MD0197PA00X+149563Y+155587X0357Y    R180 S3      
317GND              J14   -M2_4MD0197PA00X+150429Y+151925X0357Y    R180 S3      
317GND              J14   -M1_4MD0197PA00X+150429Y+156020X0357Y    R180 S3      
317GND              J14   -K3  MD0197PA00X+149563Y+157122X0357Y    R180 S3      
317GND              J14   -J4  MD0197PA00X+150429Y+157555X0357Y    R180 S3      
317GND              J14   -H3  MD0197PA00X+149563Y+158658X0357Y    R180 S3      
317GND              J14   -G4  MD0197PA00X+150429Y+159091X0357Y    R180 S3      
317GND              J14   -E3  MD0197PA00X+149563Y+160193X0357Y    R180 S3      
317GND              J14   -D4  MD0197PA00X+150429Y+160626X0357Y    R180 S3      
317GND              J14   -B3  MD0197PA00X+149563Y+161728X0357Y    R180 S3      
317GND              J14   -A4  MD0197PA00X+150429Y+162162X0357Y    R180 S3      
317GND              J14   -Z1  MD0197PA00X+147831Y+145350X0357Y    R180 S3      
317GND              J14   -Y2  MD0197PA00X+148697Y+145784X0357Y    R180 S3      
317GND              J14   -W1  MD0197PA00X+147831Y+146886X0357Y    R180 S3      
317GND              J14   -V2  MD0197PA00X+148697Y+147319X0357Y    R180 S3      
317GND              J14   -T1  MD0197PA00X+147831Y+148421X0357Y    R180 S3      
317GND              J14   -S2  MD0197PA00X+148697Y+148854X0357Y    R180 S3      
317GND              J14   -Q1  MD0197PA00X+147831Y+149957X0357Y    R180 S3      
317GND              J14   -P2  MD0197PA00X+148697Y+150390X0357Y    R180 S3      
317GND              J14   -N2_1MD0197PA00X+147831Y+151492X0357Y    R180 S3      
317GND              J14   -N1_1MD0197PA00X+147831Y+155587X0357Y    R180 S3      
317GND              J14   -M2_2MD0197PA00X+148697Y+151925X0357Y    R180 S3      
317GND              J14   -M1_2MD0197PA00X+148697Y+156020X0357Y    R180 S3      
317GND              J14   -K1  MD0197PA00X+147831Y+157122X0357Y    R180 S3      
317GND              J14   -J2  MD0197PA00X+148697Y+157555X0357Y    R180 S3      
317GND              J14   -H1  MD0197PA00X+147831Y+158658X0357Y    R180 S3      
317GND              J14   -G2  MD0197PA00X+148697Y+159091X0357Y    R180 S3      
317GND              J14   -E1  MD0197PA00X+147831Y+160193X0357Y    R180 S3      
317GND              J14   -D2  MD0197PA00X+148697Y+160626X0357Y    R180 S3      
317GND              J14   -B1  MD0197PA00X+147831Y+161728X0357Y    R180 S3      
317GND              J14   -A2  MD0197PA00X+148697Y+162162X0357Y    R180 S3      
327GND              R1432 -1          A01X+147110Y+099511X0198Y0197R270 S1      
327GND              R1430 -1          A01X+147910Y+099511X0198Y0197R270 S1      
327GND              R1427 -1          A01X+147510Y+099511X0198Y0197R270 S1      
327GND              R1423 -1          A01X+148310Y+099511X0198Y0197R270 S1      
327GND              R1429 -1          A01X+149510Y+099511X0198Y0197R270 S1      
327GND              R1428 -1          A01X+148710Y+099511X0198Y0197R270 S1      
327GND              R1425 -1          A01X+149110Y+099511X0198Y0197R270 S1      
327GND              R1433 -1          A01X+149910Y+099511X0198Y0197R270 S1      
327GND              R1437 -1          A01X+151110Y+099511X0198Y0197R270 S1      
327GND              R1436 -1          A01X+150710Y+099511X0198Y0197R270 S1      
327GND              R1431 -1          A01X+151510Y+099511X0198Y0197R270 S1      
327GND              R1422 -1          A01X+150310Y+099511X0198Y0197R270 S1      
327GND              C2581 -2   M      A18X+152236Y+092874X0280Y0320R270 S2      
327GND              R1435 -1          A01X+151910Y+099511X0198Y0197R270 S1      
327GND              R1426 -1          A01X+153110Y+099511X0198Y0197R270 S1      
327GND              R1424 -1          A01X+152310Y+099511X0198Y0197R270 S1      
327GND              C2566 -2   M      A18X+153500Y+093358X0198Y0197R270 S2      
317GND              J9    -Z9  MD0197PA00X+172083Y+145350X0357Y    R180 S3      
317GND              J9    -Y10 MD0197PA00X+172949Y+145784X0357Y    R180 S3      
317GND              J9    -W9  MD0197PA00X+172083Y+146886X0357Y    R180 S3      
317GND              J9    -V10 MD0197PA00X+172949Y+147319X0357Y    R180 S3      
317GND              J9    -T9  MD0197PA00X+172083Y+148421X0357Y    R180 S3      
317GND              J9    -S10 MD0197PA00X+172949Y+148854X0357Y    R180 S3      
317GND              J9    -Q9  MD0197PA00X+172083Y+149957X0357Y    R180 S3      
317GND              J9    -P10 MD0197PA00X+172949Y+150390X0357Y    R180 S3      
317GND              J9    -N2_9MD0197PA00X+172083Y+151492X0357Y    R180 S3      
317GND              J9    -N1_9MD0197PA00X+172083Y+155587X0357Y    R180 S3      
317GND              J9    -M2_1MD0197PA00X+172949Y+151925X0357Y    R180 S3      
317GND              J9    -M1_1MD0197PA00X+172949Y+156020X0357Y    R180 S3      
317GND              J9    -K9  MD0197PA00X+172083Y+157122X0357Y    R180 S3      
317GND              J9    -J10 MD0197PA00X+172949Y+157555X0357Y    R180 S3      
317GND              J9    -H9  MD0197PA00X+172083Y+158658X0357Y    R180 S3      
317GND              J9    -G10 MD0197PA00X+172949Y+159091X0357Y    R180 S3      
317GND              J9    -E9  MD0197PA00X+172083Y+160193X0357Y    R180 S3      
317GND              J9    -D10 MD0197PA00X+172949Y+160626X0357Y    R180 S3      
317GND              J9    -B9  MD0197PA00X+172083Y+161728X0357Y    R180 S3      
317GND              J9    -A10 MD0197PA00X+172949Y+162162X0357Y    R180 S3      
317GND              J9    -Z7  MD0197PA00X+170350Y+145350X0357Y    R180 S3      
317GND              J9    -Y8  MD0197PA00X+171216Y+145784X0357Y    R180 S3      
317GND              J9    -W7  MD0197PA00X+170350Y+146886X0357Y    R180 S3      
317GND              J9    -V8  MD0197PA00X+171216Y+147319X0357Y    R180 S3      
317GND              J9    -T7  MD0197PA00X+170350Y+148421X0357Y    R180 S3      
317GND              J9    -S8  MD0197PA00X+171216Y+148854X0357Y    R180 S3      
317GND              J9    -Q7  MD0197PA00X+170350Y+149957X0357Y    R180 S3      
317GND              J9    -P8  MD0197PA00X+171216Y+150390X0357Y    R180 S3      
317GND              J9    -N2_7MD0197PA00X+170350Y+151492X0357Y    R180 S3      
317GND              J9    -N1_7MD0197PA00X+170350Y+155587X0357Y    R180 S3      
317GND              J9    -M2_8MD0197PA00X+171216Y+151925X0357Y    R180 S3      
317GND              J9    -M1_8MD0197PA00X+171216Y+156020X0357Y    R180 S3      
317GND              J9    -K7  MD0197PA00X+170350Y+157122X0357Y    R180 S3      
317GND              J9    -J8  MD0197PA00X+171216Y+157555X0357Y    R180 S3      
317GND              J9    -H7  MD0197PA00X+170350Y+158658X0357Y    R180 S3      
317GND              J9    -G8  MD0197PA00X+171216Y+159091X0357Y    R180 S3      
317GND              J9    -E7  MD0197PA00X+170350Y+160193X0357Y    R180 S3      
317GND              J9    -D8  MD0197PA00X+171216Y+160626X0357Y    R180 S3      
317GND              J9    -B7  MD0197PA00X+170350Y+161728X0357Y    R180 S3      
317GND              J9    -A8  MD0197PA00X+171216Y+162162X0357Y    R180 S3      
317GND              J9    -Z5  MD0197PA00X+168618Y+145350X0357Y    R180 S3      
317GND              J9    -Y6  MD0197PA00X+169484Y+145784X0357Y    R180 S3      
317GND              J9    -W5  MD0197PA00X+168618Y+146886X0357Y    R180 S3      
317GND              J9    -V6  MD0197PA00X+169484Y+147319X0357Y    R180 S3      
317GND              J9    -T5  MD0197PA00X+168618Y+148421X0357Y    R180 S3      
317GND              J9    -S6  MD0197PA00X+169484Y+148854X0357Y    R180 S3      
317GND              J9    -Q5  MD0197PA00X+168618Y+149957X0357Y    R180 S3      
317GND              J9    -P6  MD0197PA00X+169484Y+150390X0357Y    R180 S3      
317GND              J9    -N2_5MD0197PA00X+168618Y+151492X0357Y    R180 S3      
317GND              J9    -N1_5MD0197PA00X+168618Y+155587X0357Y    R180 S3      
317GND              J9    -M2_6MD0197PA00X+169484Y+151925X0357Y    R180 S3      
317GND              J9    -M1_6MD0197PA00X+169484Y+156020X0357Y    R180 S3      
317GND              J9    -K5  MD0197PA00X+168618Y+157122X0357Y    R180 S3      
317GND              J9    -J6  MD0197PA00X+169484Y+157555X0357Y    R180 S3      
317GND              J9    -H5  MD0197PA00X+168618Y+158658X0357Y    R180 S3      
317GND              J9    -G6  MD0197PA00X+169484Y+159091X0357Y    R180 S3      
317GND              J9    -E5  MD0197PA00X+168618Y+160193X0357Y    R180 S3      
317GND              J9    -D6  MD0197PA00X+169484Y+160626X0357Y    R180 S3      
317GND              J9    -B5  MD0197PA00X+168618Y+161728X0357Y    R180 S3      
317GND              J9    -A6  MD0197PA00X+169484Y+162162X0357Y    R180 S3      
317GND              J9    -Z3  MD0197PA00X+166886Y+145350X0357Y    R180 S3      
317GND              J9    -Y4  MD0197PA00X+167752Y+145784X0357Y    R180 S3      
317GND              J9    -W3  MD0197PA00X+166886Y+146886X0357Y    R180 S3      
317GND              J9    -V4  MD0197PA00X+167752Y+147319X0357Y    R180 S3      
317GND              J9    -T3  MD0197PA00X+166886Y+148421X0357Y    R180 S3      
317GND              J9    -S4  MD0197PA00X+167752Y+148854X0357Y    R180 S3      
317GND              J9    -Q3  MD0197PA00X+166886Y+149957X0357Y    R180 S3      
317GND              J9    -P4  MD0197PA00X+167752Y+150390X0357Y    R180 S3      
317GND              J9    -N2_3MD0197PA00X+166886Y+151492X0357Y    R180 S3      
317GND              J9    -N1_3MD0197PA00X+166886Y+155587X0357Y    R180 S3      
317GND              J9    -M2_4MD0197PA00X+167752Y+151925X0357Y    R180 S3      
317GND              J9    -M1_4MD0197PA00X+167752Y+156020X0357Y    R180 S3      
317GND              J9    -K3  MD0197PA00X+166886Y+157122X0357Y    R180 S3      
317GND              J9    -J4  MD0197PA00X+167752Y+157555X0357Y    R180 S3      
317GND              J9    -H3  MD0197PA00X+166886Y+158658X0357Y    R180 S3      
317GND              J9    -G4  MD0197PA00X+167752Y+159091X0357Y    R180 S3      
317GND              J9    -E3  MD0197PA00X+166886Y+160193X0357Y    R180 S3      
317GND              J9    -D4  MD0197PA00X+167752Y+160626X0357Y    R180 S3      
317GND              J9    -B3  MD0197PA00X+166886Y+161728X0357Y    R180 S3      
317GND              J9    -A4  MD0197PA00X+167752Y+162162X0357Y    R180 S3      
317GND              J9    -Z1  MD0197PA00X+165154Y+145350X0357Y    R180 S3      
317GND              J9    -Y2  MD0197PA00X+166020Y+145784X0357Y    R180 S3      
317GND              J9    -W1  MD0197PA00X+165154Y+146886X0357Y    R180 S3      
317GND              J9    -V2  MD0197PA00X+166020Y+147319X0357Y    R180 S3      
317GND              J9    -T1  MD0197PA00X+165154Y+148421X0357Y    R180 S3      
317GND              J9    -S2  MD0197PA00X+166020Y+148854X0357Y    R180 S3      
317GND              J9    -Q1  MD0197PA00X+165154Y+149957X0357Y    R180 S3      
317GND              J9    -P2  MD0197PA00X+166020Y+150390X0357Y    R180 S3      
317GND              J9    -N2_1MD0197PA00X+165154Y+151492X0357Y    R180 S3      
317GND              J9    -N1_1MD0197PA00X+165154Y+155587X0357Y    R180 S3      
317GND              J9    -M2_2MD0197PA00X+166020Y+151925X0357Y    R180 S3      
317GND              J9    -M1_2MD0197PA00X+166020Y+156020X0357Y    R180 S3      
317GND              J9    -K1  MD0197PA00X+165154Y+157122X0357Y    R180 S3      
317GND              J9    -J2  MD0197PA00X+166020Y+157555X0357Y    R180 S3      
317GND              J9    -H1  MD0197PA00X+165154Y+158658X0357Y    R180 S3      
317GND              J9    -G2  MD0197PA00X+166020Y+159091X0357Y    R180 S3      
317GND              J9    -E1  MD0197PA00X+165154Y+160193X0357Y    R180 S3      
317GND              J9    -D2  MD0197PA00X+166020Y+160626X0357Y    R180 S3      
317GND              J9    -B1  MD0197PA00X+165154Y+161728X0357Y    R180 S3      
317GND              J9    -A2  MD0197PA00X+166020Y+162162X0357Y    R180 S3      
317GND              H93   -9   MD0220PA00X+173432Y+125327X0300Y         S3      
317GND              H93   -8   MD0220PA00X+172421Y+124909X0300Y         S3      
317GND              H93   -7   MD0220PA00X+171410Y+125327X0300Y         S3      
317GND              H93   -6   MD0220PA00X+170991Y+126339X0300Y         S3      
317GND              H93   -5   MD0220PA00X+171410Y+127350X0300Y         S3      
317GND              H93   -4   MD0220PA00X+172421Y+127769X0300Y         S3      
317GND              H93   -3   MD0220PA00X+173432Y+127350X0300Y         S3      
317GND              H93   -2   MD0220PA00X+173851Y+126339X0300Y         S3      
317GND              H99   -9   MD0220PA00X+173432Y+105642X0300Y         S3      
317GND              H99   -8   MD0220PA00X+172421Y+105224X0300Y         S3      
317GND              H99   -7   MD0220PA00X+171410Y+105642X0300Y         S3      
317GND              H99   -6   MD0220PA00X+170991Y+106654X0300Y         S3      
317GND              H99   -5   MD0220PA00X+171410Y+107665X0300Y         S3      
317GND              H99   -4   MD0220PA00X+172421Y+108084X0300Y         S3      
317GND              H99   -3   MD0220PA00X+173432Y+107665X0300Y         S3      
317GND              H99   -2   MD0220PA00X+173851Y+106654X0300Y         S3      
317GND              J54   -G3  MD0200PA00X+180392Y+082390X0440Y0870R180 S3      
317GND              J54   -G2  MD0200PA00X+179545Y+083492X0440Y0710R180 S3      
317GND              J54   -G1  MD0200PA00X+179545Y+081287X0440Y0710R180 S3      
327GND              U108  -1   M      A01X+177678Y+081870X0280Y0400R090 S1      
327GND              C2613 -2   M      A01X+177607Y+083647X0198Y0197R090 S1      
317GND              H134  -1   MD1260PA00X+176161Y+121500X2560Y         S3      
317GND              VIA   -    MD0100PA00X+147438Y+110209X0200Y         S0      
317GND              VIA   -    MD0100PA00X+148019Y+110209X0200Y         S0      
317GND              VIA   -    MD0100PA00X+148369Y+110209X0200Y         S0      
317GND              VIA   -    MD0100PA00X+150513Y+110509X0200Y         S0      
317GND              VIA   -    M      A01X+147438Y+116509X0200Y         S2      
017GND              VIA   -    M      A18X+147438Y+116509X0260Y         S2      
017GND                    -    MD0100PA00X+147438Y+116509                       
317GND              VIA   -    MD0100PA00X+148019Y+116509X0200Y         S0      
317GND              VIA   -    MD0100PA00X+148369Y+116509X0200Y         S0      
317GND              VIA   -    MD0100PA00X+150513Y+116809X0200Y         S0      
317GND              VIA   -    MD0100PA00X+147438Y+115249X0200Y         S0      
317GND              VIA   -    MD0100PA00X+148019Y+115249X0200Y         S0      
317GND              VIA   -    MD0100PA00X+148369Y+115249X0200Y         S0      
317GND              VIA   -    MD0100PA00X+150513Y+115549X0200Y         S0      
317GND              VIA   -    MD0100PA00X+147438Y+113989X0200Y         S0      
317GND              VIA   -    MD0100PA00X+148019Y+113989X0200Y         S0      
317GND              VIA   -    MD0100PA00X+148369Y+113989X0200Y         S0      
317GND              VIA   -    MD0100PA00X+150513Y+114289X0200Y         S0      
317GND              VIA   -    MD0100PA00X+147438Y+112729X0200Y         S0      
317GND              VIA   -    MD0100PA00X+148019Y+112729X0200Y         S0      
317GND              VIA   -    MD0100PA00X+148369Y+112729X0200Y         S0      
317GND              VIA   -    MD0100PA00X+150513Y+113029X0200Y         S0      
317GND              VIA   -    MD0100PA00X+147438Y+111469X0200Y         S0      
317GND              VIA   -    MD0100PA00X+148019Y+111469X0200Y         S0      
317GND              VIA   -    MD0100PA00X+148369Y+111469X0200Y         S0      
317GND              VIA   -    MD0100PA00X+150513Y+111769X0200Y         S0      
317GND              VIA   -    MD0100PA00X+148603Y+100935X0200Y         S0      
317GND              VIA   -    MD0100PA00X+149184Y+100935X0200Y         S0      
317GND              VIA   -    MD0100PA00X+149534Y+100935X0200Y         S0      
317GND              VIA   -    MD0100PA00X+151678Y+101235X0200Y         S0      
317GND              VIA   -    MD0100PA00X+148603Y+102195X0200Y         S0      
317GND              VIA   -    MD0100PA00X+149184Y+102195X0200Y         S0      
317GND              VIA   -    M      A01X+149534Y+102195X0200Y         S2      
017GND              VIA   -    M      A18X+149534Y+102195X0260Y         S2      
017GND                    -    MD0100PA00X+149534Y+102195                       
317GND              VIA   -    MD0100PA00X+151678Y+102495X0200Y         S0      
317GND              VIA   -    MD0100PA00X+148254Y+100245X0200Y    R090 S0      
317GND              VIA   -    MD0100PA00X+148254Y+100826X0200Y    R090 S0      
317GND              VIA   -    MD0100PA00X+148254Y+101176X0200Y    R090 S0      
317GND              VIA   -    MD0100PA00X+150513Y+118069X0200Y         S0      
317GND              VIA   -    MD0100PA00X+148369Y+117769X0200Y         S0      
317GND              VIA   -    MD0100PA00X+147438Y+117769X0200Y         S0      
317GND              VIA   -    MD0100PA00X+148019Y+117769X0200Y         S0      
317GND              H137  -1   MD1260PA00X+182716Y+123563X2560Y         S3      
327GND              PC216 -2          A01X+005474Y+112492X0198Y0197     S1      
327GND              PC206 -2          A01X+005475Y+122889X0400Y0500R180 S1      
327GND              PC207 -2          A01X+005475Y+123579X0400Y0500R180 S1      
327GND              PC205 -2          A01X+003441Y+123430X0400Y0500     S1      
327GND              PC208 -2          A01X+003441Y+122740X0400Y0500     S1      
327GND              PC209 -2          A01X+005475Y+122199X0400Y0500R180 S1      
327GND              PC204 -2          A01X+003441Y+122050X0400Y0500     S1      
327GND              PC220 -2          A01X+002913Y+120177X0198Y0197R090 S1      
327GND              C3018 -2          A01X+010300Y+103509X0120Y0150R090 S1      
327GND              C3016 -2          A01X+010611Y+103510X0120Y0150R090 S1      
327GND              C3070 -2          A01X+009687Y+102766X0280Y0320R090 S1      
327GND              C2217 -1          A18X+009571Y+087519X0198Y0197R180 S2      
327GND              C2755 -1          A18X+009571Y+087919X0198Y0197R180 S2      
327GND              C3032 -2          A01X+011553Y+115351X0280Y0320R090 S1      
327GND              C3035 -2          A01X+010602Y+115460X0280Y0320R180 S1      
327GND              C3063 -2          A01X+010602Y+114200X0280Y0320R180 S1      
327GND              C3064 -2          A01X+011043Y+114303X0120Y0150R270 S1      
327GND              C3049 -2          A01X+011553Y+114091X0280Y0320R090 S1      
327GND              C3052 -2          A01X+011043Y+113043X0120Y0150R270 S1      
327GND              C3061 -2          A01X+011553Y+112831X0280Y0320R090 S1      
327GND              C3051 -2          A01X+010602Y+112940X0280Y0320R180 S1      
327GND              C3062 -2          A01X+011553Y+111571X0280Y0320R090 S1      
327GND              C3053 -2          A01X+010602Y+111680X0280Y0320R180 S1      
327GND              C3036 -2          A01X+011043Y+110523X0120Y0150R270 S1      
327GND              C3073 -2          A01X+011553Y+110311X0280Y0320R090 S1      
327GND              C3037 -2          A01X+010602Y+110420X0280Y0320R180 S1      
327GND              C3034 -2          A01X+012208Y+102509X0120Y0150R270 S1      
327GND              C3048 -2          A01X+012718Y+102297X0280Y0320R090 S1      
327GND              C3033 -2          A01X+011767Y+102406X0280Y0320R180 S1      
327GND              C3020 -2          A01X+012208Y+101249X0120Y0150R270 S1      
327GND              C3050 -2          A01X+012718Y+101037X0280Y0320R090 S1      
327GND              C3019 -2          A01X+011767Y+101146X0280Y0320R180 S1      
327GND              C3074 -2          A01X+011026Y+101486X0280Y0320R180 S1      
327GND              C3065 -2          A01X+010916Y+100535X0280Y0320R270 S1      
327GND              C3066 -2          A01X+010814Y+100976X0120Y0150     S1      
327GND              C3017 -2          A01X+010602Y+117980X0280Y0320R180 S1      
327GND              C3038 -2          A01X+011043Y+118083X0120Y0150R270 S1      
327GND              C3031 -2          A01X+011553Y+117871X0280Y0320R090 S1      
327GND              C3054 -2          A01X+011043Y+116823X0120Y0150R270 S1      
327GND              C3030 -2          A01X+011553Y+116611X0280Y0320R090 S1      
327GND              C3015 -2          A01X+010602Y+116720X0280Y0320R180 S1      
327GND              C3055 -2          A01X+013395Y+113551X0280Y0320R270 S1      
327GND              C3067 -2          A01X+013395Y+111031X0280Y0320R270 S1      
327GND              C3058 -2          A01X+013395Y+112291X0280Y0320R270 S1      
327GND              C3024 -2          A01X+013395Y+118591X0280Y0320R270 S1      
327GND              C3021 -2          A01X+013395Y+117331X0280Y0320R270 S1      
327GND              C3042 -2          A01X+013395Y+114811X0280Y0320R270 S1      
327GND              C3027 -2          A01X+013395Y+116071X0280Y0320R270 S1      
327GND              C3045 -2          A01X+014560Y+101757X0280Y0320R270 S1      
327GND              C3039 -2          A01X+014560Y+103017X0280Y0320R270 S1      
327GND              C2990 -2          A18X+016625Y+112541X0280Y0320R090 S2      
327GND              C3009 -2          A18X+017395Y+117805X0120Y0150     S2      
327GND              C3008 -2          A18X+017395Y+118179X0120Y0150     S2      
327GND              C3007 -2          A18X+017395Y+117431X0120Y0150     S2      
327GND              C2987 -2          A18X+017395Y+115748X0120Y0150     S2      
327GND              C3005 -2          A18X+017395Y+116122X0120Y0150     S2      
327GND              C3000 -2          A18X+017395Y+116496X0120Y0150     S2      
327GND              C3004 -2          A18X+017395Y+115374X0120Y0150     S2      
327GND              C2999 -2          A18X+017395Y+115000X0120Y0150     S2      
327GND              C2924 -2          A18X+026476Y+119593X0120Y0150R270 S2      
327GND              C2939 -2          A18X+025354Y+119593X0120Y0150R270 S2      
327GND              C2910 -2          A18X+024980Y+119593X0120Y0150R270 S2      
327GND              C2905 -2          A18X+026102Y+119593X0120Y0150R270 S2      
327GND              C2904 -2          A18X+025728Y+119593X0120Y0150R270 S2      
327GND              C2907 -2          A18X+024606Y+119593X0120Y0150R270 S2      
327GND              C2906 -2          A18X+023484Y+119593X0120Y0150R270 S2      
327GND              C2901 -2          A18X+023858Y+119593X0120Y0150R270 S2      
327GND              C2908 -2          A18X+024232Y+119593X0120Y0150R270 S2      
327GND              C2922 -2          A18X+023110Y+119593X0120Y0150R270 S2      
327GND              C2918 -2          A18X+022362Y+119593X0120Y0150R270 S2      
327GND              C2917 -2          A18X+022736Y+119593X0120Y0150R270 S2      
327GND              C2913 -2          A18X+021988Y+119593X0120Y0150R270 S2      
327GND              C2912 -2          A18X+021614Y+119593X0120Y0150R270 S2      
327GND              C2916 -2          A18X+021240Y+119593X0120Y0150R270 S2      
327GND              C2915 -2          A18X+020866Y+119593X0120Y0150R270 S2      
327GND              C2914 -2          A18X+020118Y+119593X0120Y0150R270 S2      
327GND              C2909 -2          A18X+020492Y+119593X0120Y0150R270 S2      
327GND              C2995 -2          A18X+018809Y+119301X0120Y0150     S2      
327GND              C2962 -2          A18X+026300Y+120341X0120Y0150R270 S2      
327GND              C2980 -2          A18X+026674Y+120341X0120Y0150R270 S2      
327GND              C2956 -2          A18X+025926Y+120341X0120Y0150R270 S2      
327GND              C2954 -2          A18X+025552Y+120341X0120Y0150R270 S2      
327GND              C2952 -2          A18X+025178Y+120341X0120Y0150R270 S2      
327GND              C2966 -2          A18X+024804Y+120341X0120Y0150R270 S2      
327GND              C2978 -2          A18X+024056Y+120341X0120Y0150R270 S2      
327GND              C2975 -2          A18X+023682Y+120341X0120Y0150R270 S2      
327GND              C2964 -2          A18X+024430Y+120341X0120Y0150R270 S2      
327GND              C2945 -2          A18X+023292Y+120588X0280Y0320     S2      
327GND              C2967 -2          A18X+022902Y+120341X0120Y0150R270 S2      
327GND              C2974 -2          A18X+022528Y+120341X0120Y0150R270 S2      
327GND              C2970 -2          A18X+022154Y+120341X0120Y0150R270 S2      
327GND              C2976 -2          A18X+021780Y+120341X0120Y0150R270 S2      
327GND              C2986 -2          A18X+021032Y+120341X0120Y0150R270 S2      
327GND              C2983 -2          A18X+020284Y+120341X0120Y0150R270 S2      
327GND              C2982 -2          A18X+020658Y+120341X0120Y0150R270 S2      
327GND              C2973 -2          A18X+021406Y+120341X0120Y0150R270 S2      
327GND              C2984 -2          A18X+019910Y+120341X0120Y0150R270 S2      
327GND              C1171 -2          A18X+026476Y+118845X0120Y0150R270 S2      
327GND              C1213 -2          A18X+024980Y+118845X0120Y0150R270 S2      
327GND              C1204 -2          A18X+025354Y+118845X0120Y0150R270 S2      
327GND              C1196 -2          A18X+026102Y+118845X0120Y0150R270 S2      
327GND              C1193 -2          A18X+025728Y+118845X0120Y0150R270 S2      
327GND              C1238 -2          A18X+024232Y+118845X0120Y0150R270 S2      
327GND              C1233 -2          A18X+024606Y+118845X0120Y0150R270 S2      
327GND              C1228 -2          A18X+023484Y+118845X0120Y0150R270 S2      
327GND              C1226 -2          A18X+023858Y+118845X0120Y0150R270 S2      
327GND              C1202 -2          A18X+021988Y+118845X0120Y0150R270 S2      
327GND              C1198 -2          A18X+022362Y+118845X0120Y0150R270 S2      
327GND              C1181 -2          A18X+023110Y+118845X0120Y0150R270 S2      
327GND              C1231 -2          A18X+022736Y+118845X0120Y0150R270 S2      
327GND              C1217 -2          A18X+021614Y+118845X0120Y0150R270 S2      
327GND              C1222 -2          A18X+021240Y+118845X0120Y0150R270 S2      
327GND              C1194 -2          A18X+020866Y+118845X0120Y0150R270 S2      
327GND              C1180 -2          A18X+020492Y+118845X0120Y0150R270 S2      
327GND              C1178 -2          A18X+020118Y+118845X0120Y0150R270 S2      
327GND              C1179 -2          A18X+019750Y+118845X0120Y0150R270 S2      
327GND              C2996 -2          A18X+027037Y+112943X0120Y0150     S2      
327GND              C2997 -2          A18X+027037Y+113317X0120Y0150     S2      
327GND              C2927 -2          A18X+026476Y+113399X0120Y0150R090 S2      
327GND              C2940 -2          A18X+026102Y+113399X0120Y0150R090 S2      
327GND              C2938 -2          A18X+024980Y+113399X0120Y0150R090 S2      
327GND              C2936 -2          A18X+025728Y+113399X0120Y0150R090 S2      
327GND              C2920 -2          A18X+025354Y+113399X0120Y0150R090 S2      
327GND              C2921 -2          A18X+023858Y+113399X0120Y0150R090 S2      
327GND              C2919 -2          A18X+024606Y+113399X0120Y0150R090 S2      
327GND              C2941 -2          A18X+023484Y+113399X0120Y0150R090 S2      
327GND              C2923 -2          A18X+024232Y+113399X0120Y0150R090 S2      
327GND              C2937 -2          A18X+023110Y+113399X0120Y0150R090 S2      
327GND              C2933 -2          A18X+021988Y+113399X0120Y0150R090 S2      
327GND              C2943 -2          A18X+022736Y+113399X0120Y0150R090 S2      
327GND              C2942 -2          A18X+022362Y+113399X0120Y0150R090 S2      
327GND              C2932 -2          A18X+021614Y+113399X0120Y0150R090 S2      
327GND              C2934 -2          A18X+021240Y+113399X0120Y0150R090 S2      
327GND              C2931 -2          A18X+020492Y+113399X0120Y0150R090 S2      
327GND              C2930 -2          A18X+020118Y+113399X0120Y0150R090 S2      
327GND              C2935 -2          A18X+020866Y+113399X0120Y0150R090 S2      
327GND              C1169 -2          A18X+026476Y+114147X0120Y0150R090 S2      
327GND              C1172 -2          A18X+026102Y+114147X0120Y0150R090 S2      
327GND              C1168 -2          A18X+025728Y+114147X0120Y0150R090 S2      
327GND              C1237 -2          A18X+024980Y+114147X0120Y0150R090 S2      
327GND              C1236 -2          A18X+025354Y+114147X0120Y0150R090 S2      
327GND              C1240 -2          A18X+024606Y+114147X0120Y0150R090 S2      
327GND              C1221 -2          A18X+023858Y+114147X0120Y0150R090 S2      
327GND              C1212 -2          A18X+023484Y+114147X0120Y0150R090 S2      
327GND              C1208 -2          A18X+024232Y+114147X0120Y0150R090 S2      
327GND              C1183 -2          A18X+023110Y+114147X0120Y0150R090 S2      
327GND              C1235 -2          A18X+022736Y+114147X0120Y0150R090 S2      
327GND              C1215 -2          A18X+021988Y+114147X0120Y0150R090 S2      
327GND              C1203 -2          A18X+022362Y+114147X0120Y0150R090 S2      
327GND              C1199 -2          A18X+021614Y+114147X0120Y0150R090 S2      
327GND              C1186 -2          A18X+020866Y+114147X0120Y0150R090 S2      
327GND              C1184 -2          A18X+020118Y+114147X0120Y0150R090 S2      
327GND              C1176 -2          A18X+020492Y+114147X0120Y0150R090 S2      
327GND              C1206 -2          A18X+021240Y+114147X0120Y0150R090 S2      
327GND              C1170 -2          A18X+026476Y+118097X0120Y0150R270 S2      
327GND              C1232 -2          A18X+024980Y+118097X0120Y0150R270 S2      
327GND              C1210 -2          A18X+025354Y+118097X0120Y0150R270 S2      
327GND              C1175 -2          A18X+026102Y+118097X0120Y0150R270 S2      
327GND              C1173 -2          A18X+025728Y+118097X0120Y0150R270 S2      
327GND              C1239 -2          A18X+024232Y+118097X0120Y0150R270 S2      
327GND              C1229 -2          A18X+023858Y+118097X0120Y0150R270 S2      
327GND              C1227 -2          A18X+024606Y+118097X0120Y0150R270 S2      
327GND              C1214 -2          A18X+023484Y+118097X0120Y0150R270 S2      
327GND              C1205 -2          A18X+022362Y+118097X0120Y0150R270 S2      
327GND              C1189 -2          A18X+023110Y+118097X0120Y0150R270 S2      
327GND              C1234 -2          A18X+022736Y+118097X0120Y0150R270 S2      
327GND              C1216 -2          A18X+021988Y+118097X0120Y0150R270 S2      
327GND              C1220 -2          A18X+021614Y+118097X0120Y0150R270 S2      
327GND              C1218 -2          A18X+021240Y+118097X0120Y0150R270 S2      
327GND              C1190 -2          A18X+020866Y+118097X0120Y0150R270 S2      
327GND              C1182 -2          A18X+020492Y+118097X0120Y0150R270 S2      
327GND              C1177 -2          A18X+020118Y+118097X0120Y0150R270 S2      
327GND              C1191 -2          A18X+026476Y+114895X0120Y0150R090 S2      
327GND              C1195 -2          A18X+026102Y+114895X0120Y0150R090 S2      
327GND              C1167 -2          A18X+025728Y+114895X0120Y0150R090 S2      
327GND              C1211 -2          A18X+024980Y+114895X0120Y0150R090 S2      
327GND              C1209 -2          A18X+025354Y+114895X0120Y0150R090 S2      
327GND              C1207 -2          A18X+024232Y+114895X0120Y0150R090 S2      
327GND              C1230 -2          A18X+024606Y+114895X0120Y0150R090 S2      
327GND              C1224 -2          A18X+023484Y+114895X0120Y0150R090 S2      
327GND              C1223 -2          A18X+023858Y+114895X0120Y0150R090 S2      
327GND              C1165 -2          A18X+023110Y+114895X0120Y0150R090 S2      
327GND              C1201 -2          A18X+021988Y+114895X0120Y0150R090 S2      
327GND              C1200 -2          A18X+022736Y+114895X0120Y0150R090 S2      
327GND              C1197 -2          A18X+022362Y+114895X0120Y0150R090 S2      
327GND              C1219 -2          A18X+021614Y+114895X0120Y0150R090 S2      
327GND              C1188 -2          A18X+020866Y+114895X0120Y0150R090 S2      
327GND              C1187 -2          A18X+020492Y+114895X0120Y0150R090 S2      
327GND              C1185 -2   M      A18X+020118Y+114895X0120Y0150R090 S2      
327GND              C1225 -2          A18X+021240Y+114895X0120Y0150R090 S2      
327GND              C2902 -2          A18X+029520Y+116309X0280Y0320R090 S2      
327GND              C2925 -2          A18X+028077Y+117431X0120Y0150R180 S2      
327GND              C2928 -2          A18X+028077Y+115935X0120Y0150R180 S2      
327GND              C2926 -2          A18X+028077Y+116683X0120Y0150R180 S2      
327GND              C2911 -2          A18X+028077Y+117057X0120Y0150R180 S2      
327GND              C2929 -2          A18X+028077Y+115561X0120Y0150R180 S2      
327GND              C2950 -2          A18X+028825Y+115748X0120Y0150R180 S2      
327GND              C2949 -2          A18X+028825Y+116122X0120Y0150R180 S2      
327GND              C2948 -2          A18X+028825Y+116870X0120Y0150R180 S2      
327GND              C2947 -2          A18X+028825Y+117244X0120Y0150R180 S2      
327GND              C2977 -2          A18X+028825Y+116496X0120Y0150R180 S2      
327GND              C2903 -2          A18X+031196Y+116308X0280Y0320R270 S2      
327GND              R1249 -1          A01X+035622Y+121559X0198Y0197R135 S1      
327GND              R1251 -1          A01X+035905Y+121842X0198Y0197R135 S1      
327GND              R1254 -1          A01X+035339Y+121276X0198Y0197R135 S1      
327GND              PC1003-2          A18X+041312Y+093778X0400Y0500R090 S2      
327GND              PC1002-2          A18X+042112Y+093778X0400Y0500R090 S2      
327GND              PC1004-2          A18X+040512Y+093778X0400Y0500R090 S2      
327GND              PC1005-2          A18X+039712Y+093778X0400Y0500R090 S2      
327GND              PC293 -2          A01X+041312Y+093778X0400Y0500R270 S1      
327GND              PC292 -2          A01X+042112Y+093778X0400Y0500R270 S1      
327GND              PC291 -2          A01X+040512Y+093778X0400Y0500R270 S1      
327GND              PC294 -2          A01X+039712Y+093778X0400Y0500R270 S1      
327GND              PC290 -2          A01X+039161Y+093623X0198Y0197R090 S1      
327GND              PC78  -2          A18X+041110Y+110290X0400Y0500R270 S2      
327GND              PC112 -2          A18X+050881Y+110290X0400Y0500R270 S2      
327GND              PC63  -2          A18X+044322Y+110290X0400Y0500R270 S2      
327GND              PC284 -2          A01X+040097Y+084668X0400Y0500     S1      
327GND              C2695 -2          A18X+039707Y+129126X0400Y0500R180 S2      
327GND              C2699 -2          A18X+041087Y+128579X0198Y0197R090 S2      
327GND              PR10  -2          A18X+051314Y+119837X0280Y0320     S2      
327GND              PC117 -2          A18X+050014Y+119897X0400Y0500R090 S2      
327GND              PC121 -2          A18X+048667Y+119897X0400Y0500R090 S2      
327GND              PR81  -2          A18X+047145Y+119747X0198Y0197R180 S2      
327GND              PR78  -2          A18X+045562Y+119747X0198Y0197     S2      
327GND              PR9   -2          A18X+043993Y+119837X0280Y0320     S2      
327GND              PC84  -2          A18X+042693Y+119897X0400Y0500R090 S2      
327GND              PC70  -2          A18X+041347Y+119897X0400Y0500R090 S2      
327GND              PC120 -2          A01X+052707Y+119897X0400Y0500R270 S1      
327GND              PC105 -2          A01X+051360Y+120826X0950Y1110R090 S1      
327GND              PC102 -2          A01X+050014Y+119897X0400Y0500R270 S1      
327GND              PC119 -2          A01X+048667Y+120826X0950Y1110R090 S1      
327GND              PC101 -2          A01X+047321Y+119897X0400Y0500R270 S1      
327GND              PC85  -2          A01X+045386Y+119897X0400Y0500R270 S1      
327GND              PC72  -2          A01X+044040Y+120826X0950Y1110R090 S1      
327GND              PC69  -2          A01X+042693Y+119897X0400Y0500R270 S1      
327GND              PC68  -2          A01X+040000Y+119897X0400Y0500R270 S1      
327GND              PC88  -2          A01X+041347Y+120826X0950Y1110R090 S1      
327GND              PC73  -2          A01X+042791Y+109877X0198Y0197R270 S1      
327GND              PC58  -2          A01X+041226Y+109883X0198Y0197     S1      
327GND              PC1006-2          A01X+043964Y+089665X0950Y1110R270 S1      
327GND              PC295 -2          A01X+042757Y+088086X0198Y0197R270 S1      
327GND              PC287 -2          A01X+042324Y+086264X0400Y0500R180 S1      
327GND              PC286 -2          A01X+042324Y+085464X0400Y0500R180 S1      
327GND              PC285 -2          A01X+042324Y+084664X0400Y0500R180 S1      
327GND              PC46  -2          A01X+045259Y+099677X0400Y0500     S1      
327GND              PC47  -2          A01X+045621Y+100218X0198Y0197R180 S1      
327GND              PC67  -2          A01X+046269Y+115518X0198Y0197R270 S1      
327GND              PC100 -2          A01X+046885Y+115518X0198Y0197R270 S1      
327GND              PC92  -2          A01X+046875Y+112297X0198Y0197R090 S1      
327GND              PC53  -2          A18X+046767Y+101457X0198Y0197R180 S2      
327GND              PC44  -2          A18X+046246Y+100732X0198Y0197R180 S2      
327GND              PC89  -2          A01X+049350Y+109877X0198Y0197R270 S1      
327GND              PC91  -2          A01X+047785Y+109883X0198Y0197     S1      
327GND              PC95  -2          A18X+047668Y+110290X0400Y0500R270 S2      
327GND              C2783 -1          A18X+055265Y+087919X0198Y0197R180 S2      
327GND              C2308 -1          A18X+055265Y+087519X0198Y0197R180 S2      
327GND              C3212 -2          A01X+056752Y+118083X0120Y0150R270 S1      
327GND              C3205 -2          A01X+057262Y+117871X0280Y0320R090 S1      
327GND              C3191 -2          A01X+056311Y+117980X0280Y0320R180 S1      
327GND              C3204 -2          A01X+057262Y+116611X0280Y0320R090 S1      
327GND              C3225 -2          A01X+056311Y+116720X0280Y0320R180 S1      
327GND              C3192 -2          A01X+056752Y+115563X0120Y0150R270 S1      
327GND              C3206 -2          A01X+057262Y+115351X0280Y0320R090 S1      
327GND              C3207 -2          A01X+056311Y+115460X0280Y0320R180 S1      
327GND              C3208 -2          A01X+056752Y+113043X0120Y0150R270 S1      
327GND              C3235 -2          A01X+057262Y+112831X0280Y0320R090 S1      
327GND              C3211 -2          A01X+056311Y+112940X0280Y0320R180 S1      
327GND              C3209 -2          A01X+056311Y+114200X0280Y0320R180 S1      
327GND              C3238 -2          A01X+056752Y+114303X0120Y0150R270 S1      
327GND              C3223 -2          A01X+057262Y+114091X0280Y0320R090 S1      
327GND              C3190 -2          A01X+056752Y+111783X0120Y0150R270 S1      
327GND              C3236 -2          A01X+057262Y+111571X0280Y0320R090 S1      
327GND              C3189 -2          A01X+056311Y+111680X0280Y0320R180 S1      
327GND              C3194 -2          A01X+056752Y+110523X0120Y0150R270 S1      
327GND              C3247 -2          A01X+057262Y+110311X0280Y0320R090 S1      
327GND              C3237 -2          A01X+056311Y+110420X0280Y0320R180 S1      
327GND              C3193 -2          A01X+057476Y+102406X0280Y0320R180 S1      
327GND              C3210 -2          A01X+057916Y+102509X0120Y0150R270 S1      
327GND              C3222 -2          A01X+058427Y+102297X0280Y0320R090 S1      
327GND              C3226 -2          A01X+057916Y+101249X0120Y0150R270 S1      
327GND              C3224 -2          A01X+058427Y+101037X0280Y0320R090 S1      
327GND              C3227 -2          A01X+057476Y+101146X0280Y0320R180 S1      
327GND              C3248 -2          A01X+056734Y+101486X0280Y0320R180 S1      
327GND              C3240 -2          A01X+056522Y+100976X0120Y0150     S1      
327GND              C3239 -2          A01X+056625Y+100535X0280Y0320R270 S1      
327GND              C3219 -2          A01X+060269Y+101757X0280Y0320R270 S1      
327GND              C3213 -2          A01X+060269Y+103017X0280Y0320R270 S1      
327GND              C3162 -2          A18X+063104Y+115748X0120Y0150     S2      
327GND              C3179 -2          A18X+063104Y+116122X0120Y0150     S2      
327GND              C3175 -2          A18X+063104Y+116496X0120Y0150     S2      
327GND              C3174 -2          A18X+063104Y+115000X0120Y0150     S2      
327GND              C3178 -2          A18X+063104Y+115374X0120Y0150     S2      
327GND              C3161 -2          A18X+062515Y+112606X0280Y0320R090 S2      
327GND              C3112 -2          A18X+072185Y+119593X0120Y0150R270 S2      
327GND              C3092 -2          A18X+070689Y+119593X0120Y0150R270 S2      
327GND              C3104 -2          A18X+071063Y+119593X0120Y0150R270 S2      
327GND              C3083 -2          A18X+071437Y+119593X0120Y0150R270 S2      
327GND              C3086 -2          A18X+071811Y+119593X0120Y0150R270 S2      
327GND              C3085 -2          A18X+070315Y+119593X0120Y0150R270 S2      
327GND              C3117 -2          A18X+068819Y+119593X0120Y0150R270 S2      
327GND              C3089 -2          A18X+069567Y+119593X0120Y0150R270 S2      
327GND              C3084 -2          A18X+069193Y+119593X0120Y0150R270 S2      
327GND              C3076 -2          A18X+069941Y+119593X0120Y0150R270 S2      
327GND              C3091 -2          A18X+068445Y+119593X0120Y0150R270 S2      
327GND              C3090 -2          A18X+068071Y+119593X0120Y0150R270 S2      
327GND              C3081 -2          A18X+067697Y+119593X0120Y0150R270 S2      
327GND              C3078 -2          A18X+067323Y+119593X0120Y0150R270 S2      
327GND              C3088 -2          A18X+066949Y+119593X0120Y0150R270 S2      
327GND              C3087 -2          A18X+066575Y+119593X0120Y0150R270 S2      
327GND              C3079 -2          A18X+065827Y+119593X0120Y0150R270 S2      
327GND              C3077 -2          A18X+066201Y+119593X0120Y0150R270 S2      
327GND              C3137 -2          A18X+071998Y+120341X0120Y0150R270 S2      
327GND              C3160 -2          A18X+072372Y+120341X0120Y0150R270 S2      
327GND              C3127 -2          A18X+070876Y+120341X0120Y0150R270 S2      
327GND              C3128 -2          A18X+071250Y+120341X0120Y0150R270 S2      
327GND              C3139 -2          A18X+070502Y+120341X0120Y0150R270 S2      
327GND              C3129 -2          A18X+071624Y+120341X0120Y0150R270 S2      
327GND              C3140 -2          A18X+070128Y+120341X0120Y0150R270 S2      
327GND              C3152 -2          A18X+069390Y+120341X0120Y0150R270 S2      
327GND              C3143 -2          A18X+069754Y+120341X0120Y0150R270 S2      
327GND              C3119 -2          A18X+069000Y+120588X0280Y0320     S2      
327GND              C3136 -2          A18X+067510Y+120341X0120Y0150R270 S2      
327GND              C3154 -2          A18X+068610Y+120341X0120Y0150R270 S2      
327GND              C3147 -2          A18X+068258Y+120341X0120Y0150R270 S2      
327GND              C3145 -2          A18X+067884Y+120341X0120Y0150R270 S2      
327GND              C3155 -2          A18X+066388Y+120341X0120Y0150R270 S2      
327GND              C3151 -2          A18X+066762Y+120341X0120Y0150R270 S2      
327GND              C3157 -2          A18X+066014Y+120341X0120Y0150R270 S2      
327GND              C3156 -2          A18X+067136Y+120341X0120Y0150R270 S2      
327GND              C3141 -2          A18X+065640Y+120341X0120Y0150R270 S2      
327GND              C1450 -2          A18X+072185Y+118845X0120Y0150R270 S2      
327GND              C1482 -2          A18X+070689Y+118845X0120Y0150R270 S2      
327GND              C1446 -2          A18X+071811Y+118845X0120Y0150R270 S2      
327GND              C1451 -2          A18X+071437Y+118845X0120Y0150R270 S2      
327GND              C1475 -2          A18X+071063Y+118845X0120Y0150R270 S2      
327GND              C1473 -2          A18X+070315Y+118845X0120Y0150R270 S2      
327GND              C1470 -2          A18X+069193Y+118845X0120Y0150R270 S2      
327GND              C1454 -2          A18X+069567Y+118845X0120Y0150R270 S2      
327GND              C1430 -2          A18X+068819Y+118845X0120Y0150R270 S2      
327GND              C1494 -2          A18X+069941Y+118845X0120Y0150R270 S2      
327GND              C1484 -2          A18X+067697Y+118845X0120Y0150R270 S2      
327GND              C1469 -2          A18X+068071Y+118845X0120Y0150R270 S2      
327GND              C1466 -2          A18X+067323Y+118845X0120Y0150R270 S2      
327GND              C1459 -2          A18X+068445Y+118845X0120Y0150R270 S2      
327GND              C1443 -2          A18X+065827Y+118845X0120Y0150R270 S2      
327GND              C1429 -2          A18X+066201Y+118845X0120Y0150R270 S2      
327GND              C1477 -2          A18X+066949Y+118845X0120Y0150R270 S2      
327GND              C1445 -2          A18X+066575Y+118845X0120Y0150R270 S2      
327GND              C1444 -2          A18X+065459Y+118845X0120Y0150R270 S2      
327GND              C1437 -2          A18X+072185Y+114147X0120Y0150R090 S2      
327GND              C1491 -2          A18X+070315Y+114147X0120Y0150R090 S2      
327GND              C1458 -2          A18X+070689Y+114147X0120Y0150R090 S2      
327GND              C1465 -2          A18X+071063Y+114147X0120Y0150R090 S2      
327GND              C1438 -2          A18X+071811Y+114147X0120Y0150R090 S2      
327GND              C1427 -2          A18X+071437Y+114147X0120Y0150R090 S2      
327GND              C1433 -2          A18X+068819Y+114147X0120Y0150R090 S2      
327GND              C1489 -2          A18X+069567Y+114147X0120Y0150R090 S2      
327GND              C1483 -2          A18X+069193Y+114147X0120Y0150R090 S2      
327GND              C1480 -2          A18X+069941Y+114147X0120Y0150R090 S2      
327GND              C1485 -2          A18X+068071Y+114147X0120Y0150R090 S2      
327GND              C1467 -2          A18X+068445Y+114147X0120Y0150R090 S2      
327GND              C1453 -2          A18X+067323Y+114147X0120Y0150R090 S2      
327GND              C1452 -2          A18X+067697Y+114147X0120Y0150R090 S2      
327GND              C1431 -2          A18X+066575Y+114147X0120Y0150R090 S2      
327GND              C1428 -2          A18X+065827Y+114147X0120Y0150R090 S2      
327GND              C1425 -2          A18X+066201Y+114147X0120Y0150R090 S2      
327GND              C1486 -2          A18X+066949Y+114147X0120Y0150R090 S2      
327GND              C3103 -2          A18X+072185Y+113399X0120Y0150R090 S2      
327GND              C3111 -2          A18X+070315Y+113399X0120Y0150R090 S2      
327GND              C3106 -2          A18X+071811Y+113399X0120Y0150R090 S2      
327GND              C3095 -2          A18X+071063Y+113399X0120Y0150R090 S2      
327GND              C3108 -2          A18X+071437Y+113399X0120Y0150R090 S2      
327GND              C3109 -2          A18X+070689Y+113399X0120Y0150R090 S2      
327GND              C3107 -2          A18X+069567Y+113399X0120Y0150R090 S2      
327GND              C3105 -2          A18X+069941Y+113399X0120Y0150R090 S2      
327GND              C3099 -2          A18X+069193Y+113399X0120Y0150R090 S2      
327GND              C3096 -2          A18X+068819Y+113399X0120Y0150R090 S2      
327GND              C3100 -2          A18X+067323Y+113399X0120Y0150R090 S2      
327GND              C3093 -2          A18X+068445Y+113399X0120Y0150R090 S2      
327GND              C3116 -2          A18X+068071Y+113399X0120Y0150R090 S2      
327GND              C3101 -2          A18X+067697Y+113399X0120Y0150R090 S2      
327GND              C3094 -2          A18X+065827Y+113399X0120Y0150R090 S2      
327GND              C3115 -2          A18X+066575Y+113399X0120Y0150R090 S2      
327GND              C3098 -2          A18X+066201Y+113399X0120Y0150R090 S2      
327GND              C3097 -2          A18X+066949Y+113399X0120Y0150R090 S2      
327GND              C1424 -2          A18X+072185Y+118097X0120Y0150R270 S2      
327GND              C1423 -2          A18X+071811Y+118097X0120Y0150R270 S2      
327GND              C1440 -2          A18X+071437Y+118097X0120Y0150R270 S2      
327GND              C1460 -2          A18X+071063Y+118097X0120Y0150R270 S2      
327GND              C1468 -2          A18X+070689Y+118097X0120Y0150R270 S2      
327GND              C1481 -2          A18X+070315Y+118097X0120Y0150R270 S2      
327GND              C1474 -2          A18X+069941Y+118097X0120Y0150R270 S2      
327GND              C1472 -2          A18X+069193Y+118097X0120Y0150R270 S2      
327GND              C1449 -2          A18X+068819Y+118097X0120Y0150R270 S2      
327GND              C1492 -2          A18X+069567Y+118097X0120Y0150R270 S2      
327GND              C1476 -2          A18X+067323Y+118097X0120Y0150R270 S2      
327GND              C1463 -2          A18X+068445Y+118097X0120Y0150R270 S2      
327GND              C1457 -2          A18X+067697Y+118097X0120Y0150R270 S2      
327GND              C1455 -2          A18X+068071Y+118097X0120Y0150R270 S2      
327GND              C1436 -2          A18X+066575Y+118097X0120Y0150R270 S2      
327GND              C1432 -2          A18X+066201Y+118097X0120Y0150R270 S2      
327GND              C1426 -2          A18X+065827Y+118097X0120Y0150R270 S2      
327GND              C1462 -2          A18X+066949Y+118097X0120Y0150R270 S2      
327GND              C3075 -2          A18X+075228Y+116309X0280Y0320R090 S2      
327GND              C3113 -2          A18X+073786Y+117431X0120Y0150R180 S2      
327GND              C3114 -2          A18X+073786Y+115935X0120Y0150R180 S2      
327GND              C3080 -2          A18X+073786Y+117057X0120Y0150R180 S2      
327GND              C3102 -2          A18X+073786Y+116683X0120Y0150R180 S2      
327GND              C3110 -2          A18X+073786Y+115561X0120Y0150R180 S2      
327GND              C3149 -2          A18X+074534Y+116496X0120Y0150R180 S2      
327GND              C3121 -2          A18X+074534Y+116122X0120Y0150R180 S2      
327GND              C3122 -2          A18X+074534Y+116870X0120Y0150R180 S2      
327GND              C3123 -2          A18X+074534Y+117244X0120Y0150R180 S2      
327GND              C3124 -2          A18X+074534Y+115748X0120Y0150R180 S2      
327GND              C3082 -2          A18X+076905Y+116308X0280Y0320R270 S2      
327GND              R1321 -1          A01X+081048Y+121276X0198Y0197R135 S1      
327GND              R1318 -1          A01X+081614Y+121842X0198Y0197R135 S1      
327GND              R1316 -1          A01X+081331Y+121559X0198Y0197R135 S1      
327GND              C2010 -2          A18X+086819Y+083304X0280Y0320R090 S2      
327GND              C2011 -2          A18X+086819Y+082756X0280Y0320R090 S2      
327GND              C2012 -2          A18X+086819Y+082218X0280Y0320R090 S2      
327GND              PC227 -2          A01X+089844Y+124479X0400Y0500R180 S1      
327GND              PC226 -2          A01X+087644Y+124339X0400Y0500     S1      
327GND              PC224 -2          A01X+089844Y+123099X0400Y0500R180 S1      
327GND              PC225 -2          A01X+089844Y+123789X0400Y0500R180 S1      
327GND              PC228 -2          A01X+087644Y+123649X0400Y0500     S1      
327GND              PC229 -2          A01X+087644Y+122959X0400Y0500     S1      
327GND              PC237 -2          A01X+087282Y+121078X0198Y0197R090 S1      
327GND              R5535 -1   M      A01X+091966Y+080332X0198Y0197R090 S1      
327GND              R5529 -1   M      A01X+091572Y+080332X0198Y0197R090 S1      
327GND              PC247 -2          A01X+096242Y+124479X0400Y0500R180 S1      
327GND              PC245 -2          A01X+094042Y+124339X0400Y0500     S1      
327GND              PC250 -2          A01X+096242Y+123099X0400Y0500R180 S1      
327GND              PC246 -2          A01X+096242Y+123789X0400Y0500R180 S1      
327GND              PC244 -2          A01X+094042Y+122959X0400Y0500     S1      
327GND              PC249 -2          A01X+094042Y+123649X0400Y0500     S1      
327GND              PC257 -2          A01X+093679Y+121078X0198Y0197R090 S1      
327GND              C2020 -2          A18X+096085Y+081883X0280Y0320R270 S2      
327GND              C2016 -2          A18X+096085Y+080786X0280Y0320R270 S2      
327GND              C2015 -2          A18X+096085Y+081334X0280Y0320R270 S2      
327GND              C2759 -1          A18X+100974Y+087519X0198Y0197R180 S2      
327GND              C3381 -2          A01X+102020Y+114200X0280Y0320R180 S1      
327GND              C3382 -2          A01X+102460Y+114303X0120Y0150R270 S1      
327GND              C3397 -2          A01X+102971Y+114091X0280Y0320R090 S1      
327GND              C3409 -2          A01X+102971Y+112831X0280Y0320R090 S1      
327GND              C3402 -2          A01X+102460Y+113043X0120Y0150R270 S1      
327GND              C3365 -2          A01X+102020Y+112940X0280Y0320R180 S1      
327GND              C3410 -2          A01X+102971Y+111571X0280Y0320R090 S1      
327GND              C3385 -2          A01X+102020Y+111680X0280Y0320R180 S1      
327GND              C3384 -2          A01X+102460Y+111783X0120Y0150R270 S1      
327GND              C3421 -2          A01X+102971Y+110311X0280Y0320R090 S1      
327GND              C3400 -2          A01X+102460Y+110523X0120Y0150R270 S1      
327GND              C3383 -2          A01X+102020Y+110420X0280Y0320R180 S1      
327GND              C3422 -2          A01X+102443Y+101486X0280Y0320R180 S1      
327GND              C3413 -2          A01X+102334Y+100535X0280Y0320R270 S1      
327GND              C3414 -2          A01X+102231Y+100976X0120Y0150     S1      
327GND              C3379 -2          A01X+102971Y+117871X0280Y0320R090 S1      
327GND              C3364 -2          A01X+102460Y+118083X0120Y0150R270 S1      
327GND              C3367 -2          A01X+102020Y+117980X0280Y0320R180 S1      
327GND              C3378 -2          A01X+102971Y+116611X0280Y0320R090 S1      
327GND              C3401 -2          A01X+102020Y+116720X0280Y0320R180 S1      
327GND              C3380 -2          A01X+102971Y+115351X0280Y0320R090 S1      
327GND              C3386 -2          A01X+102460Y+115563X0120Y0150R270 S1      
327GND              C3411 -2          A01X+102020Y+115460X0280Y0320R180 S1      
327GND              C3363 -2          A01X+103184Y+102406X0280Y0320R180 S1      
327GND              C3396 -2          A01X+104135Y+102297X0280Y0320R090 S1      
327GND              C3366 -2          A01X+103625Y+102509X0120Y0150R270 S1      
327GND              C3368 -2          A01X+103625Y+101249X0120Y0150R270 S1      
327GND              C3399 -2          A01X+103184Y+101146X0280Y0320R180 S1      
327GND              C3398 -2          A01X+104135Y+101037X0280Y0320R090 S1      
327GND              C3387 -2          A01X+105977Y+103017X0280Y0320R270 S1      
327GND              C3393 -2          A01X+105977Y+101757X0280Y0320R270 S1      
327GND              PC213 -2          A18X+005654Y+111010X0400Y0500     S2      
327GND              PC212 -2          A18X+005654Y+111910X0400Y0500     S2      
327GND              PC215 -2          A18X+001571Y+111663X0400Y0500R180 S2      
327GND              PC214 -2          A18X+001571Y+112563X0400Y0500R180 S2      
327GND              PC256 -2          A01X+096540Y+113393X0198Y0197     S1      
327GND              PC236 -2          A01X+090143Y+113393X0198Y0197     S1      
327GND              PC252 -2          A18X+096721Y+112810X0400Y0500     S2      
327GND              PC254 -2          A18X+092638Y+113464X0400Y0500R180 S2      
327GND              PC235 -2          A18X+090323Y+112810X0400Y0500     S2      
327GND              PC233 -2          A18X+086240Y+113464X0400Y0500R180 S2      
327GND              PC253 -2          A18X+096721Y+111910X0400Y0500     S2      
327GND              PC255 -2          A18X+092638Y+112564X0400Y0500R180 S2      
327GND              PC234 -2          A18X+090323Y+111910X0400Y0500     S2      
327GND              PC232 -2          A18X+086240Y+112564X0400Y0500R180 S2      
317GND              VIA   -    MD0100PA00X+107135Y+105050X0200Y         S0      
317GND              VIA   -    MD0100PA00X+106017Y+105048X0200Y         S0      
317GND              VIA   -    MD0100PA00X+107164Y+105803X0200Y         S0      
317GND              VIA   -    MD0100PA00X+106693Y+104057X0200Y         S0      
317GND              VIA   -    MD0100PA00X+105969Y+102495X0200Y         S0      
317GND              VIA   -    MD0100PA00X+105969Y+101235X0200Y         S0      
317GND              VIA   -    MD0100PA00X+107078Y+101225X0200Y         S0      
317GND              VIA   -    MD0100PA00X+105801Y+099786X0200Y         S0      
327GND              R1362 -1          A01X+105801Y+099511X0198Y0197R270 S1      
317GND              VIA   -    MD0100PA00X+106201Y+099786X0200Y         S0      
327GND              R1366 -1          A01X+106201Y+099511X0198Y0197R270 S1      
317GND              VIA   -    MD0100PA00X+106601Y+099786X0200Y         S0      
327GND              R1355 -1          A01X+106601Y+099511X0198Y0197R270 S1      
317GND              VIA   -    MD0100PA00X+105796Y+093192X0200Y         S0      
317GND              VIA   -    MD0100PA00X+102493Y+071786X0200Y    R090 S0      
317GND              VIA   -    MD0100PA00X+102512Y+069833X0200Y    R090 S0      
317GND              VIA   -    MD0100PA00X+101816Y+068413X0200Y    R090 S0      
317GND              VIA   -    MD0100PA00X+101824Y+067865X0200Y    R090 S0      
317GND              VIA   -    MD0100PA00X+036849Y+081509X0200Y    R090 S0      
317GND              VIA   -    MD0100PA00X+001796Y+080930X0200Y    R270 S0      
317GND              VIA   -    MD0100PA00X+105146Y+163980X0200Y         S0      
317GND              VIA   -    MD0100PA00X+103146Y+163980X0200Y         S0      
317GND              VIA   -    MD0100PA00X+101146Y+163980X0200Y         S0      
317GND              VIA   -    MD0100PA00X+000304Y+119804X0200Y    R270 S0      
317GND              VIA   -    MD0100PA00X+000304Y+117804X0200Y    R270 S0      
317GND              VIA   -    MD0100PA00X+000304Y+115804X0200Y    R270 S0      
317GND              VIA   -    MD0100PA00X+000304Y+113804X0200Y    R270 S0      
317GND              VIA   -    MD0100PA00X+000304Y+111804X0200Y    R270 S0      
317GND              VIA   -    MD0100PA00X+000304Y+109804X0200Y    R270 S0      
317GND              VIA   -    MD0100PA00X+000304Y+107804X0200Y    R270 S0      
317GND              VIA   -    MD0100PA00X+000304Y+105804X0200Y    R270 S0      
317GND              VIA   -    MD0100PA00X+000304Y+103804X0200Y    R270 S0      
317GND              VIA   -    MD0100PA00X+000304Y+101804X0200Y    R270 S0      
317GND              VIA   -    MD0100PA00X+000304Y+099804X0200Y    R270 S0      
317GND              VIA   -    MD0100PA00X+000304Y+097804X0200Y    R270 S0      
317GND              VIA   -    MD0100PA00X+001200Y+164498X0200Y         S0      
317GND              VIA   -    MD0100PA00X+001675Y+113033X0200Y         S0      
317GND              VIA   -    MD0100PA00X+001425Y+113033X0200Y         S0      
317GND              VIA   -    MD0100PA00X+001665Y+111163X0200Y         S0      
317GND              VIA   -    MD0100PA00X+000885Y+111163X0200Y         S0      
317GND              VIA   -    MD0100PA00X+001145Y+111163X0200Y         S0      
317GND              VIA   -    MD0100PA00X+001415Y+111163X0200Y         S0      
317GND              VIA   -    MD0100PA00X+000895Y+112133X0200Y         S0      
317GND              VIA   -    MD0100PA00X+001675Y+112133X0200Y         S0      
317GND              VIA   -    MD0100PA00X+001155Y+112133X0200Y         S0      
317GND              VIA   -    MD0100PA00X+001425Y+112133X0200Y         S0      
317GND              VIA   -    MD0100PA00X+001796Y+094930X0200Y    R270 S0      
317GND              VIA   -    MD0100PA00X+000955Y+096195X0200Y    R270 S0      
317GND              VIA   -    MD0100PA00X+001796Y+092930X0200Y    R270 S0      
317GND              VIA   -    MD0100PA00X+001796Y+090930X0200Y    R270 S0      
317GND              VIA   -    MD0100PA00X+001796Y+088930X0200Y    R270 S0      
317GND              VIA   -    MD0100PA00X+001796Y+086930X0200Y    R270 S0      
317GND              VIA   -    MD0100PA00X+001796Y+084930X0200Y    R270 S0      
317GND              VIA   -    MD0100PA00X+001796Y+082930X0200Y    R270 S0      
317GND              VIA   -    MD0100PA00X+000302Y+163947X0200Y         S0      
317GND              VIA   -    MD0100PA00X+000304Y+157804X0200Y         S0      
317GND              VIA   -    MD0100PA00X+000304Y+155804X0200Y    R270 S0      
317GND              VIA   -    MD0100PA00X+000304Y+153804X0200Y    R270 S0      
317GND              VIA   -    MD0100PA00X+000304Y+149804X0200Y    R270 S0      
317GND              VIA   -    MD0100PA00X+000304Y+147804X0200Y    R270 S0      
317GND              VIA   -    MD0100PA00X+000304Y+145804X0200Y    R270 S0      
317GND              VIA   -    MD0100PA00X+000304Y+143804X0200Y    R270 S0      
317GND              VIA   -    MD0100PA00X+000304Y+141804X0200Y    R270 S0      
317GND              VIA   -    MD0100PA00X+000304Y+139804X0200Y    R270 S0      
317GND              VIA   -    MD0100PA00X+000304Y+137804X0200Y    R270 S0      
317GND              VIA   -    MD0100PA00X+000304Y+135804X0200Y    R270 S0      
317GND              VIA   -    MD0100PA00X+000304Y+133804X0200Y    R270 S0      
317GND              VIA   -    MD0100PA00X+000304Y+131804X0200Y    R270 S0      
317GND              VIA   -    MD0100PA00X+000304Y+129804X0200Y    R270 S0      
317GND              VIA   -    MD0100PA00X+000304Y+127804X0200Y    R270 S0      
317GND              VIA   -    MD0100PA00X+000304Y+125804X0200Y    R270 S0      
317GND              VIA   -    MD0100PA00X+000304Y+123804X0200Y    R270 S0      
317GND              VIA   -    MD0100PA00X+005292Y+090030X0200Y         S0      
317GND              VIA   -    MD0100PA00X+003200Y+164498X0200Y         S0      
317GND              VIA   -    MD0100PA00X+003041Y+122540X0200Y    R180 S0      
317GND              VIA   -    MD0100PA00X+003041Y+122790X0200Y    R180 S0      
317GND              VIA   -    MD0100PA00X+003041Y+123230X0200Y    R180 S0      
317GND              VIA   -    MD0100PA00X+003041Y+123480X0200Y    R180 S0      
317GND              VIA   -    MD0100PA00X+003093Y+120711X0200Y    R270 S0      
317GND              VIA   -    MD0100PA00X+003093Y+120991X0200Y    R270 S0      
317GND              VIA   -    MD0100PA00X+003093Y+121271X0200Y    R270 S0      
317GND              VIA   -    MD0100PA00X+002793Y+120711X0200Y    R270 S0      
317GND              VIA   -    MD0100PA00X+002793Y+120991X0200Y    R270 S0      
317GND              VIA   -    MD0100PA00X+002793Y+121271X0200Y    R270 S0      
317GND              VIA   -    MD0100PA00X+003431Y+121540X0200Y         S0      
317GND              VIA   -    MD0100PA00X+003093Y+121551X0200Y    R270 S0      
317GND              VIA   -    MD0100PA00X+002793Y+121551X0200Y    R270 S0      
317GND              VIA   -    MD0100PA00X+003041Y+122100X0200Y    R180 S0      
317GND              VIA   -    MD0100PA00X+003041Y+121850X0200Y    R180 S0      
317GND              VIA   -    MD0100PA00X+003093Y+120431X0200Y    R270 S0      
317GND              VIA   -    MD0100PA00X+002793Y+120431X0200Y    R270 S0      
317GND              VIA   -    MD0100PA00X+003822Y+109376X0200Y         S0      
317GND              VIA   -    M      A01X+003945Y+125093X0200Y         S2      
017GND              VIA   -    M      A18X+003945Y+125093X0260Y         S2      
017GND                    -    MD0100PA00X+003945Y+125093                       
327GND              PC203 -2          A01X+003945Y+124845X0198Y0197R180 S1      
317GND              VIA   -    MD0100PA00X+005120Y+121821X0200Y         S0      
317GND              VIA   -    MD0100PA00X+004964Y+120388X0200Y    R270 S0      
317GND              VIA   -    MD0100PA00X+004950Y+119907X0200Y         S0      
317GND              VIA   -    MD0100PA00X+004496Y+119062X0200Y    R270 S0      
317GND              VIA   -    MD0100PA00X+004436Y+108640X0200Y         S0      
327GND              U87   -10         A01X+004720Y+108565X0090Y0240R090 S1      
317GND              VIA   -    MD0100PA00X+003820Y+108972X0200Y         S0      
327GND              C626  -2          A01X+004070Y+108972X0198Y0197R090 S1      
317GND              VIA   -    MD0100PA00X+005037Y+108239X0200Y         S0      
317GND              VIA   -    MD0100PA00X+005037Y+108698X0200Y         S0      
317GND              VIA   -    MD0100PA00X+005825Y+122340X0200Y         S0      
317GND              VIA   -    MD0100PA00X+005825Y+123470X0200Y         S0      
317GND              VIA   -    MD0100PA00X+005825Y+123720X0200Y         S0      
317GND              VIA   -    MD0100PA00X+005825Y+123030X0200Y         S0      
317GND              VIA   -    MD0100PA00X+005825Y+122780X0200Y         S0      
317GND              VIA   -    MD0100PA00X+006594Y+120938X0200Y         S0      
317GND              VIA   -    MD0100PA00X+005825Y+122090X0200Y         S0      
317GND              VIA   -    MD0100PA00X+005722Y+112387X0200Y         S0      
317GND              VIA   -    MD0100PA00X+006438Y+111480X0200Y         S0      
317GND              VIA   -    MD0100PA00X+005908Y+111480X0200Y         S0      
317GND              VIA   -    MD0100PA00X+005648Y+111480X0200Y         S0      
317GND              VIA   -    MD0100PA00X+006168Y+111480X0200Y         S0      
317GND              VIA   -    MD0100PA00X+006428Y+110510X0200Y         S0      
317GND              VIA   -    MD0100PA00X+006158Y+110510X0200Y         S0      
317GND              VIA   -    MD0100PA00X+005638Y+110510X0200Y         S0      
317GND              VIA   -    MD0100PA00X+005898Y+110510X0200Y         S0      
317GND              VIA   -    MD0100PA00X+005500Y+108694X0200Y         S0      
317GND              VIA   -    MD0100PA00X+005505Y+108234X0200Y         S0      
327GND              U87   -TH  M      A01X+005271Y+108467X0670Y0670R180 S1      
317GND              VIA   -    MD0100PA00X+006330Y+091284X0200Y         S0      
317GND              VIA   -    MD0100PA00X+006746Y+091298X0200Y         S0      
317GND              VIA   -    MD0100PA00X+006418Y+089750X0200Y         S0      
317GND              VIA   -    MD0100PA00X+006732Y+086587X0200Y         S0      
317GND              VIA   -    MD0100PA00X+006634Y+088007X0200Y         S0      
327GND              R3442 -2          A18X+006374Y+088007X0198Y0197R090 S2      
317GND              VIA   -    MD0100PA00X+005200Y+164498X0200Y         S0      
317GND              VIA   -    MD0100PA00X+007006Y+107966X0200Y         S0      
327GND              R774  -2          A01X+006766Y+107966X0198Y0197     S1      
317GND              VIA   -    MD0100PA00X+007006Y+107166X0200Y         S0      
327GND              R773  -2          A01X+006766Y+107166X0198Y0197     S1      
317GND              VIA   -    MD0100PA00X+008468Y+101837X0200Y         S0      
327GND              Q12   -1          A01X+008468Y+101517X0240Y0240R270 S1      
317GND              VIA   -    MD0100PA00X+007699Y+094613X0200Y         S0      
317GND              VIA   -    MD0100PA00X+007193Y+087368X0200Y    R090 S0      
327GND              C2216 -1          A18X+007193Y+087661X0198Y0197     S2      
317GND              VIA   -    MD0100PA00X+006874Y+158350X0200Y         S0      
317GND              VIA   -    M      A01X+010312Y+116509X0200Y         S2      
017GND              VIA   -    M      A18X+010312Y+116509X0260Y         S2      
017GND                    -    MD0100PA00X+010312Y+116509                       
317GND              VIA   -    MD0100PA00X+009725Y+103057X0200Y         S0      
317GND              VIA   -    M      A01X+010059Y+103509X0200Y         S2      
017GND              VIA   -    M      A18X+010059Y+103509X0260Y         S2      
017GND                    -    MD0100PA00X+010059Y+103509                       
317GND              VIA   -    MD0100PA00X+009584Y+099786X0200Y         S0      
327GND              R1215 -1          A01X+009584Y+099511X0198Y0197R270 S1      
317GND              VIA   -    MD0100PA00X+009984Y+099786X0200Y         S0      
327GND              R1203 -1          A01X+009984Y+099511X0198Y0197R270 S1      
317GND              VIA   -    MD0100PA00X+009113Y+100649X0200Y         S0      
327GND              Q12   -4          A01X+009176Y+100926X0240Y0240R270 S1      
317GND              VIA   -    MD0100PA00X+008785Y+089922X0200Y         S0      
327GND              U65   -8          A18X+008653Y+090483X0140Y0610R180 S2      
317GND              VIA   -    MD0100PA00X+009158Y+087486X0200Y         S0      
317GND              VIA   -    MD0100PA00X+009158Y+087786X0200Y         S0      
317GND              VIA   -    M      A01X+008888Y+084094X0200Y         S2      
017GND              VIA   -    M      A18X+008888Y+084094X0260Y         S2      
017GND                    -    MD0100PA00X+008888Y+084094                       
317GND              VIA   -    MD0100PA00X+007200Y+164498X0200Y         S0      
317GND              VIA   -    MD0100PA00X+008243Y+158059X0200Y         S0      
317GND              VIA   -    MD0100PA00X+007600Y+158068X0200Y         S0      
317GND              VIA   -    MD0100PA00X+011243Y+115249X0200Y         S0      
317GND              VIA   -    MD0100PA00X+010893Y+115249X0200Y         S0      
317GND              VIA   -    MD0100PA00X+010312Y+115249X0200Y         S0      
317GND              VIA   -    MD0100PA00X+011243Y+113989X0200Y         S0      
317GND              VIA   -    MD0100PA00X+010312Y+112729X0200Y         S0      
317GND              VIA   -    MD0100PA00X+011243Y+112729X0200Y         S0      
317GND              VIA   -    MD0100PA00X+010893Y+112729X0200Y         S0      
317GND              VIA   -    MD0100PA00X+010893Y+111469X0200Y         S0      
317GND              VIA   -    MD0100PA00X+010312Y+111469X0200Y         S0      
317GND              VIA   -    MD0100PA00X+011243Y+111469X0200Y         S0      
317GND              VIA   -    MD0100PA00X+010312Y+110209X0200Y         S0      
317GND              VIA   -    MD0100PA00X+011243Y+110209X0200Y         S0      
317GND              VIA   -    MD0100PA00X+010893Y+110209X0200Y         S0      
317GND              VIA   -    MD0100PA00X+011128Y+101176X0200Y    R090 S0      
317GND              VIA   -    MD0100PA00X+011584Y+099786X0200Y         S0      
327GND              R1193 -1          A01X+011584Y+099511X0198Y0197R270 S1      
317GND              VIA   -    MD0100PA00X+010784Y+099786X0200Y         S0      
327GND              R1196 -1          A01X+010784Y+099511X0198Y0197R270 S1      
317GND              VIA   -    MD0100PA00X+011477Y+100935X0200Y         S0      
317GND              VIA   -    MD0100PA00X+011128Y+100826X0200Y    R090 S0      
317GND              VIA   -    MD0100PA00X+011184Y+099786X0200Y         S0      
327GND              R1188 -1          A01X+011184Y+099511X0198Y0197R270 S1      
317GND              VIA   -    MD0100PA00X+010384Y+099786X0200Y         S0      
327GND              R1192 -1          A01X+010384Y+099511X0198Y0197R270 S1      
317GND              VIA   -    MD0100PA00X+010764Y+086522X0200Y         S0      
317GND              VIA   -    MD0100PA00X+011360Y+088127X0200Y         S0      
317GND              VIA   -    MD0100PA00X+009200Y+164498X0200Y         S0      
317GND              VIA   -    MD0100PA00X+011280Y+122375X0200Y         S0      
327GND              R1168 -1          A01X+011520Y+122615X0198Y0197R045 S1      
317GND              VIA   -    MD0100PA00X+010659Y+120493X0200Y    R315 S0      
327GND              R1167 -1          A01X+010954Y+120788X0198Y0197R045 S1      
317GND              VIA   -    M      A01X+010942Y+120210X0200Y         S2      
017GND              VIA   -    M      A18X+010942Y+120210X0260Y         S2      
017GND                    -    MD0100PA00X+010942Y+120210                       
327GND              R1252 -1          A01X+011236Y+120505X0198Y0197R045 S1      
317GND              VIA   -    MD0100PA00X+011243Y+117769X0200Y         S0      
317GND              VIA   -    MD0100PA00X+010893Y+117769X0200Y         S0      
317GND              VIA   -    MD0100PA00X+010318Y+117769X0200Y         S0      
317GND              VIA   -    MD0100PA00X+011243Y+116509X0200Y         S0      
317GND              VIA   -    MD0100PA00X+010893Y+116509X0200Y         S0      
317GND              VIA   -    MD0100PA00X+011633Y+146078X0200Y         S0      
317GND              VIA   -    MD0100PA00X+010767Y+146118X0200Y         S0      
317GND              VIA   -    MD0100PA00X+011633Y+146551X0200Y         S0      
317GND              VIA   -    MD0100PA00X+010767Y+146591X0200Y         S0      
317GND              VIA   -    MD0100PA00X+010767Y+145645X0200Y         S0      
317GND              VIA   -    MD0100PA00X+010767Y+158952X0200Y         S0      
317GND              VIA   -    MD0100PA00X+011633Y+158796X0200Y         S0      
317GND              VIA   -    MD0100PA00X+010767Y+157417X0200Y         S0      
317GND              VIA   -    MD0100PA00X+011633Y+157261X0200Y         S0      
317GND              VIA   -    MD0100PA00X+011633Y+157850X0200Y         S0      
317GND              VIA   -    MD0100PA00X+010767Y+157890X0200Y         S0      
317GND              VIA   -    MD0100PA00X+011633Y+156788X0200Y         S0      
317GND              VIA   -    MD0100PA00X+010767Y+156828X0200Y         S0      
317GND              VIA   -    MD0100PA00X+010767Y+155881X0200Y         S0      
317GND              VIA   -    MD0100PA00X+011633Y+156314X0200Y         S0      
317GND              VIA   -    MD0100PA00X+010767Y+156354X0200Y         S0      
317GND              VIA   -    MD0100PA00X+011633Y+151631X0200Y         S0      
317GND              VIA   -    MD0100PA00X+010767Y+150724X0200Y         S0      
317GND              VIA   -    MD0100PA00X+010767Y+151198X0200Y         S0      
317GND              VIA   -    MD0100PA00X+011633Y+151158X0200Y         S0      
317GND              VIA   -    MD0100PA00X+010767Y+150251X0200Y         S0      
317GND              VIA   -    MD0100PA00X+011633Y+150095X0200Y         S0      
317GND              VIA   -    MD0100PA00X+011633Y+150684X0200Y         S0      
317GND              VIA   -    MD0100PA00X+010767Y+149189X0200Y         S0      
317GND              VIA   -    MD0100PA00X+011633Y+149622X0200Y         S0      
317GND              VIA   -    MD0100PA00X+010767Y+149662X0200Y         S0      
317GND              VIA   -    MD0100PA00X+010767Y+148716X0200Y         S0      
317GND              VIA   -    MD0100PA00X+011633Y+148560X0200Y         S0      
317GND              VIA   -    MD0100PA00X+011633Y+149149X0200Y         S0      
317GND              VIA   -    MD0100PA00X+010767Y+147180X0200Y         S0      
317GND              VIA   -    MD0100PA00X+011633Y+147024X0200Y         S0      
317GND              VIA   -    MD0100PA00X+011633Y+147614X0200Y         S0      
317GND              VIA   -    MD0100PA00X+010767Y+147654X0200Y         S0      
317GND              VIA   -    MD0100PA00X+011633Y+148087X0200Y         S0      
317GND              VIA   -    MD0100PA00X+010767Y+148127X0200Y         S0      
317GND              VIA   -    MD0100PA00X+013387Y+115549X0200Y         S0      
317GND              VIA   -    MD0100PA00X+013387Y+114289X0200Y         S0      
317GND              VIA   -    MD0100PA00X+013387Y+113029X0200Y         S0      
317GND              VIA   -    MD0100PA00X+013387Y+111769X0200Y         S0      
317GND              VIA   -    MD0100PA00X+013387Y+110509X0200Y         S0      
317GND              VIA   -    M      A01X+012408Y+102195X0200Y         S2      
017GND              VIA   -    M      A18X+012408Y+102195X0260Y         S2      
017GND                    -    MD0100PA00X+012408Y+102195                       
317GND              VIA   -    MD0100PA00X+012058Y+102195X0200Y         S0      
317GND              VIA   -    MD0100PA00X+012058Y+100935X0200Y         S0      
317GND              VIA   -    MD0100PA00X+012384Y+099786X0200Y         S0      
327GND              R1195 -1          A01X+012384Y+099511X0198Y0197R270 S1      
317GND              VIA   -    MD0100PA00X+012784Y+099786X0200Y         S0      
327GND              R1204 -1          A01X+012784Y+099511X0198Y0197R270 S1      
317GND              VIA   -    MD0100PA00X+013184Y+099786X0200Y         S0      
327GND              R1187 -1          A01X+013184Y+099511X0198Y0197R270 S1      
317GND              VIA   -    MD0100PA00X+011984Y+099786X0200Y         S0      
327GND              R1190 -1          A01X+011984Y+099511X0198Y0197R270 S1      
317GND              VIA   -    MD0100PA00X+012408Y+100935X0200Y         S0      
317GND              VIA   -    MD0100PA00X+012707Y+089150X0200Y         S0      
317GND              VIA   -    MD0100PA00X+012289Y+088400X0200Y         S0      
317GND              VIA   -    MD0100PA00X+011200Y+164498X0200Y         S0      
317GND              VIA   -    MD0100PA00X+010767Y+161434X0200Y         S0      
317GND              VIA   -    MD0100PA00X+011633Y+161867X0200Y         S0      
317GND              VIA   -    MD0100PA00X+011633Y+161394X0200Y         S0      
317GND              VIA   -    MD0100PA00X+010767Y+160488X0200Y         S0      
317GND              VIA   -    MD0100PA00X+011633Y+160332X0200Y         S0      
317GND              VIA   -    MD0100PA00X+011633Y+159858X0200Y         S0      
317GND              VIA   -    MD0100PA00X+010767Y+159898X0200Y         S0      
317GND              VIA   -    MD0100PA00X+011633Y+160921X0200Y         S0      
317GND              VIA   -    MD0100PA00X+010767Y+160961X0200Y         S0      
317GND              VIA   -    MD0100PA00X+011633Y+159385X0200Y         S0      
317GND              VIA   -    MD0100PA00X+010767Y+159425X0200Y         S0      
317GND              VIA   -    MD0100PA00X+011633Y+158323X0200Y         S0      
317GND              VIA   -    MD0100PA00X+010767Y+158363X0200Y         S0      
317GND              VIA   -    MD0100PA00X+012694Y+120961X0200Y         S0      
327GND              R1186 -1          A01X+013217Y+120918X0198Y0197R045 S1      
317GND              VIA   -    MD0100PA00X+012121Y+121520X0200Y         S0      
327GND              R1169 -1          A01X+012368Y+121767X0198Y0197R045 S1      
317GND              VIA   -    MD0100PA00X+013387Y+116809X0200Y         S0      
317GND              VIA   -    MD0100PA00X+013365Y+148087X0200Y         S0      
317GND              VIA   -    MD0100PA00X+013365Y+147024X0200Y         S0      
317GND              VIA   -    MD0100PA00X+013365Y+147614X0200Y         S0      
317GND              VIA   -    MD0100PA00X+012499Y+148127X0200Y         S0      
317GND              VIA   -    MD0100PA00X+012499Y+147654X0200Y         S0      
317GND              VIA   -    MD0100PA00X+012499Y+147180X0200Y         S0      
317GND              VIA   -    MD0100PA00X+013365Y+146078X0200Y         S0      
317GND              VIA   -    MD0100PA00X+013365Y+146551X0200Y         S0      
317GND              VIA   -    MD0100PA00X+012499Y+146118X0200Y         S0      
317GND              VIA   -    MD0100PA00X+012499Y+145645X0200Y         S0      
317GND              VIA   -    MD0100PA00X+012499Y+146591X0200Y         S0      
317GND              VIA   -    MD0100PA00X+012499Y+156828X0200Y         S0      
317GND              VIA   -    MD0100PA00X+013365Y+157261X0200Y         S0      
317GND              VIA   -    MD0100PA00X+013365Y+157850X0200Y         S0      
317GND              VIA   -    MD0100PA00X+012499Y+157890X0200Y         S0      
317GND              VIA   -    MD0100PA00X+012499Y+157417X0200Y         S0      
317GND              VIA   -    MD0100PA00X+013365Y+156788X0200Y         S0      
317GND              VIA   -    MD0100PA00X+013365Y+156314X0200Y         S0      
317GND              VIA   -    MD0100PA00X+012499Y+156354X0200Y         S0      
317GND              VIA   -    MD0100PA00X+012499Y+155881X0200Y         S0      
317GND              VIA   -    MD0100PA00X+013365Y+151631X0200Y         S0      
317GND              VIA   -    MD0100PA00X+012499Y+150251X0200Y         S0      
317GND              VIA   -    MD0100PA00X+012499Y+150724X0200Y         S0      
317GND              VIA   -    MD0100PA00X+012499Y+151198X0200Y         S0      
317GND              VIA   -    MD0100PA00X+013365Y+151158X0200Y         S0      
317GND              VIA   -    MD0100PA00X+013365Y+150095X0200Y         S0      
317GND              VIA   -    MD0100PA00X+013365Y+150684X0200Y         S0      
317GND              VIA   -    MD0100PA00X+013365Y+148560X0200Y         S0      
317GND              VIA   -    MD0100PA00X+013365Y+149149X0200Y         S0      
317GND              VIA   -    MD0100PA00X+012499Y+149662X0200Y         S0      
317GND              VIA   -    MD0100PA00X+012499Y+149189X0200Y         S0      
317GND              VIA   -    MD0100PA00X+012499Y+148716X0200Y         S0      
317GND              VIA   -    MD0100PA00X+013365Y+149622X0200Y         S0      
327GND              PEX0  -BA1        A01X+014508Y+110512X0180Y         S1      
327GND              PEX0  -BF2        A01X+014882Y+108642X0180Y         S1      
327GND              PEX0  -BH1        A01X+014508Y+107894X0180Y         S1      
327GND              PEX0  -BH2        A01X+014882Y+107894X0180Y         S1      
327GND              PEX0  -BF1        A01X+014508Y+108642X0180Y         S1      
317GND              VIA   -    MD0100PA00X+014853Y+104648X0200Y         S0      
317GND              VIA   -    MD0100PA00X+014552Y+101235X0200Y         S0      
317GND              VIA   -    MD0100PA00X+014552Y+102495X0200Y         S0      
317GND              VIA   -    MD0100PA00X+013584Y+099786X0200Y         S0      
327GND              R1233 -1          A01X+013584Y+099511X0198Y0197R270 S1      
317GND              VIA   -    MD0100PA00X+014384Y+099786X0200Y         S0      
327GND              R1199 -1          A01X+014384Y+099511X0198Y0197R270 S1      
317GND              VIA   -    MD0100PA00X+014784Y+099786X0200Y         S0      
327GND              R1216 -1          A01X+014784Y+099511X0198Y0197R270 S1      
317GND              VIA   -    MD0100PA00X+013984Y+099786X0200Y         S0      
327GND              R1234 -1          A01X+013984Y+099511X0198Y0197R270 S1      
317GND              VIA   -    MD0100PA00X+013200Y+164498X0200Y         S0      
317GND              VIA   -    MD0100PA00X+013365Y+161867X0200Y         S0      
317GND              VIA   -    MD0100PA00X+013365Y+161394X0200Y         S0      
317GND              VIA   -    MD0100PA00X+012499Y+161434X0200Y         S0      
317GND              VIA   -    MD0100PA00X+013365Y+160332X0200Y         S0      
317GND              VIA   -    MD0100PA00X+013365Y+159858X0200Y         S0      
317GND              VIA   -    MD0100PA00X+013365Y+160921X0200Y         S0      
317GND              VIA   -    MD0100PA00X+012499Y+159898X0200Y         S0      
317GND              VIA   -    MD0100PA00X+012499Y+160488X0200Y         S0      
317GND              VIA   -    MD0100PA00X+012499Y+160961X0200Y         S0      
317GND              VIA   -    MD0100PA00X+013365Y+158323X0200Y         S0      
317GND              VIA   -    MD0100PA00X+012499Y+158363X0200Y         S0      
317GND              VIA   -    MD0100PA00X+013365Y+158796X0200Y         S0      
317GND              VIA   -    MD0100PA00X+013365Y+159385X0200Y         S0      
317GND              VIA   -    MD0100PA00X+012499Y+159425X0200Y         S0      
317GND              VIA   -    MD0100PA00X+012499Y+158952X0200Y         S0      
317GND              VIA   -    MD0100PA00X+013446Y+118065X0200Y         S0      
327GND              PEX0  -AF2        A01X+014882Y+116122X0180Y         S1      
327GND              PEX0  -AD1        A01X+014508Y+116870X0180Y         S1      
327GND              PEX0  -AF1        A01X+014508Y+116122X0180Y         S1      
327GND              PEX0  -AH2        A01X+014882Y+115374X0180Y         S1      
327GND              PEX0  -AK2        A01X+014882Y+114626X0180Y         S1      
327GND              PEX0  -AH1        A01X+014508Y+115374X0180Y         S1      
327GND              PEX0  -AK1        A01X+014508Y+114626X0180Y         S1      
327GND              PEX0  -AR2        A01X+014882Y+112756X0180Y         S1      
327GND              PEX0  -AN1        A01X+014508Y+113504X0180Y         S1      
327GND              PEX0  -AR1        A01X+014508Y+112756X0180Y         S1      
327GND              PEX0  -AN2        A01X+014882Y+113504X0180Y         S1      
327GND              PEX0  -AU2        A01X+014882Y+112008X0180Y         S1      
327GND              PEX0  -AW2        A01X+014882Y+111260X0180Y         S1      
327GND              PEX0  -AU1        A01X+014508Y+112008X0180Y         S1      
327GND              PEX0  -AW1        A01X+014508Y+111260X0180Y         S1      
327GND              PEX0  -BA2        A01X+014882Y+110512X0180Y         S1      
327GND              PEX0  -BC2        A01X+014882Y+109764X0180Y         S1      
327GND              PEX0  -BC1        A01X+014508Y+109764X0180Y         S1      
327GND              PEX0  -B1         A01X+014508Y+125098X0180Y         S1      
317GND              VIA   -    MD0100PA00X+014232Y+146591X0200Y         S0      
317GND              VIA   -    MD0100PA00X+014232Y+146118X0200Y         S0      
317GND              VIA   -    MD0100PA00X+014232Y+145645X0200Y         S0      
317GND              VIA   -    MD0100PA00X+014232Y+156828X0200Y         S0      
317GND              VIA   -    MD0100PA00X+014232Y+157890X0200Y         S0      
317GND              VIA   -    MD0100PA00X+014232Y+157417X0200Y         S0      
317GND              VIA   -    MD0100PA00X+014232Y+156354X0200Y         S0      
317GND              VIA   -    MD0100PA00X+014232Y+155881X0200Y         S0      
317GND              VIA   -    MD0100PA00X+014232Y+151198X0200Y         S0      
317GND              VIA   -    MD0100PA00X+014232Y+150251X0200Y         S0      
317GND              VIA   -    MD0100PA00X+014232Y+150724X0200Y         S0      
317GND              VIA   -    MD0100PA00X+014232Y+149662X0200Y         S0      
317GND              VIA   -    MD0100PA00X+014232Y+149189X0200Y         S0      
317GND              VIA   -    MD0100PA00X+014232Y+148716X0200Y         S0      
317GND              VIA   -    MD0100PA00X+014232Y+148127X0200Y         S0      
317GND              VIA   -    MD0100PA00X+014232Y+147654X0200Y         S0      
317GND              VIA   -    MD0100PA00X+014232Y+147180X0200Y         S0      
327GND              PEX0  -BE3        A01X+015256Y+109016X0180Y         S1      
327GND              PEX0  -BE4        A01X+015630Y+109016X0180Y         S1      
327GND              PEX0  -BE5        A01X+016004Y+109016X0180Y         S1      
327GND              PEX0  -BF3        A01X+015256Y+108642X0180Y         S1      
327GND              PEX0  -BF5        A01X+016004Y+108642X0180Y         S1      
327GND              PEX0  -BG3        A01X+015256Y+108268X0180Y         S1      
327GND              PEX0  -BG5        A01X+016004Y+108268X0180Y         S1      
327GND              PEX0  -BH4        A01X+015630Y+107894X0180Y         S1      
327GND              PEX0  -BJ2        A01X+014882Y+107520X0180Y         S1      
317GND              VIA   -    MD0100PA00X+015551Y+106515X0200Y         S0      
327GND              PEX0  -BJ6        A01X+016378Y+107520X0180Y         S1      
327GND              PEX0  -BJ4        A01X+015630Y+107520X0180Y         S1      
317GND              VIA   -    MD0100PA00X+016403Y+104147X0200Y         S0      
317GND              VIA   -    MD0100PA00X+015984Y+099786X0200Y         S0      
327GND              R1191 -1          A01X+015984Y+099511X0198Y0197R270 S1      
317GND              VIA   -    MD0100PA00X+015184Y+099786X0200Y         S0      
327GND              R1189 -1          A01X+015184Y+099511X0198Y0197R270 S1      
317GND              VIA   -    MD0100PA00X+014232Y+161434X0200Y         S0      
317GND              VIA   -    MD0100PA00X+014232Y+159898X0200Y         S0      
317GND              VIA   -    MD0100PA00X+014232Y+160488X0200Y         S0      
317GND              VIA   -    MD0100PA00X+014232Y+160961X0200Y         S0      
317GND              VIA   -    MD0100PA00X+014232Y+158363X0200Y         S0      
317GND              VIA   -    MD0100PA00X+014232Y+159425X0200Y         S0      
317GND              VIA   -    MD0100PA00X+014232Y+158952X0200Y         S0      
327GND              PEX0  -AJ3        A01X+015256Y+115000X0180Y         S1      
327GND              PEX0  -AJ4        A01X+015630Y+115000X0180Y         S1      
327GND              PEX0  -AJ5        A01X+016004Y+115000X0180Y         S1      
327GND              PEX0  -AK3        A01X+015256Y+114626X0180Y         S1      
327GND              PEX0  -AG6        A01X+016378Y+115748X0180Y         S1      
327GND              PEX0  -AH6        A01X+016378Y+115374X0180Y         S1      
327GND              PEX0  -AJ6        A01X+016378Y+115000X0180Y         S1      
327GND              PEX0  -AK6        A01X+016378Y+114626X0180Y         S1      
327GND              PEX0  -AM7        A01X+016752Y+113878X0180Y         S1      
327GND              PEX0  -AP6        A01X+016378Y+113130X0180Y         S1      
327GND              PEX0  -AP7        A01X+016752Y+113130X0180Y         S1      
327GND              PEX0  -AT6        A01X+016378Y+112382X0180Y         S1      
327GND              PEX0  -AM3        A01X+015256Y+113878X0180Y         S1      
327GND              PEX0  -AP3        A01X+015256Y+113130X0180Y         S1      
327GND              PEX0  -AP4        A01X+015630Y+113130X0180Y         S1      
327GND              PEX0  -AP5        A01X+016004Y+113130X0180Y         S1      
327GND              PEX0  -AR5        A01X+016004Y+112756X0180Y         S1      
327GND              PEX0  -AN5        A01X+016004Y+113504X0180Y         S1      
327GND              PEX0  -AV6        A01X+016378Y+111634X0180Y         S1      
327GND              PEX0  -AV7        A01X+016752Y+111634X0180Y         S1      
327GND              PEX0  -AT3        A01X+015256Y+112382X0180Y         S1      
327GND              PEX0  -AT4        A01X+015630Y+112382X0180Y         S1      
327GND              PEX0  -AT5        A01X+016004Y+112382X0180Y         S1      
327GND              PEX0  -AU5        A01X+016004Y+112008X0180Y         S1      
327GND              PEX0  -AV3        A01X+015256Y+111634X0180Y         S1      
327GND              PEX0  -AV4        A01X+015630Y+111634X0180Y         S1      
327GND              PEX0  -AV5        A01X+016004Y+111634X0180Y         S1      
327GND              PEX0  -AW5        A01X+016004Y+111260X0180Y         S1      
327GND              PEX0  -BC4        A01X+015630Y+109764X0180Y         S1      
327GND              PEX0  -AY3        A01X+015256Y+110886X0180Y         S1      
327GND              PEX0  -AY4        A01X+015630Y+110886X0180Y         S1      
327GND              PEX0  -AY6        A01X+016378Y+110886X0180Y         S1      
327GND              PEX0  -AY7        A01X+016752Y+110886X0180Y         S1      
327GND              PEX0  -BA7        A01X+016752Y+110512X0180Y         S1      
327GND              PEX0  -BB7        A01X+016752Y+110138X0180Y         S1      
327GND              PEX0  -BC6        A01X+016378Y+109764X0180Y         S1      
327GND              PEX0  -AY5        A01X+016004Y+110886X0180Y         S1      
327GND              PEX0  -BA3        A01X+015256Y+110512X0180Y         S1      
327GND              PEX0  -BA5        A01X+016004Y+110512X0180Y         S1      
327GND              PEX0  -BB3        A01X+015256Y+110138X0180Y         S1      
327GND              PEX0  -BB5        A01X+016004Y+110138X0180Y         S1      
327GND              PEX0  -BE6        A01X+016378Y+109016X0180Y         S1      
327GND              PEX0  -BE7        A01X+016752Y+109016X0180Y         S1      
327GND              PEX0  -BG7        A01X+016752Y+108268X0180Y         S1      
327GND              PEX0  -BH6        A01X+016378Y+107894X0180Y         S1      
327GND              PEX0  -AD6        A01X+016378Y+116870X0180Y         S1      
327GND              PEX0  -AE6        A01X+016378Y+116496X0180Y         S1      
327GND              PEX0  -AF6        A01X+016378Y+116122X0180Y         S1      
327GND              PEX0  -AD2        A01X+014882Y+116870X0180Y         S1      
327GND              PEX0  -AD3        A01X+015256Y+116870X0180Y         S1      
327GND              PEX0  -AE3        A01X+015256Y+116496X0180Y         S1      
327GND              PEX0  -AE5        A01X+016004Y+116496X0180Y         S1      
327GND              PEX0  -AE4 M      A01X+015630Y+116496X0180Y         S1      
327GND              PEX0  -AF3        A01X+015256Y+116122X0180Y         S1      
327GND              PEX0  -AG3        A01X+015256Y+115748X0180Y         S1      
327GND              PEX0  -AG4        A01X+015630Y+115748X0180Y         S1      
327GND              PEX0  -AG5        A01X+016004Y+115748X0180Y         S1      
327GND              PEX0  -AH3        A01X+015256Y+115374X0180Y         S1      
317GND              VIA   -    MD0100PA00X+015964Y+149189X0200Y         S0      
317GND              VIA   -    MD0100PA00X+015964Y+148127X0200Y         S0      
317GND              VIA   -    MD0100PA00X+015964Y+147654X0200Y         S0      
317GND              VIA   -    MD0100PA00X+015964Y+147180X0200Y         S0      
317GND              VIA   -    MD0100PA00X+015098Y+148087X0200Y         S0      
317GND              VIA   -    MD0100PA00X+015098Y+147024X0200Y         S0      
317GND              VIA   -    MD0100PA00X+015098Y+147614X0200Y         S0      
317GND              VIA   -    MD0100PA00X+015964Y+145645X0200Y         S0      
317GND              VIA   -    MD0100PA00X+015964Y+146591X0200Y         S0      
317GND              VIA   -    MD0100PA00X+015098Y+146078X0200Y         S0      
317GND              VIA   -    MD0100PA00X+015098Y+146551X0200Y         S0      
317GND              VIA   -    MD0100PA00X+015964Y+146118X0200Y         S0      
317GND              VIA   -    MD0100PA00X+015964Y+157417X0200Y         S0      
317GND              VIA   -    MD0100PA00X+015964Y+156828X0200Y         S0      
317GND              VIA   -    MD0100PA00X+015098Y+157261X0200Y         S0      
317GND              VIA   -    MD0100PA00X+015098Y+157850X0200Y         S0      
317GND              VIA   -    MD0100PA00X+015098Y+156788X0200Y         S0      
317GND              VIA   -    MD0100PA00X+015964Y+157890X0200Y         S0      
317GND              VIA   -    MD0100PA00X+015098Y+156314X0200Y         S0      
317GND              VIA   -    MD0100PA00X+015964Y+156354X0200Y         S0      
317GND              VIA   -    MD0100PA00X+015964Y+155881X0200Y         S0      
317GND              VIA   -    MD0100PA00X+015098Y+151631X0200Y         S0      
317GND              VIA   -    MD0100PA00X+015098Y+150684X0200Y         S0      
317GND              VIA   -    MD0100PA00X+015964Y+151198X0200Y         S0      
317GND              VIA   -    MD0100PA00X+015964Y+150251X0200Y         S0      
317GND              VIA   -    MD0100PA00X+015964Y+150724X0200Y         S0      
317GND              VIA   -    MD0100PA00X+015098Y+151158X0200Y         S0      
317GND              VIA   -    MD0100PA00X+015098Y+150095X0200Y         S0      
317GND              VIA   -    MD0100PA00X+015964Y+148716X0200Y         S0      
317GND              VIA   -    MD0100PA00X+015098Y+149622X0200Y         S0      
317GND              VIA   -    MD0100PA00X+015098Y+148560X0200Y         S0      
317GND              VIA   -    MD0100PA00X+015098Y+149149X0200Y         S0      
317GND              VIA   -    MD0100PA00X+015964Y+149662X0200Y         S0      
317GND              VIA   -    MD0100PA00X+015200Y+164498X0200Y         S0      
317GND              VIA   -    MD0100PA00X+015964Y+161434X0200Y         S0      
317GND              VIA   -    MD0100PA00X+015098Y+161867X0200Y         S0      
317GND              VIA   -    MD0100PA00X+015098Y+161394X0200Y         S0      
317GND              VIA   -    MD0100PA00X+015964Y+159898X0200Y         S0      
317GND              VIA   -    MD0100PA00X+015964Y+160488X0200Y         S0      
317GND              VIA   -    MD0100PA00X+015964Y+160961X0200Y         S0      
317GND              VIA   -    MD0100PA00X+015098Y+160332X0200Y         S0      
317GND              VIA   -    MD0100PA00X+015098Y+159858X0200Y         S0      
317GND              VIA   -    MD0100PA00X+015098Y+160921X0200Y         S0      
317GND              VIA   -    MD0100PA00X+015964Y+159425X0200Y         S0      
317GND              VIA   -    MD0100PA00X+015964Y+158952X0200Y         S0      
317GND              VIA   -    MD0100PA00X+015964Y+158363X0200Y         S0      
317GND              VIA   -    MD0100PA00X+015098Y+158796X0200Y         S0      
317GND              VIA   -    MD0100PA00X+015098Y+159385X0200Y         S0      
317GND              VIA   -    MD0100PA00X+015098Y+158323X0200Y         S0      
327GND              PEX0  -AP11       A01X+018248Y+113130X0180Y         S1      
327GND              PEX0  -AR11       A01X+018248Y+112756X0180Y         S1      
327GND              PEX0  -AR8        A01X+017126Y+112756X0180Y         S1      
327GND              PEX0  -AR9        A01X+017500Y+112756X0180Y         S1      
327GND              PEX0  -AM10       A01X+017874Y+113878X0180Y         S1      
327GND              PEX0  -AN10M      A01X+017874Y+113504X0180Y         S1      
327GND              PEX0  -AN11       A01X+018248Y+113504X0180Y         S1      
327GND              PEX0  -AP10       A01X+017874Y+113130X0180Y         S1      
327GND              PEX0  -AR10       A01X+017874Y+112756X0180Y         S1      
327GND              PEX0  -AN8        A01X+017126Y+113504X0180Y         S1      
327GND              PEX0  -AN9        A01X+017500Y+113504X0180Y         S1      
327GND              PEX0  -AT11       A01X+018248Y+112382X0180Y         S1      
327GND              PEX0  -AU11       A01X+018248Y+112008X0180Y         S1      
327GND              PEX0  -AV11       A01X+018248Y+111634X0180Y         S1      
327GND              PEX0  -AW8        A01X+017126Y+111260X0180Y         S1      
327GND              PEX0  -AW9        A01X+017500Y+111260X0180Y         S1      
327GND              PEX0  -AT10       A01X+017874Y+112382X0180Y         S1      
327GND              PEX0  -AU10       A01X+017874Y+112008X0180Y         S1      
327GND              PEX0  -AU9        A01X+017500Y+112008X0180Y         S1      
327GND              PEX0  -AV10       A01X+017874Y+111634X0180Y         S1      
327GND              PEX0  -AT7        A01X+016752Y+112382X0180Y         S1      
327GND              PEX0  -AU8        A01X+017126Y+112008X0180Y         S1      
327GND              PEX0  -AY8        A01X+017126Y+110886X0180Y         S1      
327GND              PEX0  -AF11       A01X+018248Y+116122X0180Y         S1      
327GND              PEX0  -AG10       A01X+017874Y+115748X0180Y         S1      
327GND              PEX0  -AF9        A01X+017500Y+116122X0180Y         S1      
327GND              PEX0  -AK11       A01X+018248Y+114626X0180Y         S1      
327GND              PEX0  -AH11       A01X+018248Y+115374X0180Y         S1      
327GND              PEX0  -AG11       A01X+018248Y+115748X0180Y         S1      
327GND              PEX0  -AH9        A01X+017500Y+115374X0180Y         S1      
327GND              PEX0  -AG9        A01X+017500Y+115748X0180Y         S1      
327GND              PEX0  -AJ9        A01X+017500Y+115000X0180Y         S1      
327GND              PEX0  -AK8        A01X+017126Y+114626X0180Y         S1      
327GND              PEX0  -AK9        A01X+017500Y+114626X0180Y         S1      
327GND              PEX0  -AJ11       A01X+018248Y+115000X0180Y         S1      
327GND              PEX0  -AM11       A01X+018248Y+113878X0180Y         S1      
317GND              VIA   -    MD0100PA00X+017696Y+155881X0200Y         S0      
317GND              VIA   -    MD0100PA00X+017696Y+156354X0200Y         S0      
317GND              VIA   -    MD0100PA00X+016830Y+156314X0200Y         S0      
317GND              VIA   -    MD0100PA00X+016830Y+151631X0200Y         S0      
317GND              VIA   -    MD0100PA00X+017696Y+151198X0200Y         S0      
317GND              VIA   -    MD0100PA00X+016830Y+151158X0200Y         S0      
317GND              VIA   -    MD0100PA00X+016830Y+150095X0200Y         S0      
317GND              VIA   -    MD0100PA00X+016830Y+150684X0200Y         S0      
317GND              VIA   -    MD0100PA00X+017696Y+150252X0200Y         S0      
317GND              VIA   -    MD0100PA00X+017696Y+150725X0200Y         S0      
317GND              VIA   -    MD0100PA00X+017696Y+149662X0200Y         S0      
317GND              VIA   -    MD0100PA00X+017696Y+148716X0200Y         S0      
317GND              VIA   -    MD0100PA00X+017696Y+149189X0200Y         S0      
317GND              VIA   -    MD0100PA00X+016830Y+149622X0200Y         S0      
317GND              VIA   -    MD0100PA00X+016830Y+148560X0200Y         S0      
317GND              VIA   -    MD0100PA00X+016830Y+149149X0200Y         S0      
317GND              VIA   -    MD0100PA00X+017696Y+148127X0200Y         S0      
317GND              VIA   -    MD0100PA00X+017696Y+147181X0200Y         S0      
317GND              VIA   -    MD0100PA00X+017696Y+147654X0200Y         S0      
317GND              VIA   -    MD0100PA00X+016830Y+148087X0200Y         S0      
317GND              VIA   -    MD0100PA00X+016830Y+147024X0200Y         S0      
317GND              VIA   -    MD0100PA00X+016830Y+147614X0200Y         S0      
317GND              VIA   -    MD0100PA00X+017696Y+146118X0200Y         S0      
317GND              VIA   -    MD0100PA00X+017696Y+145645X0200Y         S0      
317GND              VIA   -    MD0100PA00X+017696Y+146591X0200Y         S0      
317GND              VIA   -    MD0100PA00X+016830Y+146078X0200Y         S0      
317GND              VIA   -    MD0100PA00X+016830Y+146551X0200Y         S0      
317GND              VIA   -    MD0100PA00X+017200Y+164498X0200Y         S0      
317GND              VIA   -    MD0100PA00X+017696Y+161434X0200Y         S0      
317GND              VIA   -    MD0100PA00X+016830Y+161867X0200Y         S0      
317GND              VIA   -    MD0100PA00X+016830Y+161394X0200Y         S0      
317GND              VIA   -    MD0100PA00X+017696Y+160488X0200Y         S0      
317GND              VIA   -    MD0100PA00X+017696Y+159898X0200Y         S0      
317GND              VIA   -    MD0100PA00X+017696Y+160961X0200Y         S0      
317GND              VIA   -    MD0100PA00X+016830Y+160332X0200Y         S0      
317GND              VIA   -    MD0100PA00X+016830Y+159858X0200Y         S0      
317GND              VIA   -    MD0100PA00X+016830Y+160921X0200Y         S0      
317GND              VIA   -    MD0100PA00X+017696Y+158952X0200Y         S0      
317GND              VIA   -    MD0100PA00X+017696Y+159425X0200Y         S0      
317GND              VIA   -    MD0100PA00X+016830Y+158796X0200Y         S0      
317GND              VIA   -    MD0100PA00X+016830Y+159385X0200Y         S0      
317GND              VIA   -    MD0100PA00X+017696Y+158363X0200Y         S0      
317GND              VIA   -    MD0100PA00X+016830Y+158323X0200Y         S0      
317GND              VIA   -    MD0100PA00X+016830Y+156788X0200Y         S0      
317GND              VIA   -    MD0100PA00X+016830Y+157261X0200Y         S0      
317GND              VIA   -    MD0100PA00X+016830Y+157850X0200Y         S0      
317GND              VIA   -    MD0100PA00X+017696Y+156828X0200Y         S0      
327GND              PEX0  -AU15       A01X+019744Y+112008X0180Y         S1      
327GND              PEX0  -AT12       A01X+018622Y+112382X0180Y         S1      
327GND              PEX0  -AT13       A01X+018996Y+112382X0180Y         S1      
327GND              PEX0  -AT14       A01X+019370Y+112382X0180Y         S1      
327GND              PEX0  -AU12       A01X+018622Y+112008X0180Y         S1      
327GND              PEX0  -AU13       A01X+018996Y+112008X0180Y         S1      
327GND              PEX0  -AU14       A01X+019370Y+112008X0180Y         S1      
327GND              PEX0  -AF13       A01X+018996Y+116122X0180Y         S1      
327GND              PEX0  -AH13M      A01X+018996Y+115374X0180Y         S1      
327GND              PEX0  -AF15       A01X+019744Y+116122X0180Y         S1      
327GND              PEX0  -AG14M      A01X+019370Y+115748X0180Y         S1      
327GND              PEX0  -AK13       A01X+018996Y+114626X0180Y         S1      
327GND              PEX0  -AM13       A01X+018996Y+113878X0180Y         S1      
327GND              PEX0  -AN12       A01X+018622Y+113504X0180Y         S1      
327GND              PEX0  -AN13       A01X+018996Y+113504X0180Y         S1      
327GND              PEX0  -AP12       A01X+018622Y+113130X0180Y         S1      
327GND              PEX0  -AP13       A01X+018996Y+113130X0180Y         S1      
327GND              PEX0  -AR12       A01X+018622Y+112756X0180Y         S1      
327GND              PEX0  -AR13       A01X+018996Y+112756X0180Y         S1      
327GND              PEX0  -AR14       A01X+019370Y+112756X0180Y         S1      
327GND              PEX0  -AT15       A01X+019744Y+112382X0180Y         S1      
317GND              VIA   -    MD0100PA00X+018562Y+147024X0200Y         S0      
317GND              VIA   -    MD0100PA00X+018562Y+147614X0200Y         S0      
317GND              VIA   -    MD0100PA00X+018562Y+148087X0200Y         S0      
317GND              VIA   -    MD0100PA00X+018562Y+146078X0200Y         S0      
317GND              VIA   -    MD0100PA00X+018562Y+146551X0200Y         S0      
317GND              VIA   -    MD0100PA00X+019200Y+164498X0200Y         S0      
317GND              VIA   -    MD0100PA00X+018562Y+148560X0200Y         S0      
327GND              PEX0  -AR16       A01X+020118Y+112756X0180Y         S1      
327GND              PEX0  -AT16       A01X+020118Y+112382X0180Y         S1      
327GND              PEX0  -AU16       A01X+020118Y+112008X0180Y         S1      
327GND              PEX0  -AE20       A01X+021614Y+116496X0180Y         S1      
327GND              PEX0  -AD19M      A01X+021240Y+116870X0180Y         S1      
327GND              PEX0  -AC18M      A01X+020866Y+117244X0180Y         S1      
327GND              C1100 -2          A18X+020824Y+116229X0280Y0320R090 S2      
327GND              PEX0  -AF19       A01X+021240Y+116122X0180Y         S1      
327GND              PEX0  -AG18M      A01X+020866Y+115748X0180Y         S1      
327GND              PEX0  -AJ14M      A01X+019370Y+115000X0180Y         S1      
327GND              PEX0  -AH15M      A01X+019744Y+115374X0180Y         S1      
327GND              PEX0  -AF17       A01X+020492Y+116122X0180Y         S1      
327GND              PEX0  -AG16M      A01X+020118Y+115748X0180Y         S1      
317GND              VIA   -    MD0100PA00X+021147Y+145768X0180Y         S0      
317GND              VIA   -    MD0100PA00X+021147Y+146263X0180Y         S0      
317GND              VIA   -    MD0100PA00X+021147Y+145163X0180Y         S0      
317GND              VIA   -    MD0100PA00X+021147Y+144668X0180Y         S0      
327GND              PEX0  -M21        A01X+021988Y+121358X0180Y         S1      
327GND              PEX0  -AC24       A01X+023110Y+117244X0180Y         S1      
327GND              PEX0  -AF21       A01X+021988Y+116122X0180Y         S1      
327GND              PEX0  -AG20M      A01X+021614Y+115748X0180Y         S1      
327GND              PEX0  -AE22       A01X+022362Y+116496X0180Y         S1      
327GND              PEX0  -AD21M      A01X+021988Y+116870X0180Y         S1      
327GND              PEX0  -AC20M      A01X+021614Y+117244X0180Y         S1      
327GND              PEX0  -AE24       A01X+023110Y+116496X0180Y         S1      
327GND              PEX0  -AC22M      A01X+022362Y+117244X0180Y         S1      
327GND              PEX0  -AD23M      A01X+022736Y+116870X0180Y         S1      
327GND              PEX0  -AG24       A01X+023110Y+115748X0180Y         S1      
327GND              PEX0  -AF23       A01X+022736Y+116122X0180Y         S1      
327GND              PEX0  -AG22M      A01X+022362Y+115748X0180Y         S1      
327GND              PEX0  -AK15M      A01X+019744Y+114626X0180Y         S1      
327GND              PEX0  -AJ18M      A01X+020866Y+115000X0180Y         S1      
327GND              PEX0  -AJ17M      A01X+020492Y+115000X0180Y         S1      
327GND              PEX0  -AJ16M      A01X+020118Y+115000X0180Y         S1      
327GND              PEX0  -AJ21M      A01X+021988Y+115000X0180Y         S1      
327GND              PEX0  -AJ23M      A01X+022736Y+115000X0180Y         S1      
327GND              PEX0  -AJ22M      A01X+022362Y+115000X0180Y         S1      
327GND              PEX0  -AJ20M      A01X+021614Y+115000X0180Y         S1      
327GND              PEX0  -AJ24       A01X+023110Y+115000X0180Y         S1      
327GND              PEX0  -AJ19M      A01X+021240Y+115000X0180Y         S1      
327GND              PEX0  -AL18M      A01X+020866Y+114252X0180Y         S1      
327GND              PEX0  -AL17M      A01X+020492Y+114252X0180Y         S1      
327GND              PEX0  -AL16M      A01X+020118Y+114252X0180Y         S1      
327GND              PEX0  -AL19M      A01X+021240Y+114252X0180Y         S1      
327GND              PEX0  -AL23M      A01X+022736Y+114252X0180Y         S1      
327GND              PEX0  -AL22M      A01X+022362Y+114252X0180Y         S1      
327GND              PEX0  -AL20M      A01X+021614Y+114252X0180Y         S1      
327GND              PEX0  -AL21M      A01X+021988Y+114252X0180Y         S1      
327GND              PEX0  -AL24       A01X+023110Y+114252X0180Y         S1      
327GND              PEX0  -AM15       A01X+019744Y+113878X0180Y         S1      
327GND              PEX0  -AN15M      A01X+019744Y+113504X0180Y         S1      
327GND              PEX0  -AN24       A01X+023110Y+113504X0180Y         S1      
327GND              PEX0  -AN23M      A01X+022736Y+113504X0180Y         S1      
327GND              PEX0  -AN22M      A01X+022362Y+113504X0180Y         S1      
327GND              PEX0  -AN20M      A01X+021614Y+113504X0180Y         S1      
327GND              PEX0  -AN21M      A01X+021988Y+113504X0180Y         S1      
327GND              PEX0  -AN18M      A01X+020866Y+113504X0180Y         S1      
327GND              PEX0  -AN17M      A01X+020492Y+113504X0180Y         S1      
327GND              PEX0  -AN16M      A01X+020118Y+113504X0180Y         S1      
327GND              PEX0  -AN19M      A01X+021240Y+113504X0180Y         S1      
327GND              PEX0  -AP15M      A01X+019744Y+113130X0180Y         S1      
327GND              PEX0  -AR15M      A01X+019744Y+112756X0180Y         S1      
317GND              VIA   -    MD0100PA00X+022696Y+151044X0200Y         S0      
327GND              R1802 -2          A01X+022947Y+151044X0198Y0197R180 S1      
317GND              VIA   -    MD0100PA00X+022291Y+150203X0200Y         S0      
317GND              VIA   -    MD0100PA00X+022324Y+150677X0200Y         S0      
317GND              VIA   -    MD0100PA00X+022475Y+145163X0180Y    R270 S0      
317GND              VIA   -    MD0100PA00X+022974Y+146263X0180Y    R270 S0      
317GND              VIA   -    MD0100PA00X+022974Y+145163X0180Y    R270 S0      
317GND              VIA   -    MD0100PA00X+022475Y+145768X0180Y    R270 S0      
317GND              VIA   -    MD0100PA00X+022974Y+145768X0180Y    R270 S0      
317GND              VIA   -    MD0100PA00X+022475Y+146263X0180Y    R270 S0      
317GND              VIA   -    MD0100PA00X+021646Y+145768X0180Y         S0      
317GND              VIA   -    MD0100PA00X+021646Y+146263X0180Y         S0      
317GND              VIA   -    MD0100PA00X+021646Y+145163X0180Y         S0      
317GND              VIA   -    MD0100PA00X+022475Y+144668X0180Y    R270 S0      
317GND              VIA   -    MD0100PA00X+022974Y+144668X0180Y    R270 S0      
317GND              VIA   -    MD0100PA00X+021646Y+144668X0180Y         S0      
327GND              PEX0  -BJ24       A01X+023110Y+107520X0180Y         S1      
327GND              PEX0  -BH24       A01X+023110Y+107894X0180Y         S1      
327GND              PEX0  -BG25       A01X+023484Y+108268X0180Y         S1      
327GND              PEX0  -BJ26       A01X+023858Y+107520X0180Y         S1      
327GND              PEX0  -BH26       A01X+023858Y+107894X0180Y         S1      
327GND              PEX0  -AD25       A01X+023484Y+116870X0180Y         S1      
327GND              PEX0  -AC26M      A01X+023858Y+117244X0180Y         S1      
327GND              C1102 -2          A18X+024190Y+116229X0280Y0320R090 S2      
327GND              PEX0  -AF25       A01X+023484Y+116122X0180Y         S1      
327GND              PEX0  -AG26M      A01X+023858Y+115748X0180Y         S1      
317GND              VIA   -    MD0100PA00X+025180Y+082413X0200Y    R090 S0      
327GND              PEX0  -AF27       A01X+024232Y+116122X0180Y         S1      
327GND              PEX0  -AG28M      A01X+024606Y+115748X0180Y         S1      
327GND              PEX0  -AC28M      A01X+024606Y+117244X0180Y         S1      
327GND              PEX0  -AE26       A01X+023858Y+116496X0180Y         S1      
327GND              PEX0  -AD27M      A01X+024232Y+116870X0180Y         S1      
327GND              PEX0  -AG32M      A01X+026102Y+115748X0180Y         S1      
327GND              PEX0  -AF31       A01X+025728Y+116122X0180Y         S1      
327GND              PEX0  -AF29       A01X+024980Y+116122X0180Y         S1      
327GND              PEX0  -AG30M      A01X+025354Y+115748X0180Y         S1      
327GND              PEX0  -AC32M      A01X+026102Y+117244X0180Y         S1      
327GND              PEX0  -AE30       A01X+025354Y+116496X0180Y         S1      
327GND              PEX0  -AD31M      A01X+025728Y+116870X0180Y         S1      
327GND              PEX0  -AE28       A01X+024606Y+116496X0180Y         S1      
327GND              PEX0  -AC30M      A01X+025354Y+117244X0180Y         S1      
327GND              PEX0  -AD29M      A01X+024980Y+116870X0180Y         S1      
327GND              PEX0  -AE32       A01X+026102Y+116496X0180Y         S1      
327GND              PEX0  -AN27M      A01X+024232Y+113504X0180Y         S1      
327GND              PEX0  -AN25       A01X+023484Y+113504X0180Y         S1      
327GND              PEX0  -AN26M      A01X+023858Y+113504X0180Y         S1      
327GND              PEX0  -AN28M      A01X+024606Y+113504X0180Y         S1      
327GND              PEX0  -AN32M      A01X+026102Y+113504X0180Y         S1      
327GND              PEX0  -AN29M      A01X+024980Y+113504X0180Y         S1      
327GND              PEX0  -AN30M      A01X+025354Y+113504X0180Y         S1      
327GND              PEX0  -AN31M      A01X+025728Y+113504X0180Y         S1      
327GND              PEX0  -AN33M      A01X+026476Y+113504X0180Y         S1      
327GND              PEX0  -AN34M      A01X+026850Y+113504X0180Y         S1      
327GND              PEX0  -AM34       A01X+026850Y+113878X0180Y         S1      
327GND              PEX0  -AN35M      A01X+027224Y+113504X0180Y         S1      
327GND              PEX0  -AA25       A01X+023484Y+117992X0180Y         S1      
327GND              PEX0  -AA27M      A01X+024232Y+117992X0180Y         S1      
327GND              PEX0  -AA26M      A01X+023858Y+117992X0180Y         S1      
327GND              PEX0  -AA32M      A01X+026102Y+117992X0180Y         S1      
327GND              PEX0  -AA31M      A01X+025728Y+117992X0180Y         S1      
327GND              PEX0  -AA29M      A01X+024980Y+117992X0180Y         S1      
327GND              PEX0  -AA30M      A01X+025354Y+117992X0180Y         S1      
327GND              PEX0  -Y34 M      A01X+026850Y+118366X0180Y         S1      
327GND              PEX0  -AA33M      A01X+026476Y+117992X0180Y         S1      
327GND              PEX0  -AA28M      A01X+024606Y+117992X0180Y         S1      
317GND              VIA   -    MD0100PA00X+027200Y+164498X0200Y         S0      
327GND              R1245 -2   M      A18X+029144Y+117648X0198Y0197R090 S2      
327GND              PEX0  -W38        A01X+028346Y+118740X0180Y         S1      
327GND              PEX0  -AF37       A01X+027972Y+116122X0180Y         S1      
327GND              PEX0  -AG37       A01X+027972Y+115748X0180Y         S1      
317GND              VIA   -    MD0100PA00X+028956Y+149622X0200Y         S0      
317GND              VIA   -    MD0100PA00X+028090Y+149662X0200Y         S0      
317GND              VIA   -    MD0100PA00X+028090Y+148716X0200Y         S0      
317GND              VIA   -    MD0100PA00X+028956Y+148560X0200Y         S0      
317GND              VIA   -    MD0100PA00X+028956Y+149149X0200Y         S0      
317GND              VIA   -    MD0100PA00X+028090Y+149189X0200Y         S0      
317GND              VIA   -    MD0100PA00X+028090Y+148127X0200Y         S0      
317GND              VIA   -    MD0100PA00X+028090Y+147180X0200Y         S0      
317GND              VIA   -    MD0100PA00X+028956Y+147024X0200Y         S0      
317GND              VIA   -    MD0100PA00X+028956Y+147614X0200Y         S0      
317GND              VIA   -    MD0100PA00X+028090Y+147654X0200Y         S0      
317GND              VIA   -    MD0100PA00X+028956Y+148087X0200Y         S0      
317GND              VIA   -    MD0100PA00X+028090Y+145645X0200Y         S0      
317GND              VIA   -    MD0100PA00X+028956Y+146078X0200Y         S0      
317GND              VIA   -    MD0100PA00X+028090Y+146118X0200Y         S0      
317GND              VIA   -    MD0100PA00X+028956Y+146551X0200Y         S0      
317GND              VIA   -    MD0100PA00X+028090Y+146591X0200Y         S0      
317GND              VIA   -    MD0100PA00X+028090Y+159425X0200Y         S0      
317GND              VIA   -    MD0100PA00X+028956Y+158323X0200Y         S0      
317GND              VIA   -    MD0100PA00X+028090Y+158363X0200Y         S0      
317GND              VIA   -    MD0100PA00X+028090Y+158952X0200Y         S0      
317GND              VIA   -    MD0100PA00X+028956Y+158796X0200Y         S0      
317GND              VIA   -    MD0100PA00X+028956Y+157261X0200Y         S0      
317GND              VIA   -    MD0100PA00X+028956Y+157850X0200Y         S0      
317GND              VIA   -    MD0100PA00X+028090Y+157890X0200Y         S0      
317GND              VIA   -    MD0100PA00X+028956Y+156788X0200Y         S0      
317GND              VIA   -    MD0100PA00X+028090Y+156828X0200Y         S0      
317GND              VIA   -    MD0100PA00X+028090Y+157417X0200Y         S0      
317GND              VIA   -    MD0100PA00X+028090Y+155881X0200Y         S0      
317GND              VIA   -    MD0100PA00X+028956Y+156314X0200Y         S0      
317GND              VIA   -    MD0100PA00X+028090Y+156354X0200Y         S0      
317GND              VIA   -    MD0100PA00X+028956Y+151631X0200Y         S0      
317GND              VIA   -    MD0100PA00X+028090Y+151198X0200Y         S0      
317GND              VIA   -    MD0100PA00X+028956Y+151158X0200Y         S0      
317GND              VIA   -    MD0100PA00X+028090Y+150251X0200Y         S0      
317GND              VIA   -    MD0100PA00X+028956Y+150095X0200Y         S0      
317GND              VIA   -    MD0100PA00X+028956Y+150684X0200Y         S0      
317GND              VIA   -    MD0100PA00X+028090Y+150724X0200Y         S0      
317GND              VIA   -    MD0100PA00X+029200Y+164498X0200Y         S0      
317GND              VIA   -    MD0100PA00X+028956Y+161867X0200Y         S0      
317GND              VIA   -    MD0100PA00X+028956Y+161394X0200Y         S0      
317GND              VIA   -    MD0100PA00X+028090Y+161434X0200Y         S0      
317GND              VIA   -    MD0100PA00X+028090Y+160488X0200Y         S0      
317GND              VIA   -    MD0100PA00X+028956Y+160332X0200Y         S0      
317GND              VIA   -    MD0100PA00X+028956Y+159858X0200Y         S0      
317GND              VIA   -    MD0100PA00X+028090Y+159898X0200Y         S0      
317GND              VIA   -    MD0100PA00X+028956Y+160921X0200Y         S0      
317GND              VIA   -    MD0100PA00X+028090Y+160961X0200Y         S0      
317GND              VIA   -    MD0100PA00X+028956Y+159385X0200Y         S0      
327GND              PEX0  -AF44       A01X+030590Y+116122X0180Y         S1      
317GND              VIA   -    MD0100PA00X+030688Y+149622X0200Y         S0      
317GND              VIA   -    MD0100PA00X+030688Y+148560X0200Y         S0      
317GND              VIA   -    MD0100PA00X+030688Y+149149X0200Y         S0      
317GND              VIA   -    MD0100PA00X+029822Y+149662X0200Y         S0      
317GND              VIA   -    MD0100PA00X+029822Y+149189X0200Y         S0      
317GND              VIA   -    MD0100PA00X+029822Y+148716X0200Y         S0      
317GND              VIA   -    MD0100PA00X+030688Y+147614X0200Y         S0      
317GND              VIA   -    MD0100PA00X+029822Y+148127X0200Y         S0      
317GND              VIA   -    MD0100PA00X+029822Y+147654X0200Y         S0      
317GND              VIA   -    MD0100PA00X+029822Y+147180X0200Y         S0      
317GND              VIA   -    MD0100PA00X+030688Y+148087X0200Y         S0      
317GND              VIA   -    MD0100PA00X+030688Y+147024X0200Y         S0      
317GND              VIA   -    MD0100PA00X+030688Y+146078X0200Y         S0      
317GND              VIA   -    MD0100PA00X+030688Y+146551X0200Y         S0      
317GND              VIA   -    MD0100PA00X+029822Y+146118X0200Y         S0      
317GND              VIA   -    MD0100PA00X+029822Y+145645X0200Y         S0      
317GND              VIA   -    MD0100PA00X+029822Y+146591X0200Y         S0      
317GND              VIA   -    MD0100PA00X+030688Y+158796X0200Y         S0      
317GND              VIA   -    MD0100PA00X+030688Y+159385X0200Y         S0      
317GND              VIA   -    MD0100PA00X+029822Y+159425X0200Y         S0      
317GND              VIA   -    MD0100PA00X+029822Y+158952X0200Y         S0      
317GND              VIA   -    MD0100PA00X+030688Y+158323X0200Y         S0      
317GND              VIA   -    MD0100PA00X+029822Y+158363X0200Y         S0      
317GND              VIA   -    MD0100PA00X+030688Y+157261X0200Y         S0      
317GND              VIA   -    MD0100PA00X+030688Y+157850X0200Y         S0      
317GND              VIA   -    MD0100PA00X+029822Y+157890X0200Y         S0      
317GND              VIA   -    MD0100PA00X+029822Y+157417X0200Y         S0      
317GND              VIA   -    MD0100PA00X+030688Y+156788X0200Y         S0      
317GND              VIA   -    MD0100PA00X+029822Y+156828X0200Y         S0      
317GND              VIA   -    MD0100PA00X+030688Y+156314X0200Y         S0      
317GND              VIA   -    MD0100PA00X+029822Y+156354X0200Y         S0      
317GND              VIA   -    MD0100PA00X+029822Y+155881X0200Y         S0      
317GND              VIA   -    MD0100PA00X+030688Y+151631X0200Y         S0      
317GND              VIA   -    MD0100PA00X+029822Y+151198X0200Y         S0      
317GND              VIA   -    MD0100PA00X+030688Y+151158X0200Y         S0      
317GND              VIA   -    MD0100PA00X+030688Y+150095X0200Y         S0      
317GND              VIA   -    MD0100PA00X+030688Y+150684X0200Y         S0      
317GND              VIA   -    MD0100PA00X+029822Y+150251X0200Y         S0      
317GND              VIA   -    MD0100PA00X+029822Y+150724X0200Y         S0      
317GND              VIA   -    MD0100PA00X+031200Y+164498X0200Y         S0      
317GND              VIA   -    MD0100PA00X+030688Y+161867X0200Y         S0      
317GND              VIA   -    MD0100PA00X+030688Y+161394X0200Y         S0      
317GND              VIA   -    MD0100PA00X+029822Y+161434X0200Y         S0      
317GND              VIA   -    MD0100PA00X+030688Y+160921X0200Y         S0      
317GND              VIA   -    MD0100PA00X+029822Y+159898X0200Y         S0      
317GND              VIA   -    MD0100PA00X+029822Y+160488X0200Y         S0      
317GND              VIA   -    MD0100PA00X+029822Y+160961X0200Y         S0      
317GND              VIA   -    MD0100PA00X+030688Y+160332X0200Y         S0      
317GND              VIA   -    MD0100PA00X+030688Y+159858X0200Y         S0      
327GND              PEX0  -F49        A01X+032461Y+123602X0180Y         S1      
327GND              PEX0  -G49        A01X+032461Y+123228X0180Y         S1      
327GND              PEX0  -F48        A01X+032087Y+123602X0180Y         S1      
317GND              VIA   -    MD0100PA00X+032420Y+147024X0200Y         S0      
317GND              VIA   -    MD0100PA00X+032420Y+147614X0200Y         S0      
317GND              VIA   -    MD0100PA00X+031554Y+148127X0200Y         S0      
317GND              VIA   -    MD0100PA00X+031554Y+147654X0200Y         S0      
317GND              VIA   -    MD0100PA00X+031554Y+147180X0200Y         S0      
317GND              VIA   -    MD0100PA00X+032420Y+148087X0200Y         S0      
317GND              VIA   -    MD0100PA00X+032420Y+146078X0200Y         S0      
317GND              VIA   -    MD0100PA00X+032420Y+146551X0200Y         S0      
317GND              VIA   -    MD0100PA00X+031554Y+146118X0200Y         S0      
317GND              VIA   -    MD0100PA00X+031554Y+145645X0200Y         S0      
317GND              VIA   -    MD0100PA00X+031554Y+146591X0200Y         S0      
317GND              VIA   -    MD0100PA00X+031554Y+156828X0200Y         S0      
317GND              VIA   -    MD0100PA00X+032420Y+157261X0200Y         S0      
317GND              VIA   -    MD0100PA00X+032420Y+157850X0200Y         S0      
317GND              VIA   -    MD0100PA00X+032420Y+156788X0200Y         S0      
317GND              VIA   -    MD0100PA00X+031554Y+157890X0200Y         S0      
317GND              VIA   -    MD0100PA00X+031554Y+157417X0200Y         S0      
317GND              VIA   -    MD0100PA00X+032420Y+156314X0200Y         S0      
317GND              VIA   -    MD0100PA00X+031554Y+156354X0200Y         S0      
317GND              VIA   -    MD0100PA00X+031554Y+155881X0200Y         S0      
317GND              VIA   -    MD0100PA00X+032420Y+151631X0200Y         S0      
317GND              VIA   -    MD0100PA00X+032420Y+150684X0200Y         S0      
317GND              VIA   -    MD0100PA00X+031554Y+151198X0200Y         S0      
317GND              VIA   -    MD0100PA00X+031554Y+150251X0200Y         S0      
317GND              VIA   -    MD0100PA00X+031554Y+150724X0200Y         S0      
317GND              VIA   -    MD0100PA00X+032420Y+151158X0200Y         S0      
317GND              VIA   -    MD0100PA00X+032420Y+150095X0200Y         S0      
317GND              VIA   -    MD0100PA00X+032420Y+149622X0200Y         S0      
317GND              VIA   -    MD0100PA00X+032420Y+148560X0200Y         S0      
317GND              VIA   -    MD0100PA00X+032420Y+149149X0200Y         S0      
317GND              VIA   -    MD0100PA00X+031554Y+149662X0200Y         S0      
317GND              VIA   -    MD0100PA00X+031554Y+149189X0200Y         S0      
317GND              VIA   -    MD0100PA00X+031554Y+148716X0200Y         S0      
317GND              VIA   -    MD0100PA00X+033756Y+101829X0200Y         S0      
317GND              VIA   -    MD0100PA00X+032420Y+161867X0200Y         S0      
317GND              VIA   -    MD0100PA00X+032420Y+161394X0200Y         S0      
317GND              VIA   -    MD0100PA00X+031554Y+161434X0200Y         S0      
317GND              VIA   -    MD0100PA00X+032420Y+160332X0200Y         S0      
317GND              VIA   -    MD0100PA00X+032420Y+159858X0200Y         S0      
317GND              VIA   -    MD0100PA00X+032420Y+160921X0200Y         S0      
317GND              VIA   -    MD0100PA00X+031554Y+159898X0200Y         S0      
317GND              VIA   -    MD0100PA00X+031554Y+160488X0200Y         S0      
317GND              VIA   -    MD0100PA00X+031554Y+160961X0200Y         S0      
317GND              VIA   -    MD0100PA00X+032420Y+158796X0200Y         S0      
317GND              VIA   -    MD0100PA00X+032420Y+159385X0200Y         S0      
317GND              VIA   -    MD0100PA00X+032420Y+158323X0200Y         S0      
317GND              VIA   -    MD0100PA00X+031554Y+159425X0200Y         S0      
317GND              VIA   -    MD0100PA00X+031554Y+158952X0200Y         S0      
317GND              VIA   -    MD0100PA00X+031554Y+158363X0200Y         S0      
317GND              VIA   -    MD0100PA00X+033690Y+119641X0200Y         S0      
317GND              VIA   -    MD0100PA00X+033286Y+149662X0200Y         S0      
317GND              VIA   -    MD0100PA00X+033286Y+149189X0200Y         S0      
317GND              VIA   -    MD0100PA00X+033286Y+148716X0200Y         S0      
317GND              VIA   -    MD0100PA00X+034153Y+149622X0200Y         S0      
317GND              VIA   -    MD0100PA00X+034153Y+148560X0200Y         S0      
317GND              VIA   -    MD0100PA00X+034153Y+149149X0200Y         S0      
317GND              VIA   -    MD0100PA00X+033286Y+148127X0200Y         S0      
317GND              VIA   -    MD0100PA00X+033286Y+147654X0200Y         S0      
317GND              VIA   -    MD0100PA00X+033286Y+147180X0200Y         S0      
317GND              VIA   -    MD0100PA00X+034153Y+148087X0200Y         S0      
317GND              VIA   -    MD0100PA00X+034153Y+147024X0200Y         S0      
317GND              VIA   -    MD0100PA00X+034153Y+147614X0200Y         S0      
317GND              VIA   -    MD0100PA00X+034153Y+146551X0200Y         S0      
317GND              VIA   -    MD0100PA00X+033286Y+146118X0200Y         S0      
317GND              VIA   -    MD0100PA00X+033286Y+145645X0200Y         S0      
317GND              VIA   -    MD0100PA00X+033286Y+146591X0200Y         S0      
317GND              VIA   -    MD0100PA00X+034153Y+146078X0200Y         S0      
317GND              VIA   -    MD0100PA00X+034153Y+158796X0200Y         S0      
317GND              VIA   -    MD0100PA00X+034153Y+159385X0200Y         S0      
317GND              VIA   -    MD0100PA00X+034153Y+158323X0200Y         S0      
317GND              VIA   -    MD0100PA00X+033286Y+159425X0200Y         S0      
317GND              VIA   -    MD0100PA00X+033286Y+158952X0200Y         S0      
317GND              VIA   -    MD0100PA00X+033286Y+158363X0200Y         S0      
317GND              VIA   -    MD0100PA00X+033286Y+157417X0200Y         S0      
317GND              VIA   -    MD0100PA00X+033286Y+156828X0200Y         S0      
317GND              VIA   -    MD0100PA00X+034153Y+157261X0200Y         S0      
317GND              VIA   -    MD0100PA00X+034153Y+157850X0200Y         S0      
317GND              VIA   -    MD0100PA00X+034153Y+156788X0200Y         S0      
317GND              VIA   -    MD0100PA00X+033286Y+157890X0200Y         S0      
317GND              VIA   -    MD0100PA00X+034153Y+156314X0200Y         S0      
317GND              VIA   -    MD0100PA00X+033286Y+156354X0200Y         S0      
317GND              VIA   -    MD0100PA00X+033286Y+155881X0200Y         S0      
317GND              VIA   -    MD0100PA00X+034153Y+151631X0200Y         S0      
317GND              VIA   -    MD0100PA00X+033286Y+150251X0200Y         S0      
317GND              VIA   -    MD0100PA00X+033286Y+150724X0200Y         S0      
317GND              VIA   -    MD0100PA00X+034153Y+151158X0200Y         S0      
317GND              VIA   -    MD0100PA00X+034153Y+150095X0200Y         S0      
317GND              VIA   -    MD0100PA00X+034153Y+150684X0200Y         S0      
317GND              VIA   -    MD0100PA00X+033286Y+151198X0200Y         S0      
317GND              VIA   -    M      A01X+036066Y+120979X0200Y         S2      
017GND              VIA   -    M      A18X+036066Y+120979X0260Y         S2      
017GND                    -    MD0100PA00X+036066Y+120979                       
317GND              VIA   -    MD0100PA00X+035254Y+116017X0200Y         S0      
317GND              VIA   -    MD0100PA00X+035795Y+115946X0200Y         S0      
317GND              VIA   -    MD0100PA00X+035156Y+113241X0200Y         S0      
317GND              VIA   -    MD0100PA00X+035593Y+113204X0200Y         S0      
317GND              VIA   -    MD0100PA00X+033200Y+164498X0200Y         S0      
317GND              VIA   -    MD0100PA00X+033286Y+161434X0200Y         S0      
317GND              VIA   -    MD0100PA00X+034153Y+161867X0200Y         S0      
317GND              VIA   -    MD0100PA00X+034153Y+161394X0200Y         S0      
317GND              VIA   -    MD0100PA00X+033286Y+160488X0200Y         S0      
317GND              VIA   -    MD0100PA00X+033286Y+160961X0200Y         S0      
317GND              VIA   -    MD0100PA00X+034153Y+160332X0200Y         S0      
317GND              VIA   -    MD0100PA00X+034153Y+159858X0200Y         S0      
317GND              VIA   -    MD0100PA00X+034153Y+160921X0200Y         S0      
317GND              VIA   -    MD0100PA00X+033286Y+159898X0200Y         S0      
317GND              VIA   -    MD0100PA00X+037021Y+096781X0200Y    R180 S0      
327GND              R818  -2          A01X+037286Y+096781X0198Y0197R180 S1      
317GND              VIA   -    MD0100PA00X+037021Y+095981X0200Y    R180 S0      
327GND              R816  -2          A01X+037286Y+095981X0198Y0197R180 S1      
317GND              VIA   -    MD0100PA00X+036794Y+094608X0200Y         S0      
317GND              VIA   -    MD0100PA00X+037142Y+093718X0200Y         S0      
317GND              VIA   -    MD0100PA00X+037504Y+093296X0200Y         S0      
317GND              VIA   -    MD0100PA00X+036827Y+092810X0200Y    R090 S0      
317GND              VIA   -    MD0100PA00X+035200Y+164498X0200Y         S0      
317GND              VIA   -    MD0100PA00X+035019Y+161434X0200Y         S0      
317GND              VIA   -    MD0100PA00X+035019Y+159898X0200Y         S0      
317GND              VIA   -    MD0100PA00X+035019Y+160961X0200Y         S0      
317GND              VIA   -    MD0100PA00X+035019Y+160488X0200Y         S0      
317GND              VIA   -    MD0100PA00X+035019Y+158952X0200Y         S0      
317GND              VIA   -    MD0100PA00X+035019Y+159425X0200Y         S0      
317GND              VIA   -    MD0100PA00X+035019Y+158363X0200Y         S0      
317GND              VIA   -    MD0100PA00X+035019Y+157417X0200Y         S0      
317GND              VIA   -    MD0100PA00X+035019Y+157890X0200Y         S0      
317GND              VIA   -    MD0100PA00X+035019Y+156828X0200Y         S0      
317GND              VIA   -    MD0100PA00X+035019Y+155881X0200Y         S0      
317GND              VIA   -    MD0100PA00X+035019Y+156354X0200Y         S0      
317GND              VIA   -    MD0100PA00X+035019Y+151198X0200Y         S0      
317GND              VIA   -    MD0100PA00X+035019Y+150252X0200Y         S0      
317GND              VIA   -    MD0100PA00X+035019Y+150725X0200Y         S0      
317GND              VIA   -    MD0100PA00X+035019Y+149662X0200Y         S0      
317GND              VIA   -    MD0100PA00X+035019Y+148716X0200Y         S0      
317GND              VIA   -    MD0100PA00X+035019Y+149189X0200Y         S0      
317GND              VIA   -    MD0100PA00X+036984Y+121894X0200Y         S0      
327GND              R1246 -1          A01X+036471Y+122407X0198Y0197R135 S1      
317GND              VIA   -    MD0100PA00X+036274Y+121186X0200Y         S0      
317GND              VIA   -    MD0100PA00X+036503Y+121416X0200Y         S0      
317GND              VIA   -    MD0100PA00X+036892Y+119542X0200Y         S0      
327GND              R4180 -1   M      A01X+036640Y+119542X0198Y0197R090 S1      
317GND              VIA   -    MD0100PA00X+036866Y+118265X0200Y         S0      
317GND              VIA   -    MD0100PA00X+036613Y+116282X0200Y         S0      
327GND              C2781 -1          A01X+036613Y+116522X0198Y0197R090 S1      
317GND              VIA   -    MD0100PA00X+036866Y+114694X0200Y         S0      
327GND              C2754 -1          A01X+036616Y+114694X0198Y0197R090 S1      
317GND              VIA   -    MD0100PA00X+038547Y+095995X0200Y    R180 S0      
317GND              VIA   -    MD0100PA00X+039015Y+095990X0200Y    R180 S0      
317GND              VIA   -    MD0100PA00X+039161Y+093865X0200Y         S0      
317GND              VIA   -    MD0100PA00X+038661Y+086829X0200Y    R180 S0      
327GND              C838  -2          A01X+038962Y+086829X0198Y0197R180 S1      
317GND              VIA   -    MD0100PA00X+037200Y+164498X0200Y         S0      
317GND              VIA   -    MD0100PA00X+038764Y+130209X0200Y    R270 S0      
317GND              VIA   -    MD0100PA00X+038759Y+129668X0200Y    R270 S0      
317GND              VIA   -    MD0100PA00X+038104Y+100944X0200Y         S0      
317GND              VIA   -    MD0100PA00X+038138Y+100301X0200Y         S0      
317GND              VIA   -    MD0100PA00X+039015Y+095531X0200Y    R180 S0      
317GND              VIA   -    MD0100PA00X+038551Y+095536X0200Y    R180 S0      
327GND              U96   -TH  M      A01X+038781Y+095763X0670Y0670     S1      
317GND              VIA   -    MD0100PA00X+039642Y+109728X0200Y    R090 S0      
317GND              VIA   -    MD0100PA00X+039892Y+109728X0200Y    R090 S0      
317GND              VIA   -    MD0100PA00X+040282Y+095175X0200Y    R180 S0      
327GND              C830  -2          A01X+039982Y+095307X0198Y0197R270 S1      
317GND              VIA   -    MD0100PA00X+040268Y+094854X0200Y    R180 S0      
327GND              C829  -2          A01X+039990Y+094854X0198Y0197     S1      
317GND              VIA   -    MD0100PA00X+039618Y+095586X0200Y    R180 S0      
327GND              U96   -10         A01X+039332Y+095664X0090Y0240R270 S1      
317GND              VIA   -    MD0100PA00X+040912Y+093669X0200Y         S0      
317GND              VIA   -    MD0100PA00X+040112Y+093919X0200Y         S0      
317GND              VIA   -    MD0100PA00X+040912Y+093919X0200Y         S0      
317GND              VIA   -    MD0100PA00X+040112Y+093669X0200Y         S0      
317GND              VIA   -    MD0100PA00X+040719Y+088357X0200Y    R180 S0      
317GND              VIA   -    MD0100PA00X+040642Y+087484X0200Y    R090 S0      
327GND              PR188 -1          A01X+040348Y+087584X0198Y0197R270 S1      
317GND              VIA   -    MD0100PA00X+040697Y+087876X0200Y    R090 S0      
317GND              VIA   -    MD0100PA00X+039988Y+085068X0200Y    R270 S0      
317GND              VIA   -    MD0100PA00X+040238Y+085068X0200Y    R270 S0      
317GND              VIA   -    MD0100PA00X+039988Y+084268X0200Y    R270 S0      
317GND              VIA   -    MD0100PA00X+040238Y+084268X0200Y    R270 S0      
317GND              VIA   -    MD0100PA00X+039200Y+164498X0200Y         S0      
317GND              VIA   -    MD0100PA00X+038202Y+155170X0200Y         S0      
327GND              R5458 -1          A01X+038444Y+155170X0198Y0197     S1      
317GND              VIA   -    MD0100PA00X+038202Y+154770X0200Y         S0      
327GND              R5457 -2          A01X+038444Y+154770X0198Y0197R180 S1      
317GND              VIA   -    MD0100PA00X+038202Y+155570X0200Y         S0      
327GND              R5460 -2          A01X+038444Y+155570X0198Y0197R180 S1      
317GND              VIA   -    MD0100PA00X+040466Y+133297X0180Y         S0      
327GND              C2696 -2          A18X+040466Y+133024X0198Y0197R270 S2      
317GND              VIA   -    MD0100PA00X+040852Y+133297X0180Y         S0      
327GND              C2697 -2          A18X+040852Y+133022X0198Y0197R270 S2      
317GND              VIA   -    MD0100PA00X+039972Y+129520X0200Y         S0      
327GND              R4227 -2          A18X+040006Y+129796X0198Y0197     S2      
317GND              VIA   -    MD0100PA00X+039770Y+128707X0200Y         S0      
317GND              VIA   -    MD0100PA00X+040632Y+120940X0200Y         S0      
317GND              VIA   -    MD0100PA00X+040632Y+121190X0200Y         S0      
317GND              VIA   -    MD0100PA00X+040632Y+120690X0200Y         S0      
317GND              VIA   -    MD0100PA00X+040400Y+120082X0200Y    R180 S0      
317GND              VIA   -    MD0100PA00X+040400Y+119832X0200Y    R180 S0      
317GND              VIA   -    MD0100PA00X+040632Y+120440X0200Y         S0      
317GND              VIA   -    MD0100PA00X+040326Y+115268X0200Y         S0      
317GND              VIA   -    MD0100PA00X+040610Y+114444X0200Y         S0      
317GND              VIA   -    MD0100PA00X+040610Y+114694X0200Y         S0      
317GND              VIA   -    MD0100PA00X+040610Y+114194X0200Y         S0      
317GND              VIA   -    MD0100PA00X+040610Y+113694X0200Y         S0      
317GND              VIA   -    MD0100PA00X+040610Y+113444X0200Y         S0      
317GND              VIA   -    MD0100PA00X+040610Y+113194X0200Y         S0      
317GND              VIA   -    MD0100PA00X+040923Y+112580X0200Y         S0      
317GND              VIA   -    MD0100PA00X+040763Y+112930X0200Y         S0      
317GND              VIA   -    MD0100PA00X+041013Y+112930X0200Y         S0      
317GND              VIA   -    MD0100PA00X+040610Y+113944X0200Y         S0      
317GND              VIA   -    MD0100PA00X+040923Y+112310X0200Y         S0      
317GND              VIA   -    MD0100PA00X+050082Y+137488X0180Y         S0      
317GND              VIA   -    MD0100PA00X+050082Y+138180X0180Y         S0      
317GND              VIA   -    MD0100PA00X+050082Y+136989X0180Y         S0      
317GND              VIA   -    MD0100PA00X+044458Y+136260X0180Y         S0      
317GND              VIA   -    MD0100PA00X+043962Y+136260X0180Y         S0      
317GND              VIA   -    MD0100PA00X+044458Y+135760X0180Y         S0      
317GND              VIA   -    MD0100PA00X+043962Y+135760X0180Y         S0      
317GND              VIA   -    MD0100PA00X+043962Y+135068X0180Y         S0      
317GND              VIA   -    MD0100PA00X+044458Y+135068X0180Y         S0      
317GND              VIA   -    MD0100PA00X+043962Y+134569X0180Y         S0      
317GND              VIA   -    MD0100PA00X+044458Y+134569X0180Y         S0      
317GND              VIA   -    M      A01X+041999Y+109852X0200Y         S2      
017GND              VIA   -    M      A18X+041999Y+109852X0260Y         S2      
017GND                    -    MD0100PA00X+041999Y+109852                       
317GND              VIA   -    MD0100PA00X+041717Y+109889X0200Y         S0      
317GND              VIA   -    MD0100PA00X+042518Y+109877X0200Y         S0      
317GND              VIA   -    MD0100PA00X+041712Y+093919X0200Y         S0      
317GND              VIA   -    MD0100PA00X+041712Y+093669X0200Y         S0      
317GND              VIA   -    MD0100PA00X+042512Y+093919X0200Y         S0      
317GND              VIA   -    MD0100PA00X+042512Y+093669X0200Y         S0      
317GND              VIA   -    MD0100PA00X+041121Y+089211X0200Y    R090 S0      
327GND              PC288 -2          A01X+041121Y+088955X0198Y0197R180 S1      
317GND              VIA   -    MD0100PA00X+042576Y+087832X0200Y    R090 S0      
317GND              VIA   -    MD0100PA00X+042238Y+086723X0200Y    R180 S0      
317GND              VIA   -    MD0100PA00X+042576Y+086712X0200Y    R090 S0      
317GND              VIA   -    MD0100PA00X+042576Y+087552X0200Y    R090 S0      
317GND              VIA   -    MD0100PA00X+042576Y+087272X0200Y    R090 S0      
317GND              VIA   -    MD0100PA00X+042576Y+086992X0200Y    R090 S0      
317GND              VIA   -    MD0100PA00X+042465Y+085864X0200Y    R270 S0      
317GND              VIA   -    MD0100PA00X+042215Y+085864X0200Y    R270 S0      
317GND              VIA   -    MD0100PA00X+042465Y+085064X0200Y    R270 S0      
317GND              VIA   -    MD0100PA00X+042215Y+085064X0200Y    R270 S0      
317GND              VIA   -    MD0100PA00X+042215Y+084264X0200Y    R270 S0      
317GND              VIA   -    MD0100PA00X+042465Y+084264X0200Y    R270 S0      
317GND              VIA   -    M      A01X+042243Y+083480X0200Y    R180 S2      
017GND              VIA   -    M      A18X+042243Y+083480X0260Y    R180 S2      
017GND                    -    MD0100PA00X+042243Y+083480                       
317GND              VIA   -    MD0100PA00X+040546Y+156956X0200Y         S0      
327GND              R5443 -2          A01X+040546Y+156658X0198Y0197R090 S1      
317GND              VIA   -    MD0100PA00X+040946Y+156956X0200Y         S0      
327GND              C3637 -2          A01X+040946Y+156658X0198Y0197R090 S1      
317GND              VIA   -    MD0100PA00X+040091Y+154994X0200Y    R090 S0      
317GND              VIA   -    MD0100PA00X+040705Y+154994X0200Y    R090 S0      
317GND              VIA   -    MD0100PA00X+040091Y+154442X0200Y    R090 S0      
317GND              VIA   -    MD0100PA00X+040705Y+153790X0200Y    R090 S0      
317GND              VIA   -    MD0100PA00X+040091Y+153790X0200Y    R090 S0      
317GND              VIA   -    MD0100PA00X+050082Y+138679X0180Y         S0      
317GND              VIA   -    MD0100PA00X+042372Y+131052X0200Y         S0      
317GND              VIA   -    MD0100PA00X+042558Y+129174X0200Y         S0      
327GND              C2698 -2          A18X+042558Y+128884X0198Y0197R180 S2      
317GND              VIA   -    MD0100PA00X+041335Y+130020X0200Y         S0      
317GND              VIA   -    MD0100PA00X+042374Y+130012X0200Y         S0      
317GND              VIA   -    MD0100PA00X+041854Y+130020X0200Y         S0      
317GND              VIA   -    MD0100PA00X+041117Y+128278X0200Y         S0      
317GND              VIA   -    MD0100PA00X+042062Y+121212X0200Y         S0      
317GND              VIA   -    MD0100PA00X+042062Y+120962X0200Y         S0      
317GND              VIA   -    MD0100PA00X+042062Y+120712X0200Y         S0      
317GND              VIA   -    MD0100PA00X+041747Y+119832X0200Y    R180 S0      
317GND              VIA   -    MD0100PA00X+041747Y+120082X0200Y    R180 S0      
317GND              VIA   -    MD0100PA00X+042062Y+120462X0200Y         S0      
317GND              VIA   -    MD0100PA00X+042293Y+119832X0200Y         S0      
317GND              VIA   -    MD0100PA00X+042293Y+120082X0200Y         S0      
317GND              VIA   -    MD0100PA00X+041210Y+115521X0200Y         S0      
317GND              VIA   -    MD0100PA00X+041210Y+115271X0200Y         S0      
317GND              VIA   -    MD0100PA00X+042250Y+115521X0200Y         S0      
317GND              VIA   -    MD0100PA00X+042250Y+115271X0200Y         S0      
317GND              VIA   -    MD0100PA00X+042513Y+112580X0200Y         S0      
317GND              VIA   -    MD0100PA00X+041763Y+112580X0200Y         S0      
317GND              VIA   -    MD0100PA00X+042013Y+112580X0200Y         S0      
317GND              VIA   -    MD0100PA00X+041263Y+112930X0200Y         S0      
317GND              VIA   -    MD0100PA00X+041513Y+112930X0200Y         S0      
317GND              VIA   -    MD0100PA00X+041763Y+112930X0200Y         S0      
317GND              VIA   -    MD0100PA00X+042013Y+112930X0200Y         S0      
317GND              VIA   -    MD0100PA00X+042263Y+112930X0200Y         S0      
317GND              VIA   -    MD0100PA00X+042513Y+112930X0200Y         S0      
317GND              VIA   -    MD0100PA00X+042263Y+112580X0200Y         S0      
317GND              VIA   -    MD0100PA00X+042066Y+111382X0193Y    R180 S0      
317GND              VIA   -    MD0100PA00X+041818Y+111942X0193Y    R180 S0      
317GND              VIA   -    MD0100PA00X+041818Y+111382X0193Y    R180 S0      
317GND              VIA   -    MD0100PA00X+042314Y+111942X0193Y    R180 S0      
317GND              VIA   -    MD0100PA00X+041723Y+112310X0200Y         S0      
317GND              VIA   -    MD0100PA00X+041973Y+112310X0200Y         S0      
327GND              PU7   -7_9-M      A01X+041721Y+112618X0827Y2126R270 S1      
317GND              VIA   -    MD0100PA00X+042314Y+111382X0193Y    R180 S0      
317GND              VIA   -    MD0100PA00X+042066Y+111942X0193Y    R180 S0      
327GND              PU7   -40  M      A01X+042066Y+111663X0690Y0770R180 S1      
317GND              VIA   -    MD0100PA00X+046410Y+135760X0180Y         S0      
317GND              VIA   -    MD0100PA00X+046410Y+136260X0180Y         S0      
317GND              VIA   -    MD0100PA00X+045186Y+135760X0180Y         S0      
317GND              VIA   -    MD0100PA00X+045186Y+136260X0180Y         S0      
317GND              VIA   -    MD0100PA00X+045682Y+135760X0180Y         S0      
317GND              VIA   -    MD0100PA00X+045682Y+136260X0180Y         S0      
317GND              VIA   -    MD0100PA00X+045682Y+135068X0180Y         S0      
317GND              VIA   -    MD0100PA00X+046410Y+135068X0180Y         S0      
317GND              VIA   -    MD0100PA00X+045186Y+135068X0180Y         S0      
317GND              VIA   -    MD0100PA00X+046410Y+134569X0180Y         S0      
317GND              VIA   -    MD0100PA00X+045186Y+134569X0180Y         S0      
317GND              VIA   -    MD0100PA00X+045682Y+134569X0180Y         S0      
317GND              VIA   -    MD0100PA00X+041340Y+131048X0200Y         S0      
317GND              VIA   -    MD0100PA00X+041856Y+131052X0200Y         S0      
317GND              VIA   -    MD0100PA00X+041337Y+130530X0200Y         S0      
317GND              VIA   -    MD0100PA00X+042376Y+130530X0200Y         S0      
327GND              U118  -33  M      A18X+041856Y+130532X1240Y1240     S2      
317GND              VIA   -    MD0100PA00X+042876Y+087832X0200Y    R090 S0      
317GND              VIA   -    MD0100PA00X+042876Y+087552X0200Y    R090 S0      
317GND              VIA   -    MD0100PA00X+042876Y+087272X0200Y    R090 S0      
317GND              VIA   -    MD0100PA00X+042876Y+086712X0200Y    R090 S0      
317GND              VIA   -    MD0100PA00X+041200Y+164498X0200Y         S0      
317GND              VIA   -    MD0100PA00X+041346Y+156956X0200Y         S0      
327GND              R5456 -2          A01X+041346Y+156658X0198Y0197R090 S1      
317GND              VIA   -    MD0100PA00X+042162Y+154988X0200Y    R090 S0      
317GND              VIA   -    MD0100PA00X+041301Y+154994X0200Y    R090 S0      
317GND              VIA   -    MD0100PA00X+042620Y+153409X0200Y    R090 S0      
327GND              R5455 -1          A01X+042719Y+153709X0198Y0197R180 S1      
317GND              VIA   -    MD0100PA00X+041301Y+154410X0200Y    R090 S0      
317GND              VIA   -    MD0100PA00X+041301Y+153790X0200Y    R090 S0      
327GND              U353  -TH  M      A01X+040700Y+154392X1400Y1400R090 S1      
317GND              VIA   -    MD0100PA00X+050578Y+138679X0180Y         S0      
317GND              VIA   -    MD0100PA00X+051802Y+138679X0180Y         S0      
317GND              VIA   -    MD0100PA00X+051306Y+138679X0180Y         S0      
317GND              VIA   -    MD0100PA00X+050578Y+136989X0180Y         S0      
317GND              VIA   -    MD0100PA00X+051802Y+137488X0180Y         S0      
317GND              VIA   -    MD0100PA00X+051802Y+138180X0180Y         S0      
317GND              VIA   -    MD0080PA00X+051948Y+137238X0160Y         S0      
317GND              VIA   -    MD0080PA00X+051948Y+138430X0160Y         S0      
317GND              VIA   -    MD0100PA00X+051802Y+136989X0180Y         S0      
317GND              VIA   -    MD0100PA00X+051306Y+137488X0180Y         S0      
317GND              VIA   -    MD0100PA00X+051306Y+138180X0180Y         S0      
317GND              VIA   -    MD0100PA00X+051306Y+136989X0180Y         S0      
317GND              VIA   -    MD0100PA00X+050578Y+137488X0180Y         S0      
317GND              VIA   -    MD0100PA00X+050578Y+138180X0180Y         S0      
317GND              VIA   -    MD0100PA00X+042933Y+114444X0200Y         S0      
317GND              VIA   -    MD0100PA00X+042933Y+114694X0200Y         S0      
317GND              VIA   -    MD0100PA00X+043723Y+115240X0200Y         S0      
317GND              VIA   -    MD0100PA00X+043723Y+115490X0200Y         S0      
317GND              VIA   -    MD0100PA00X+043823Y+114444X0200Y         S0      
317GND              VIA   -    MD0100PA00X+043823Y+114694X0200Y         S0      
317GND              VIA   -    MD0100PA00X+043823Y+114194X0200Y         S0      
317GND              VIA   -    MD0100PA00X+043573Y+114444X0200Y         S0      
317GND              VIA   -    MD0100PA00X+043573Y+114694X0200Y         S0      
317GND              VIA   -    MD0100PA00X+043573Y+114194X0200Y         S0      
317GND              VIA   -    MD0100PA00X+042933Y+114194X0200Y         S0      
317GND              VIA   -    MD0100PA00X+043823Y+113694X0200Y         S0      
317GND              VIA   -    MD0100PA00X+043823Y+113444X0200Y         S0      
317GND              VIA   -    MD0100PA00X+043823Y+113194X0200Y         S0      
317GND              VIA   -    MD0100PA00X+043573Y+113944X0200Y         S0      
317GND              VIA   -    MD0100PA00X+043573Y+113694X0200Y         S0      
317GND              VIA   -    MD0100PA00X+043573Y+113444X0200Y         S0      
317GND              VIA   -    MD0100PA00X+043573Y+113194X0200Y         S0      
317GND              VIA   -    MD0100PA00X+042933Y+113194X0200Y         S0      
317GND              VIA   -    MD0100PA00X+042933Y+113944X0200Y         S0      
317GND              VIA   -    MD0100PA00X+042933Y+113444X0200Y         S0      
317GND              VIA   -    MD0100PA00X+042933Y+113694X0200Y         S0      
317GND              VIA   -    MD0100PA00X+044226Y+112930X0200Y         S0      
317GND              VIA   -    MD0100PA00X+043976Y+112930X0200Y         S0      
317GND              VIA   -    MD0100PA00X+044136Y+112580X0200Y         S0      
317GND              VIA   -    MD0100PA00X+043823Y+113944X0200Y         S0      
317GND              VIA   -    MD0100PA00X+044136Y+112310X0200Y         S0      
317GND              VIA   -    MD0100PA00X+043233Y+090045X0200Y    R090 S0      
317GND              VIA   -    MD0100PA00X+043233Y+089485X0200Y    R090 S0      
317GND              VIA   -    MD0100PA00X+043233Y+089765X0200Y    R090 S0      
317GND              VIA   -    MD0100PA00X+043233Y+089205X0200Y    R090 S0      
317GND              VIA   -    MD0100PA00X+042876Y+086992X0200Y    R090 S0      
317GND              VIA   -    MD0100PA00X+047634Y+135068X0180Y         S0      
317GND              VIA   -    MD0100PA00X+048130Y+135068X0180Y         S0      
317GND              VIA   -    MD0100PA00X+046906Y+135068X0180Y         S0      
317GND              VIA   -    MD0100PA00X+047634Y+134569X0180Y         S0      
317GND              VIA   -    MD0100PA00X+048130Y+134569X0180Y         S0      
317GND              VIA   -    MD0100PA00X+046906Y+134569X0180Y         S0      
317GND              VIA   -    MD0080PA00X+048276Y+134819X0160Y         S0      
317GND              VIA   -    MD0100PA00X+043248Y+132578X0200Y         S0      
317GND              VIA   -    MD0100PA00X+044090Y+131137X0200Y         S0      
327GND              C2702 -2          A18X+043840Y+130986X0198Y0197R180 S2      
317GND              VIA   -    MD0100PA00X+043799Y+128654X0200Y         S0      
317GND              VIA   -    MD0100PA00X+043325Y+120690X0200Y         S0      
317GND              VIA   -    MD0100PA00X+043325Y+121190X0200Y         S0      
317GND              VIA   -    MD0100PA00X+043325Y+120940X0200Y         S0      
317GND              VIA   -    MD0100PA00X+043093Y+119832X0200Y    R180 S0      
317GND              VIA   -    MD0100PA00X+043093Y+120082X0200Y    R180 S0      
317GND              VIA   -    MD0100PA00X+043325Y+120440X0200Y         S0      
317GND              VIA   -    MD0100PA00X+053026Y+138679X0180Y         S0      
317GND              VIA   -    MD0100PA00X+053754Y+138180X0180Y         S0      
317GND              VIA   -    MD0100PA00X+053754Y+136989X0180Y         S0      
317GND              VIA   -    MD0100PA00X+053026Y+137488X0180Y         S0      
317GND              VIA   -    MD0100PA00X+053026Y+138180X0180Y         S0      
317GND              VIA   -    MD0100PA00X+053026Y+136989X0180Y         S0      
317GND              VIA   -    MD0100PA00X+052530Y+137488X0180Y         S0      
317GND              VIA   -    MD0100PA00X+052530Y+138180X0180Y         S0      
317GND              VIA   -    MD0100PA00X+052530Y+136989X0180Y         S0      
317GND              VIA   -    MD0100PA00X+053754Y+137488X0180Y         S0      
317GND              VIA   -    MD0080PA00X+053172Y+137238X0160Y         S0      
317GND              VIA   -    MD0080PA00X+053172Y+138430X0160Y         S0      
317GND              VIA   -    MD0100PA00X+046906Y+136260X0180Y         S0      
317GND              VIA   -    MD0080PA00X+048276Y+136010X0160Y         S0      
317GND              VIA   -    MD0100PA00X+047634Y+135760X0180Y         S0      
317GND              VIA   -    MD0100PA00X+047634Y+136260X0180Y         S0      
317GND              VIA   -    MD0100PA00X+048130Y+135760X0180Y         S0      
317GND              VIA   -    MD0100PA00X+048130Y+136260X0180Y         S0      
317GND              VIA   -    MD0100PA00X+046906Y+135760X0180Y         S0      
317GND              VIA   -    MD0100PA00X+045262Y+115521X0200Y         S0      
317GND              VIA   -    MD0100PA00X+045262Y+115271X0200Y         S0      
317GND              VIA   -    MD0100PA00X+044322Y+115271X0200Y         S0      
317GND              VIA   -    MD0100PA00X+044322Y+115521X0200Y         S0      
317GND              VIA   -    MD0100PA00X+045476Y+112930X0200Y         S0      
317GND              VIA   -    MD0100PA00X+045726Y+112580X0200Y         S0      
317GND              VIA   -    MD0100PA00X+045476Y+112580X0200Y         S0      
317GND              VIA   -    MD0100PA00X+045226Y+112930X0200Y         S0      
317GND              VIA   -    MD0100PA00X+044976Y+112930X0200Y         S0      
317GND              VIA   -    MD0100PA00X+044726Y+112930X0200Y         S0      
317GND              VIA   -    MD0100PA00X+044476Y+112930X0200Y         S0      
317GND              VIA   -    MD0100PA00X+045226Y+112580X0200Y         S0      
317GND              VIA   -    MD0100PA00X+044976Y+112580X0200Y         S0      
317GND              VIA   -    MD0100PA00X+045726Y+112930X0200Y         S0      
317GND              VIA   -    MD0100PA00X+045527Y+111382X0193Y    R180 S0      
317GND              VIA   -    MD0100PA00X+045279Y+111942X0193Y    R180 S0      
317GND              VIA   -    MD0100PA00X+045279Y+111382X0193Y    R180 S0      
317GND              VIA   -    MD0100PA00X+045031Y+111942X0193Y    R180 S0      
317GND              VIA   -    MD0100PA00X+045031Y+111382X0193Y    R180 S0      
317GND              VIA   -    MD0100PA00X+045527Y+111942X0193Y    R180 S0      
327GND              PU8   -40  M      A01X+045278Y+111663X0690Y0770R180 S1      
317GND              VIA   -    MD0100PA00X+045186Y+112310X0200Y         S0      
317GND              VIA   -    MD0100PA00X+044936Y+112310X0200Y         S0      
327GND              PU8   -7_9-M      A01X+044934Y+112618X0827Y2126R270 S1      
317GND              VIA   -    MD0100PA00X+045024Y+109307X0200Y    R180 S0      
317GND              VIA   -    MD0100PA00X+044686Y+109843X0200Y         S0      
317GND              VIA   -    M      A01X+045212Y+109852X0200Y         S2      
017GND              VIA   -    M      A18X+045212Y+109852X0260Y         S2      
017GND                    -    MD0100PA00X+045212Y+109852                       
317GND              VIA   -    MD0100PA00X+045730Y+109877X0200Y         S0      
317GND              VIA   -    MD0100PA00X+045024Y+109027X0200Y    R180 S0      
317GND              VIA   -    MD0100PA00X+044309Y+103027X0200Y         S0      
317GND              VIA   -    MD0100PA00X+044309Y+102277X0200Y         S0      
317GND              VIA   -    MD0100PA00X+045371Y+101882X0200Y         S0      
327GND              PC56  -2          A01X+045371Y+101232X0198Y0197R180 S1      
327GND              PR94  -2   M      A01X+045371Y+101632X0198Y0197R180 S1      
327GND              PC54  -2          A18X+045059Y+101734X0198Y0197R270 S2      
317GND              VIA   -    MD0100PA00X+044973Y+100086X0200Y         S0      
317GND              VIA   -    MD0100PA00X+045232Y+100083X0200Y         S0      
317GND              VIA   -    MD0100PA00X+045621Y+100468X0200Y         S0      
327GND              PC45  -2          A01X+045621Y+100718X0198Y0197R180 S1      
327GND              PR98  -2          A18X+045459Y+100719X0198Y0197R090 S2      
317GND              VIA   -    MD0100PA00X+044900Y+099448X0200Y         S0      
317GND              VIA   -    MD0100PA00X+045482Y+097462X0200Y         S0      
317GND              VIA   -    MD0100PA00X+043200Y+164498X0200Y         S0      
317GND              VIA   -    MD0100PA00X+043066Y+156356X0200Y    R180 S0      
317GND              VIA   -    MD0100PA00X+043768Y+155016X0200Y         S0      
317GND              VIA   -    MD0100PA00X+052530Y+138679X0180Y         S0      
317GND              VIA   -    MD0100PA00X+053754Y+138679X0180Y         S0      
317GND              VIA   -    MD0100PA00X+049354Y+135068X0180Y         S0      
317GND              VIA   -    MD0100PA00X+048858Y+135068X0180Y         S0      
317GND              VIA   -    MD0100PA00X+049354Y+134569X0180Y         S0      
317GND              VIA   -    MD0100PA00X+048858Y+134569X0180Y         S0      
317GND              VIA   -    MD0100PA00X+043962Y+137488X0180Y         S0      
317GND              VIA   -    MD0100PA00X+043962Y+136989X0180Y         S0      
317GND              VIA   -    MD0080PA00X+049500Y+134819X0160Y         S0      
317GND              VIA   -    MD0100PA00X+045189Y+130602X0200Y    R090 S0      
317GND              VIA   -    MD0100PA00X+045683Y+129912X0200Y    R090 S0      
317GND              VIA   -    MD0100PA00X+045130Y+129304X0200Y         S0      
327GND              R1224 -1          A18X+044848Y+129304X0198Y0197     S2      
317GND              VIA   -    MD0100PA00X+045189Y+130107X0200Y    R090 S0      
317GND              VIA   -    MD0100PA00X+044755Y+121212X0200Y         S0      
317GND              VIA   -    MD0100PA00X+044755Y+120712X0200Y         S0      
317GND              VIA   -    MD0100PA00X+044755Y+120962X0200Y         S0      
317GND              VIA   -    MD0100PA00X+044986Y+120082X0200Y         S0      
317GND              VIA   -    MD0100PA00X+044986Y+119832X0200Y         S0      
317GND              VIA   -    MD0100PA00X+044755Y+120462X0200Y         S0      
317GND              VIA   -    MD0100PA00X+045412Y+146591X0180Y         S0      
317GND              VIA   -    MD0100PA00X+054250Y+138679X0180Y         S0      
317GND              VIA   -    MD0100PA00X+054978Y+138679X0180Y         S0      
317GND              VIA   -    MD0100PA00X+055474Y+138679X0180Y         S0      
317GND              VIA   -    MD0080PA00X+054396Y+138430X0160Y         S0      
317GND              VIA   -    MD0080PA00X+054396Y+137238X0160Y         S0      
317GND              VIA   -    MD0100PA00X+055474Y+136989X0180Y         S0      
317GND              VIA   -    MD0100PA00X+054250Y+138180X0180Y         S0      
317GND              VIA   -    MD0100PA00X+054250Y+136989X0180Y         S0      
317GND              VIA   -    MD0100PA00X+054978Y+137488X0180Y         S0      
317GND              VIA   -    MD0100PA00X+054978Y+138180X0180Y         S0      
317GND              VIA   -    MD0100PA00X+054978Y+136989X0180Y         S0      
317GND              VIA   -    MD0100PA00X+054250Y+137488X0180Y         S0      
317GND              VIA   -    MD0100PA00X+055474Y+137488X0180Y         S0      
317GND              VIA   -    MD0100PA00X+055474Y+138180X0180Y         S0      
317GND              VIA   -    MD0100PA00X+048858Y+136260X0180Y         S0      
317GND              VIA   -    MD0100PA00X+049354Y+135760X0180Y         S0      
317GND              VIA   -    MD0100PA00X+049354Y+136260X0180Y         S0      
317GND              VIA   -    MD0100PA00X+048858Y+135760X0180Y         S0      
317GND              VIA   -    MD0100PA00X+043962Y+138180X0180Y         S0      
317GND              VIA   -    MD0100PA00X+043962Y+138679X0180Y         S0      
317GND              VIA   -    MD0080PA00X+049500Y+136010X0160Y         S0      
317GND              VIA   -    MD0100PA00X+045412Y+160488X0200Y         S0      
317GND              VIA   -    MD0100PA00X+045412Y+159898X0180Y         S0      
317GND              VIA   -    MD0100PA00X+045412Y+159425X0180Y         S0      
317GND              VIA   -    MD0100PA00X+045412Y+158952X0200Y         S0      
317GND              VIA   -    MD0100PA00X+045412Y+158363X0180Y         S0      
317GND              VIA   -    MD0100PA00X+045412Y+157417X0200Y         S0      
317GND              VIA   -    MD0100PA00X+045412Y+156354X0180Y         S0      
317GND              VIA   -    MD0100PA00X+045412Y+156828X0180Y         S0      
317GND              VIA   -    MD0100PA00X+045412Y+157890X0180Y         S0      
317GND              VIA   -    MD0100PA00X+045412Y+155881X0200Y         S0      
317GND              VIA   -    MD0100PA00X+045412Y+150251X0200Y         S0      
317GND              VIA   -    MD0100PA00X+045412Y+150724X0180Y         S0      
317GND              VIA   -    MD0100PA00X+045412Y+151198X0180Y         S0      
317GND              VIA   -    MD0100PA00X+045412Y+149662X0180Y         S0      
317GND              VIA   -    MD0100PA00X+045412Y+148716X0200Y         S0      
317GND              VIA   -    MD0100PA00X+045412Y+149189X0180Y         S0      
317GND              VIA   -    MD0100PA00X+045412Y+147654X0180Y         S0      
317GND              VIA   -    MD0100PA00X+045412Y+148127X0180Y         S0      
317GND              VIA   -    MD0100PA00X+045412Y+147180X0200Y         S0      
317GND              VIA   -    MD0100PA00X+045412Y+146118X0180Y         S0      
317GND              VIA   -    MD0100PA00X+046919Y+113444X0200Y         S0      
317GND              VIA   -    MD0100PA00X+046919Y+113694X0200Y         S0      
317GND              VIA   -    MD0100PA00X+046919Y+113944X0200Y         S0      
317GND              VIA   -    MD0100PA00X+047169Y+113194X0200Y         S0      
317GND              VIA   -    MD0100PA00X+047169Y+113444X0200Y         S0      
317GND              VIA   -    MD0100PA00X+047169Y+113694X0200Y         S0      
317GND              VIA   -    MD0100PA00X+047169Y+113944X0200Y         S0      
317GND              VIA   -    MD0100PA00X+046146Y+113194X0200Y         S0      
317GND              VIA   -    MD0100PA00X+046146Y+113944X0200Y         S0      
317GND              VIA   -    MD0100PA00X+046146Y+113444X0200Y         S0      
317GND              VIA   -    MD0100PA00X+046146Y+113694X0200Y         S0      
317GND              VIA   -    MD0100PA00X+047322Y+112930X0200Y         S0      
317GND              VIA   -    MD0100PA00X+047482Y+112580X0200Y         S0      
317GND              VIA   -    MD0100PA00X+047482Y+112310X0200Y         S0      
317GND              VIA   -    MD0100PA00X+046028Y+109307X0200Y         S0      
317GND              VIA   -    MD0100PA00X+046028Y+109027X0200Y         S0      
317GND              VIA   -    MD0100PA00X+046243Y+103022X0200Y         S0      
327GND              PC55  -2          A18X+046038Y+102677X0198Y0197R270 S2      
317GND              VIA   -    MD0100PA00X+046950Y+101730X0200Y    R090 S0      
317GND              VIA   -    MD0100PA00X+046950Y+102330X0200Y    R090 S0      
317GND              VIA   -    MD0100PA00X+046950Y+101130X0200Y    R090 S0      
317GND              VIA   -    MD0100PA00X+046749Y+092453X0200Y         S0      
317GND              VIA   -    MD0100PA00X+047505Y+088595X0200Y         S0      
317GND              VIA   -    MD0100PA00X+046046Y+086705X0200Y         S0      
317GND              VIA   -    MD0100PA00X+046313Y+085920X0200Y         S0      
317GND              VIA   -    MD0100PA00X+047468Y+085792X0200Y         S0      
317GND              VIA   -    MD0100PA00X+047503Y+084325X0200Y         S0      
317GND              VIA   -    MD0100PA00X+046224Y+080979X0200Y         S0      
317GND              VIA   -    MD0100PA00X+045200Y+164498X0200Y         S0      
317GND              VIA   -    MD0100PA00X+045412Y+161434X0180Y         S0      
317GND              VIA   -    MD0100PA00X+045412Y+160961X0180Y         S0      
317GND              VIA   -    MD0100PA00X+044458Y+138679X0180Y         S0      
317GND              VIA   -    MD0100PA00X+045186Y+138180X0180Y         S0      
317GND              VIA   -    MD0100PA00X+045186Y+138679X0180Y         S0      
317GND              VIA   -    MD0100PA00X+045682Y+138180X0180Y         S0      
317GND              VIA   -    MD0100PA00X+045682Y+138679X0180Y         S0      
317GND              VIA   -    MD0100PA00X+044458Y+138180X0180Y         S0      
317GND              VIA   -    MD0080PA00X+044604Y+138430X0160Y         S0      
317GND              VIA   -    MD0080PA00X+045828Y+138430X0160Y         S0      
317GND              VIA   -    MD0100PA00X+044458Y+137488X0180Y         S0      
317GND              VIA   -    MD0100PA00X+045186Y+136980X0180Y         S0      
317GND              VIA   -    MD0100PA00X+045682Y+136980X0180Y         S0      
317GND              VIA   -    MD0100PA00X+044458Y+136989X0180Y         S0      
317GND              VIA   -    MD0080PA00X+044604Y+137238X0160Y         S0      
317GND              VIA   -    MD0080PA00X+045828Y+137238X0160Y         S0      
317GND              VIA   -    MD0100PA00X+045186Y+137488X0180Y         S0      
317GND              VIA   -    MD0100PA00X+045682Y+137488X0180Y         S0      
317GND              VIA   -    MD0100PA00X+046146Y+114694X0200Y         S0      
317GND              VIA   -    MD0100PA00X+046146Y+114194X0200Y         S0      
317GND              VIA   -    MD0100PA00X+046885Y+115268X0200Y         S0      
317GND              VIA   -    MD0100PA00X+046269Y+115268X0200Y         S0      
317GND              VIA   -    MD0100PA00X+046146Y+114444X0200Y         S0      
317GND              VIA   -    MD0100PA00X+047169Y+114444X0200Y         S0      
317GND              VIA   -    MD0100PA00X+046919Y+114194X0200Y         S0      
317GND              VIA   -    MD0100PA00X+046919Y+114694X0200Y         S0      
317GND              VIA   -    MD0100PA00X+046919Y+114444X0200Y         S0      
317GND              VIA   -    MD0100PA00X+047169Y+114194X0200Y         S0      
317GND              VIA   -    MD0100PA00X+047169Y+114694X0200Y         S0      
317GND              VIA   -    MD0100PA00X+046919Y+113194X0200Y         S0      
317GND              VIA   -    MD0100PA00X+046279Y+146551X0180Y         S0      
317GND              VIA   -    MD0100PA00X+047145Y+146591X0180Y         S0      
317GND              VIA   -    MD0100PA00X+046279Y+146078X0200Y         S0      
317GND              VIA   -    MD0100PA00X+047145Y+146118X0180Y         S0      
317GND              VIA   -    MD0100PA00X+056202Y+138679X0180Y         S0      
317GND              VIA   -    MD0100PA00X+045682Y+141099X0180Y         S0      
317GND              VIA   -    MD0100PA00X+045186Y+141099X0180Y         S0      
317GND              VIA   -    MD0100PA00X+056698Y+138679X0180Y         S0      
317GND              VIA   -    MD0100PA00X+045682Y+139399X0180Y         S0      
317GND              VIA   -    MD0100PA00X+045186Y+139908X0180Y         S0      
317GND              VIA   -    MD0100PA00X+045186Y+140600X0180Y         S0      
317GND              VIA   -    MD0100PA00X+056698Y+137488X0180Y         S0      
317GND              VIA   -    MD0100PA00X+056698Y+138180X0180Y         S0      
317GND              VIA   -    MD0100PA00X+045186Y+139399X0180Y         S0      
317GND              VIA   -    MD0100PA00X+056698Y+136989X0180Y         S0      
317GND              VIA   -    MD0100PA00X+056202Y+137488X0180Y         S0      
317GND              VIA   -    MD0100PA00X+056202Y+138180X0180Y         S0      
317GND              VIA   -    MD0100PA00X+056202Y+136989X0180Y         S0      
317GND              VIA   -    MD0100PA00X+045682Y+139908X0180Y         S0      
317GND              VIA   -    MD0100PA00X+045682Y+140600X0180Y         S0      
317GND              VIA   -    MD0100PA00X+046279Y+151631X0180Y         S0      
317GND              VIA   -    MD0100PA00X+046279Y+150095X0180Y         S0      
317GND              VIA   -    MD0100PA00X+046279Y+150684X0200Y         S0      
317GND              VIA   -    MD0100PA00X+046279Y+151158X0180Y         S0      
317GND              VIA   -    MD0100PA00X+047145Y+150724X0180Y         S0      
317GND              VIA   -    MD0100PA00X+047145Y+150251X0200Y         S0      
317GND              VIA   -    MD0100PA00X+047145Y+151198X0180Y         S0      
317GND              VIA   -    MD0100PA00X+047145Y+148716X0200Y         S0      
317GND              VIA   -    MD0100PA00X+046279Y+148560X0180Y         S0      
317GND              VIA   -    MD0100PA00X+046279Y+149149X0200Y         S0      
317GND              VIA   -    MD0100PA00X+047145Y+149189X0180Y         S0      
317GND              VIA   -    MD0100PA00X+046279Y+149622X0180Y         S0      
317GND              VIA   -    MD0100PA00X+047145Y+149662X0180Y         S0      
317GND              VIA   -    MD0100PA00X+046279Y+147024X0180Y         S0      
317GND              VIA   -    MD0100PA00X+046279Y+147614X0200Y         S0      
317GND              VIA   -    MD0100PA00X+047145Y+147654X0180Y         S0      
317GND              VIA   -    MD0100PA00X+047145Y+147180X0200Y         S0      
317GND              VIA   -    MD0100PA00X+046279Y+148087X0180Y         S0      
317GND              VIA   -    MD0100PA00X+047145Y+148127X0180Y         S0      
317GND              VIA   -    MD0100PA00X+047145Y+160488X0200Y         S0      
317GND              VIA   -    MD0100PA00X+047145Y+160961X0180Y         S0      
317GND              VIA   -    MD0100PA00X+046279Y+160332X0180Y         S0      
317GND              VIA   -    MD0100PA00X+046279Y+159858X0180Y         S0      
317GND              VIA   -    MD0100PA00X+046279Y+160921X0200Y         S0      
317GND              VIA   -    MD0100PA00X+047145Y+159898X0180Y         S0      
317GND              VIA   -    MD0100PA00X+046279Y+158796X0180Y         S0      
317GND              VIA   -    MD0100PA00X+046279Y+158323X0180Y         S0      
317GND              VIA   -    MD0100PA00X+047145Y+158363X0180Y         S0      
317GND              VIA   -    MD0100PA00X+047145Y+158952X0200Y         S0      
317GND              VIA   -    MD0100PA00X+046279Y+159385X0200Y         S0      
317GND              VIA   -    MD0100PA00X+047145Y+159425X0180Y         S0      
317GND              VIA   -    MD0100PA00X+047145Y+157890X0180Y         S0      
317GND              VIA   -    MD0100PA00X+046279Y+157261X0180Y         S0      
317GND              VIA   -    MD0100PA00X+046279Y+156788X0180Y         S0      
317GND              VIA   -    MD0100PA00X+047145Y+156354X0180Y         S0      
317GND              VIA   -    MD0100PA00X+047145Y+156828X0180Y         S0      
317GND              VIA   -    MD0100PA00X+047145Y+157417X0200Y         S0      
317GND              VIA   -    MD0100PA00X+046279Y+157850X0200Y         S0      
317GND              VIA   -    MD0100PA00X+047145Y+155881X0200Y         S0      
317GND              VIA   -    MD0100PA00X+046279Y+156314X0200Y         S0      
317GND              VIA   -    MD0100PA00X+048282Y+112310X0200Y         S0      
317GND              VIA   -    MD0100PA00X+048032Y+109843X0200Y         S0      
317GND              VIA   -    M      A01X+048557Y+109852X0200Y         S2      
017GND              VIA   -    M      A18X+048557Y+109852X0260Y         S2      
017GND                    -    MD0100PA00X+048557Y+109852                       
317GND              VIA   -    MD0100PA00X+049076Y+109877X0200Y         S0      
317GND              VIA   -    MD0100PA00X+047550Y+102330X0200Y    R090 S0      
317GND              VIA   -    MD0100PA00X+048150Y+101730X0200Y    R090 S0      
317GND              VIA   -    MD0100PA00X+048150Y+102330X0200Y    R090 S0      
317GND              VIA   -    MD0100PA00X+047550Y+101130X0200Y    R090 S0      
317GND              VIA   -    MD0100PA00X+048150Y+101130X0200Y    R090 S0      
327GND              PU6   -TH  M      A01X+047550Y+101730X1440Y1440R090 S1      
317GND              VIA   -    MD0100PA00X+049014Y+098952X0200Y         S0      
317GND              VIA   -    MD0100PA00X+048364Y+095215X0200Y         S0      
317GND              VIA   -    MD0100PA00X+048839Y+093890X0200Y         S0      
317GND              VIA   -    MD0100PA00X+048194Y+092463X0200Y         S0      
317GND              VIA   -    MD0100PA00X+048847Y+085701X0200Y         S0      
317GND              VIA   -    MD0100PA00X+049153Y+084321X0200Y         S0      
317GND              VIA   -    MD0100PA00X+049145Y+083455X0200Y         S0      
317GND              VIA   -    MD0100PA00X+048159Y+082639X0200Y         S0      
317GND              VIA   -    MD0100PA00X+048582Y+081979X0200Y         S0      
317GND              VIA   -    MD0100PA00X+048625Y+080450X0200Y         S0      
327GND              U99   -2          A18X+049005Y+080450X0240Y0440R270 S2      
317GND              VIA   -    MD0100PA00X+047200Y+164498X0200Y         S0      
317GND              VIA   -    MD0100PA00X+046279Y+161867X0180Y         S0      
317GND              VIA   -    MD0100PA00X+046279Y+161394X0180Y         S0      
317GND              VIA   -    MD0100PA00X+047145Y+161434X0180Y         S0      
317GND              VIA   -    MD0100PA00X+046906Y+137488X0180Y         S0      
317GND              VIA   -    MD0100PA00X+047634Y+137488X0180Y         S0      
317GND              VIA   -    MD0100PA00X+046410Y+137488X0180Y         S0      
317GND              VIA   -    MD0100PA00X+046906Y+136989X0180Y         S0      
317GND              VIA   -    MD0100PA00X+047634Y+136989X0180Y         S0      
317GND              VIA   -    MD0100PA00X+046410Y+136989X0180Y         S0      
317GND              VIA   -    MD0100PA00X+047952Y+120940X0200Y         S0      
317GND              VIA   -    MD0100PA00X+047952Y+121190X0200Y         S0      
317GND              VIA   -    MD0100PA00X+047952Y+120690X0200Y         S0      
317GND              VIA   -    MD0100PA00X+047721Y+120082X0200Y    R180 S0      
317GND              VIA   -    MD0100PA00X+047952Y+120440X0200Y         S0      
317GND              VIA   -    MD0100PA00X+049067Y+120082X0200Y    R180 S0      
317GND              VIA   -    MD0100PA00X+049067Y+119832X0200Y    R180 S0      
317GND              VIA   -    MD0100PA00X+047721Y+119832X0200Y    R180 S0      
317GND              VIA   -    MD0100PA00X+048808Y+115271X0200Y         S0      
317GND              VIA   -    MD0100PA00X+048808Y+115521X0200Y         S0      
317GND              VIA   -    MD0100PA00X+047768Y+115521X0200Y         S0      
317GND              VIA   -    MD0100PA00X+047768Y+115271X0200Y         S0      
317GND              VIA   -    MD0100PA00X+048822Y+112930X0200Y         S0      
317GND              VIA   -    MD0100PA00X+049072Y+112580X0200Y         S0      
317GND              VIA   -    MD0100PA00X+048822Y+112580X0200Y         S0      
317GND              VIA   -    MD0100PA00X+048572Y+112930X0200Y         S0      
317GND              VIA   -    MD0100PA00X+048322Y+112930X0200Y         S0      
317GND              VIA   -    MD0100PA00X+048072Y+112930X0200Y         S0      
317GND              VIA   -    MD0100PA00X+047822Y+112930X0200Y         S0      
317GND              VIA   -    MD0100PA00X+047572Y+112930X0200Y         S0      
317GND              VIA   -    MD0100PA00X+048572Y+112580X0200Y         S0      
317GND              VIA   -    MD0100PA00X+048322Y+112580X0200Y         S0      
317GND              VIA   -    MD0100PA00X+049072Y+112930X0200Y         S0      
317GND              VIA   -    MD0100PA00X+048873Y+111382X0193Y    R180 S0      
317GND              VIA   -    MD0100PA00X+048377Y+111942X0193Y    R180 S0      
317GND              VIA   -    MD0100PA00X+048625Y+111942X0193Y    R180 S0      
317GND              VIA   -    MD0100PA00X+048625Y+111382X0193Y    R180 S0      
317GND              VIA   -    MD0100PA00X+048377Y+111382X0193Y    R180 S0      
317GND              VIA   -    MD0100PA00X+048873Y+111942X0193Y    R180 S0      
327GND              PU9   -40  M      A01X+048624Y+111663X0690Y0770R180 S1      
317GND              VIA   -    MD0100PA00X+048532Y+112310X0200Y         S0      
327GND              PU9   -7_9-M      A01X+048280Y+112618X0827Y2126R270 S1      
317GND              VIA   -    MD0100PA00X+046906Y+141099X0180Y         S0      
317GND              VIA   -    MD0100PA00X+046410Y+141099X0180Y         S0      
317GND              VIA   -    MD0100PA00X+046906Y+140600X0180Y         S0      
317GND              VIA   -    MD0080PA00X+047052Y+140850X0160Y         S0      
317GND              VIA   -    MD0080PA00X+047052Y+139658X0160Y         S0      
317GND              VIA   -    MD0080PA00X+045828Y+140850X0160Y         S0      
317GND              VIA   -    MD0080PA00X+045828Y+139658X0160Y         S0      
317GND              VIA   -    MD0100PA00X+046410Y+139908X0180Y         S0      
317GND              VIA   -    MD0100PA00X+046410Y+140600X0180Y         S0      
317GND              VIA   -    MD0100PA00X+046906Y+139409X0180Y         S0      
317GND              VIA   -    MD0100PA00X+046410Y+139409X0180Y         S0      
317GND              VIA   -    MD0100PA00X+046906Y+139908X0180Y         S0      
317GND              VIA   -    MD0100PA00X+046410Y+138679X0180Y         S0      
317GND              VIA   -    MD0100PA00X+046906Y+138180X0180Y         S0      
317GND              VIA   -    MD0100PA00X+046906Y+138679X0180Y         S0      
317GND              VIA   -    MD0100PA00X+047634Y+138180X0180Y         S0      
317GND              VIA   -    MD0100PA00X+047634Y+138679X0180Y         S0      
317GND              VIA   -    MD0100PA00X+046410Y+138180X0180Y         S0      
317GND              VIA   -    MD0100PA00X+048877Y+149662X0180Y         S0      
317GND              VIA   -    MD0100PA00X+048011Y+148560X0180Y         S0      
317GND              VIA   -    MD0100PA00X+048011Y+149149X0200Y         S0      
317GND              VIA   -    MD0100PA00X+048877Y+149189X0180Y         S0      
317GND              VIA   -    MD0100PA00X+048877Y+148716X0200Y         S0      
317GND              VIA   -    MD0100PA00X+048011Y+149622X0180Y         S0      
317GND              VIA   -    MD0100PA00X+048011Y+148087X0180Y         S0      
317GND              VIA   -    MD0100PA00X+048877Y+148127X0180Y         S0      
317GND              VIA   -    MD0100PA00X+048877Y+147654X0180Y         S0      
317GND              VIA   -    MD0100PA00X+048877Y+147180X0200Y         S0      
317GND              VIA   -    MD0100PA00X+048011Y+147024X0180Y         S0      
317GND              VIA   -    MD0100PA00X+048011Y+147614X0200Y         S0      
317GND              VIA   -    MD0100PA00X+048877Y+146118X0180Y         S0      
317GND              VIA   -    MD0100PA00X+048877Y+146591X0180Y         S0      
317GND              VIA   -    MD0100PA00X+048011Y+146551X0180Y         S0      
317GND              VIA   -    MD0100PA00X+048011Y+146078X0200Y         S0      
317GND              VIA   -    MD0100PA00X+048011Y+159385X0200Y         S0      
317GND              VIA   -    MD0100PA00X+048877Y+159425X0180Y         S0      
317GND              VIA   -    MD0100PA00X+048011Y+158796X0180Y         S0      
317GND              VIA   -    MD0100PA00X+048011Y+158323X0180Y         S0      
317GND              VIA   -    MD0100PA00X+048877Y+158363X0180Y         S0      
317GND              VIA   -    MD0100PA00X+048877Y+158952X0200Y         S0      
317GND              VIA   -    MD0100PA00X+048011Y+157261X0180Y         S0      
317GND              VIA   -    MD0100PA00X+048011Y+156788X0180Y         S0      
317GND              VIA   -    MD0100PA00X+048877Y+156354X0180Y         S0      
317GND              VIA   -    MD0100PA00X+048877Y+156828X0180Y         S0      
317GND              VIA   -    MD0100PA00X+048877Y+157417X0200Y         S0      
317GND              VIA   -    MD0100PA00X+048011Y+157850X0200Y         S0      
317GND              VIA   -    MD0100PA00X+048877Y+157890X0180Y         S0      
317GND              VIA   -    MD0100PA00X+048011Y+156314X0200Y         S0      
317GND              VIA   -    MD0100PA00X+048877Y+155881X0200Y         S0      
317GND              VIA   -    MD0100PA00X+048011Y+151631X0180Y         S0      
317GND              VIA   -    MD0100PA00X+048877Y+150724X0180Y         S0      
317GND              VIA   -    MD0100PA00X+048877Y+150251X0200Y         S0      
317GND              VIA   -    MD0100PA00X+048011Y+150095X0180Y         S0      
317GND              VIA   -    MD0100PA00X+048011Y+150684X0200Y         S0      
317GND              VIA   -    MD0100PA00X+048011Y+151158X0180Y         S0      
317GND              VIA   -    MD0100PA00X+048877Y+151198X0180Y         S0      
317GND              VIA   -    MD0100PA00X+050657Y+100477X0200Y         S0      
327GND              C200  -1          A01X+050417Y+100477X0198Y0197R180 S1      
317GND              VIA   -    MD0100PA00X+050657Y+100077X0200Y         S0      
327GND              C199  -2          A01X+050417Y+100077X0198Y0197     S1      
317GND              VIA   -    MD0100PA00X+049305Y+097608X0200Y         S0      
317GND              VIA   -    MD0100PA00X+049960Y+096396X0200Y         S0      
317GND              VIA   -    MD0100PA00X+049964Y+086154X0200Y         S0      
317GND              VIA   -    MD0100PA00X+049747Y+083303X0200Y         S0      
327GND              U105  -2          A18X+050127Y+083303X0140Y0440R270 S2      
317GND              VIA   -    MD0100PA00X+050374Y+084683X0200Y         S0      
327GND              C2609 -1          A01X+050617Y+084465X0198Y0197     S1      
327GND              U107  -2          A18X+049995Y+084683X0140Y0440R270 S2      
317GND              VIA   -    MD0100PA00X+049280Y+084649X0200Y         S0      
317GND              VIA   -    MD0100PA00X+050625Y+082469X0200Y         S0      
317GND              VIA   -    MD0100PA00X+049166Y+082917X0200Y         S0      
317GND              VIA   -    MD0100PA00X+050434Y+081204X0200Y         S0      
317GND              VIA   -    MD0100PA00X+048011Y+161867X0180Y         S0      
317GND              VIA   -    MD0100PA00X+048011Y+161394X0180Y         S0      
317GND              VIA   -    MD0100PA00X+048877Y+161434X0180Y         S0      
317GND              VIA   -    MD0100PA00X+048011Y+160332X0180Y         S0      
317GND              VIA   -    MD0100PA00X+048011Y+159858X0180Y         S0      
317GND              VIA   -    MD0100PA00X+048011Y+160921X0200Y         S0      
317GND              VIA   -    MD0100PA00X+048877Y+159898X0180Y         S0      
317GND              VIA   -    MD0100PA00X+048877Y+160488X0200Y         S0      
317GND              VIA   -    MD0100PA00X+048877Y+160961X0180Y         S0      
317GND              VIA   -    MD0100PA00X+050256Y+115521X0200Y         S0      
317GND              VIA   -    MD0100PA00X+050256Y+115271X0200Y         S0      
317GND              VIA   -    MD0100PA00X+049492Y+114194X0200Y         S0      
317GND              VIA   -    MD0100PA00X+049492Y+114444X0200Y         S0      
317GND              VIA   -    MD0100PA00X+049492Y+114694X0200Y         S0      
317GND              VIA   -    MD0100PA00X+050132Y+114194X0200Y         S0      
317GND              VIA   -    MD0100PA00X+050132Y+114694X0200Y         S0      
317GND              VIA   -    MD0100PA00X+050132Y+114444X0200Y         S0      
317GND              VIA   -    MD0100PA00X+050382Y+114194X0200Y         S0      
317GND              VIA   -    MD0100PA00X+050382Y+114694X0200Y         S0      
317GND              VIA   -    MD0100PA00X+050382Y+114444X0200Y         S0      
317GND              VIA   -    MD0100PA00X+049492Y+113194X0200Y         S0      
317GND              VIA   -    MD0100PA00X+049492Y+113944X0200Y         S0      
317GND              VIA   -    MD0100PA00X+049492Y+113444X0200Y         S0      
317GND              VIA   -    MD0100PA00X+049492Y+113694X0200Y         S0      
317GND              VIA   -    MD0100PA00X+050132Y+113194X0200Y         S0      
317GND              VIA   -    MD0100PA00X+050132Y+113444X0200Y         S0      
317GND              VIA   -    MD0100PA00X+050132Y+113694X0200Y         S0      
317GND              VIA   -    MD0100PA00X+050132Y+113944X0200Y         S0      
317GND              VIA   -    MD0100PA00X+050382Y+113194X0200Y         S0      
317GND              VIA   -    MD0100PA00X+050382Y+113444X0200Y         S0      
317GND              VIA   -    MD0100PA00X+050382Y+113694X0200Y         S0      
317GND              VIA   -    MD0100PA00X+050382Y+113944X0200Y         S0      
317GND              VIA   -    MD0100PA00X+050785Y+112930X0200Y         S0      
317GND              VIA   -    MD0100PA00X+050535Y+112930X0200Y         S0      
317GND              VIA   -    MD0100PA00X+050695Y+112580X0200Y         S0      
317GND              VIA   -    MD0100PA00X+050695Y+112310X0200Y         S0      
317GND              VIA   -    MD0100PA00X+050657Y+103077X0200Y         S0      
327GND              C832  -1          A01X+050417Y+103077X0198Y0197R180 S1      
317GND              VIA   -    MD0100PA00X+050657Y+101627X0200Y         S0      
327GND              C833  -2   M      A01X+050417Y+101627X0198Y0197     S1      
317GND              VIA   -    MD0100PA00X+048130Y+137488X0180Y         S0      
317GND              VIA   -    MD0100PA00X+048130Y+136989X0180Y         S0      
317GND              VIA   -    MD0100PA00X+048858Y+136989X0180Y         S0      
317GND              VIA   -    MD0100PA00X+049354Y+136989X0180Y         S0      
317GND              VIA   -    MD0100PA00X+049354Y+137488X0180Y         S0      
317GND              VIA   -    MD0100PA00X+048858Y+137488X0180Y         S0      
317GND              VIA   -    MD0100PA00X+049382Y+121212X0200Y         S0      
317GND              VIA   -    MD0100PA00X+049382Y+120962X0200Y         S0      
317GND              VIA   -    MD0100PA00X+049382Y+120712X0200Y         S0      
317GND              VIA   -    MD0100PA00X+050645Y+120940X0200Y         S0      
317GND              VIA   -    MD0100PA00X+050645Y+121190X0200Y         S0      
317GND              VIA   -    MD0100PA00X+050645Y+120690X0200Y         S0      
317GND              VIA   -    MD0100PA00X+049614Y+119832X0200Y         S0      
317GND              VIA   -    MD0100PA00X+049614Y+120082X0200Y         S0      
317GND              VIA   -    MD0100PA00X+049382Y+120462X0200Y         S0      
317GND              VIA   -    MD0100PA00X+050414Y+120082X0200Y    R180 S0      
317GND              VIA   -    MD0100PA00X+050414Y+119832X0200Y    R180 S0      
317GND              VIA   -    MD0100PA00X+050645Y+120440X0200Y         S0      
317GND              VIA   -    MD0100PA00X+049354Y+141099X0180Y         S0      
317GND              VIA   -    MD0100PA00X+048130Y+141099X0180Y         S0      
317GND              VIA   -    MD0100PA00X+048858Y+141099X0180Y         S0      
317GND              VIA   -    MD0080PA00X+048276Y+139658X0160Y         S0      
317GND              VIA   -    MD0080PA00X+048276Y+140850X0160Y         S0      
317GND              VIA   -    MD0100PA00X+048858Y+139908X0180Y         S0      
317GND              VIA   -    MD0100PA00X+048858Y+140600X0180Y         S0      
317GND              VIA   -    MD0100PA00X+048130Y+139409X0180Y         S0      
317GND              VIA   -    MD0100PA00X+048858Y+139409X0180Y         S0      
317GND              VIA   -    MD0100PA00X+047634Y+139908X0180Y         S0      
317GND              VIA   -    MD0100PA00X+047634Y+140600X0180Y         S0      
317GND              VIA   -    MD0100PA00X+047634Y+139409X0180Y         S0      
317GND              VIA   -    MD0100PA00X+049354Y+139908X0180Y         S0      
317GND              VIA   -    MD0100PA00X+049354Y+140600X0180Y         S0      
317GND              VIA   -    MD0100PA00X+049354Y+139409X0180Y         S0      
317GND              VIA   -    MD0100PA00X+048130Y+139908X0180Y         S0      
317GND              VIA   -    MD0100PA00X+048130Y+140600X0180Y         S0      
317GND              VIA   -    MD0100PA00X+048130Y+138679X0180Y         S0      
317GND              VIA   -    MD0100PA00X+048130Y+138180X0180Y         S0      
317GND              VIA   -    MD0100PA00X+049354Y+138180X0180Y         S0      
317GND              VIA   -    MD0100PA00X+049354Y+138679X0180Y         S0      
317GND              VIA   -    MD0100PA00X+048858Y+138180X0180Y         S0      
317GND              VIA   -    MD0100PA00X+048858Y+138679X0180Y         S0      
317GND              VIA   -    MD0100PA00X+050609Y+155881X0200Y         S0      
317GND              VIA   -    MD0100PA00X+049743Y+156314X0200Y         S0      
317GND              VIA   -    MD0100PA00X+049743Y+151631X0180Y         S0      
317GND              VIA   -    MD0100PA00X+049743Y+151158X0180Y         S0      
317GND              VIA   -    MD0100PA00X+050609Y+150724X0180Y         S0      
317GND              VIA   -    MD0100PA00X+050609Y+150251X0200Y         S0      
317GND              VIA   -    MD0100PA00X+049743Y+150095X0180Y         S0      
317GND              VIA   -    MD0100PA00X+049743Y+150684X0200Y         S0      
317GND              VIA   -    MD0100PA00X+050609Y+151198X0180Y         S0      
317GND              VIA   -    MD0100PA00X+050609Y+149662X0180Y         S0      
317GND              VIA   -    MD0100PA00X+050609Y+149189X0180Y         S0      
317GND              VIA   -    MD0100PA00X+050609Y+148716X0200Y         S0      
317GND              VIA   -    MD0100PA00X+049743Y+148560X0180Y         S0      
317GND              VIA   -    MD0100PA00X+049743Y+149149X0200Y         S0      
317GND              VIA   -    MD0100PA00X+049743Y+149622X0180Y         S0      
317GND              VIA   -    MD0100PA00X+050609Y+147654X0180Y         S0      
317GND              VIA   -    MD0100PA00X+050609Y+147180X0200Y         S0      
317GND              VIA   -    MD0100PA00X+049743Y+147024X0180Y         S0      
317GND              VIA   -    MD0100PA00X+049743Y+147614X0200Y         S0      
317GND              VIA   -    MD0100PA00X+050609Y+148127X0180Y         S0      
317GND              VIA   -    MD0100PA00X+049743Y+148087X0180Y         S0      
317GND              VIA   -    MD0100PA00X+050609Y+146118X0180Y         S0      
317GND              VIA   -    MD0100PA00X+049743Y+146078X0200Y         S0      
317GND              VIA   -    MD0100PA00X+050609Y+146591X0180Y         S0      
317GND              VIA   -    MD0100PA00X+049743Y+146551X0180Y         S0      
317GND              VIA   -    MD0100PA00X+047634Y+141099X0180Y         S0      
317GND              VIA   -    MD0100PA00X+049200Y+164498X0200Y         S0      
317GND              VIA   -    MD0100PA00X+050609Y+161434X0180Y         S0      
317GND              VIA   -    MD0100PA00X+049743Y+161867X0180Y         S0      
317GND              VIA   -    MD0100PA00X+049743Y+161394X0180Y         S0      
317GND              VIA   -    MD0100PA00X+049743Y+160332X0180Y         S0      
317GND              VIA   -    MD0100PA00X+049743Y+159858X0180Y         S0      
317GND              VIA   -    MD0100PA00X+050609Y+160961X0180Y         S0      
317GND              VIA   -    MD0100PA00X+049743Y+160921X0200Y         S0      
317GND              VIA   -    MD0100PA00X+050609Y+159898X0180Y         S0      
317GND              VIA   -    MD0100PA00X+050609Y+160488X0200Y         S0      
317GND              VIA   -    MD0100PA00X+049743Y+158323X0180Y         S0      
317GND              VIA   -    MD0100PA00X+050609Y+159425X0180Y         S0      
317GND              VIA   -    MD0100PA00X+049743Y+159385X0200Y         S0      
317GND              VIA   -    MD0100PA00X+050609Y+158363X0180Y         S0      
317GND              VIA   -    MD0100PA00X+050609Y+158952X0200Y         S0      
317GND              VIA   -    MD0100PA00X+049743Y+158796X0180Y         S0      
317GND              VIA   -    MD0100PA00X+050609Y+156354X0180Y         S0      
317GND              VIA   -    MD0100PA00X+050609Y+156828X0180Y         S0      
317GND              VIA   -    MD0100PA00X+050609Y+157417X0200Y         S0      
317GND              VIA   -    MD0100PA00X+049743Y+157261X0180Y         S0      
317GND              VIA   -    MD0100PA00X+049743Y+156788X0180Y         S0      
317GND              VIA   -    MD0100PA00X+050609Y+157890X0180Y         S0      
317GND              VIA   -    MD0100PA00X+049743Y+157850X0200Y         S0      
317GND              VIA   -    MD0100PA00X+051590Y+111942X0193Y    R180 S0      
317GND              VIA   -    MD0100PA00X+051590Y+111382X0193Y    R180 S0      
317GND              VIA   -    MD0100PA00X+052086Y+111942X0193Y    R180 S0      
317GND              VIA   -    MD0100PA00X+051745Y+112310X0200Y         S0      
317GND              VIA   -    MD0100PA00X+051495Y+112310X0200Y         S0      
317GND              VIA   -    MD0100PA00X+052289Y+109877X0200Y         S0      
317GND              VIA   -    MD0100PA00X+051583Y+109307X0200Y    R180 S0      
317GND              VIA   -    MD0100PA00X+051245Y+109843X0200Y         S0      
317GND              VIA   -    MD0100PA00X+051770Y+109852X0200Y         S0      
317GND              VIA   -    MD0100PA00X+051583Y+109057X0200Y    R180 S0      
317GND              VIA   -    MD0100PA00X+051979Y+103127X0200Y         S0      
317GND              VIA   -    MD0100PA00X+051489Y+095219X0200Y         S0      
317GND              VIA   -    M      A01X+052448Y+095229X0200Y    R090 S2      
017GND              VIA   -    M      A18X+052448Y+095229X0260Y    R090 S2      
017GND                    -    MD0100PA00X+052448Y+095229                       
317GND              VIA   -    MD0100PA00X+051626Y+093916X0200Y         S0      
317GND              VIA   -    MD0100PA00X+050967Y+090030X0200Y         S0      
317GND              VIA   -    M      A01X+051102Y+091144X0200Y         S2      
017GND              VIA   -    M      A18X+051102Y+091144X0260Y         S2      
017GND                    -    MD0100PA00X+051102Y+091144                       
317GND              VIA   -    MD0100PA00X+052112Y+089750X0200Y         S0      
317GND              VIA   -    MD0100PA00X+050943Y+088839X0200Y         S0      
317GND              VIA   -    MD0100PA00X+052327Y+088007X0200Y         S0      
327GND              R3459 -2          A18X+052068Y+088007X0198Y0197R090 S2      
317GND              VIA   -    MD0100PA00X+050805Y+087779X0200Y         S0      
317GND              VIA   -    MD0100PA00X+051783Y+083456X0200Y         S0      
327GND              C2611 -1          A18X+051783Y+083166X0198Y0197     S2      
317GND              VIA   -    MD0100PA00X+052072Y+084613X0200Y         S0      
317GND              VIA   -    MD0100PA00X+052156Y+082093X0200Y         S0      
327GND              C2603 -2          A18X+052574Y+082107X0198Y0197R090 S2      
317GND              VIA   -    MD0100PA00X+052118Y+081400X0200Y         S0      
327GND              C2586 -2          A18X+052374Y+081655X0280Y0320     S2      
327GND              C2592 -2          A18X+052524Y+079357X0198Y0197R090 S2      
317GND              VIA   -    MD0100PA00X+050578Y+134569X0180Y         S0      
317GND              VIA   -    MD0100PA00X+051802Y+134569X0180Y         S0      
317GND              VIA   -    MD0100PA00X+051306Y+135068X0180Y         S0      
317GND              VIA   -    MD0100PA00X+050578Y+135068X0180Y         S0      
317GND              VIA   -    MD0100PA00X+051802Y+135068X0180Y         S0      
317GND              VIA   -    MD0080PA00X+050724Y+134819X0160Y         S0      
317GND              VIA   -    MD0100PA00X+050082Y+134569X0180Y         S0      
317GND              VIA   -    MD0100PA00X+050082Y+135068X0180Y         S0      
317GND              VIA   -    MD0100PA00X+052075Y+121212X0200Y         S0      
317GND              VIA   -    MD0100PA00X+052075Y+120962X0200Y         S0      
317GND              VIA   -    MD0100PA00X+052075Y+120712X0200Y         S0      
317GND              VIA   -    MD0100PA00X+052307Y+119832X0200Y         S0      
317GND              VIA   -    MD0100PA00X+052307Y+120082X0200Y         S0      
317GND              VIA   -    MD0100PA00X+052075Y+120462X0200Y         S0      
317GND              VIA   -    MD0100PA00X+050881Y+115521X0200Y         S0      
317GND              VIA   -    MD0100PA00X+050881Y+115271X0200Y         S0      
317GND              VIA   -    MD0100PA00X+051821Y+115271X0200Y         S0      
317GND              VIA   -    MD0100PA00X+051821Y+115521X0200Y         S0      
317GND              VIA   -    MD0100PA00X+052035Y+112930X0200Y         S0      
317GND              VIA   -    MD0100PA00X+052285Y+112580X0200Y         S0      
317GND              VIA   -    MD0100PA00X+052035Y+112580X0200Y         S0      
317GND              VIA   -    MD0100PA00X+051785Y+112930X0200Y         S0      
317GND              VIA   -    MD0100PA00X+051535Y+112930X0200Y         S0      
317GND              VIA   -    MD0100PA00X+051285Y+112930X0200Y         S0      
317GND              VIA   -    MD0100PA00X+051035Y+112930X0200Y         S0      
317GND              VIA   -    MD0100PA00X+051785Y+112580X0200Y         S0      
317GND              VIA   -    MD0100PA00X+051535Y+112580X0200Y         S0      
317GND              VIA   -    MD0100PA00X+052285Y+112930X0200Y         S0      
327GND              PU10  -7_9-M      A01X+051493Y+112618X0827Y2126R270 S1      
317GND              VIA   -    MD0100PA00X+052086Y+111382X0193Y    R180 S0      
317GND              VIA   -    MD0100PA00X+051838Y+111942X0193Y    R180 S0      
317GND              VIA   -    MD0100PA00X+051838Y+111382X0193Y    R180 S0      
327GND              PU10  -40  M      A01X+051837Y+111663X0690Y0770R180 S1      
317GND              VIA   -    MD0100PA00X+050578Y+139409X0180Y         S0      
317GND              VIA   -    MD0100PA00X+051306Y+139908X0180Y         S0      
317GND              VIA   -    MD0100PA00X+051306Y+140600X0180Y         S0      
317GND              VIA   -    MD0100PA00X+051306Y+139409X0180Y         S0      
317GND              VIA   -    MD0100PA00X+050082Y+139908X0180Y         S0      
317GND              VIA   -    MD0100PA00X+050082Y+140600X0180Y         S0      
317GND              VIA   -    MD0100PA00X+050578Y+139908X0180Y         S0      
317GND              VIA   -    MD0100PA00X+050578Y+140600X0180Y         S0      
317GND              VIA   -    MD0100PA00X+050082Y+139409X0180Y         S0      
317GND              VIA   -    MD0080PA00X+049500Y+139658X0160Y         S0      
317GND              VIA   -    MD0080PA00X+049500Y+140850X0160Y         S0      
317GND              VIA   -    MD0080PA00X+050724Y+139658X0160Y         S0      
317GND              VIA   -    MD0080PA00X+050724Y+140850X0160Y         S0      
317GND              VIA   -    MD0100PA00X+050082Y+135760X0180Y         S0      
317GND              VIA   -    MD0100PA00X+050082Y+136260X0180Y         S0      
317GND              VIA   -    MD0100PA00X+051802Y+136260X0180Y         S0      
317GND              VIA   -    MD0100PA00X+051306Y+135760X0180Y         S0      
317GND              VIA   -    MD0100PA00X+051306Y+136260X0180Y         S0      
317GND              VIA   -    MD0100PA00X+050578Y+135760X0180Y         S0      
317GND              VIA   -    MD0100PA00X+050578Y+136260X0180Y         S0      
317GND              VIA   -    MD0100PA00X+051802Y+135760X0180Y         S0      
317GND              VIA   -    MD0080PA00X+050724Y+136010X0160Y         S0      
317GND              VIA   -    MD0100PA00X+051306Y+134569X0180Y         S0      
317GND              VIA   -    MD0100PA00X+051476Y+149622X0180Y         S0      
317GND              VIA   -    MD0100PA00X+051476Y+148560X0180Y         S0      
317GND              VIA   -    MD0100PA00X+051476Y+149149X0200Y         S0      
317GND              VIA   -    MD0100PA00X+051476Y+147024X0180Y         S0      
317GND              VIA   -    MD0100PA00X+051476Y+147614X0200Y         S0      
317GND              VIA   -    MD0100PA00X+051476Y+148087X0180Y         S0      
317GND              VIA   -    MD0100PA00X+051476Y+146551X0180Y         S0      
317GND              VIA   -    MD0100PA00X+051476Y+146078X0200Y         S0      
317GND              VIA   -    MD0100PA00X+051306Y+141099X0180Y         S0      
317GND              VIA   -    MD0100PA00X+050082Y+141099X0180Y         S0      
317GND              VIA   -    MD0100PA00X+050578Y+141099X0180Y         S0      
317GND              VIA   -    MD0100PA00X+051476Y+161867X0180Y         S0      
317GND              VIA   -    MD0100PA00X+051476Y+161394X0180Y         S0      
317GND              VIA   -    MD0100PA00X+051476Y+159858X0180Y         S0      
317GND              VIA   -    MD0100PA00X+051476Y+160921X0200Y         S0      
317GND              VIA   -    MD0100PA00X+051476Y+160332X0180Y         S0      
317GND              VIA   -    MD0100PA00X+051476Y+158796X0180Y         S0      
317GND              VIA   -    MD0100PA00X+051476Y+158323X0180Y         S0      
317GND              VIA   -    MD0100PA00X+051476Y+159385X0200Y         S0      
317GND              VIA   -    MD0100PA00X+051476Y+157850X0200Y         S0      
317GND              VIA   -    MD0100PA00X+051476Y+157261X0180Y         S0      
317GND              VIA   -    MD0100PA00X+051476Y+156788X0180Y         S0      
317GND              VIA   -    MD0100PA00X+051476Y+156314X0200Y         S0      
317GND              VIA   -    MD0100PA00X+051476Y+151631X0180Y         S0      
317GND              VIA   -    MD0100PA00X+051476Y+150095X0180Y         S0      
317GND              VIA   -    MD0100PA00X+051476Y+150684X0200Y         S0      
317GND              VIA   -    MD0100PA00X+051476Y+151158X0180Y         S0      
317GND              VIA   -    MD0100PA00X+050947Y+098161X0200Y    R090 S0      
317GND              VIA   -    MD0100PA00X+052735Y+091146X0200Y         S0      
317GND              VIA   -    MD0100PA00X+052887Y+087368X0200Y    R090 S0      
327GND              C2307 -1          A18X+052887Y+087661X0198Y0197     S2      
317GND              VIA   -    MD0100PA00X+053664Y+083865X0200Y    R270 S0      
327GND              U98   -47         A01X+053664Y+083440X0110Y0540     S1      
317GND              VIA   -    MD0100PA00X+052773Y+084703X0200Y         S0      
317GND              VIA   -    MD0100PA00X+053131Y+082269X0200Y         S0      
327GND              U98   -51         A01X+052690Y+082269X0110Y0540R090 S1      
327GND              C2593 -2          A18X+053424Y+082257X0198Y0197R090 S2      
317GND              VIA   -    MD0100PA00X+053167Y+081572X0200Y         S0      
327GND              C2585 -2          A18X+052874Y+081572X0198Y0197R270 S2      
327GND              C2602 -2          A18X+053230Y+079789X0280Y0320R090 S2      
327GND              U98   -1   M      A01X+053467Y+078933X0110Y0540     S1      
317GND              VIA   -    MD0100PA00X+051200Y+164498X0200Y         S0      
317GND              VIA   -    MD0100PA00X+053754Y+136260X0180Y         S0      
317GND              VIA   -    MD0100PA00X+053026Y+135760X0180Y         S0      
317GND              VIA   -    MD0100PA00X+052530Y+135760X0180Y         S0      
317GND              VIA   -    MD0100PA00X+053026Y+136260X0180Y         S0      
317GND              VIA   -    MD0100PA00X+052530Y+136260X0180Y         S0      
317GND              VIA   -    MD0100PA00X+053754Y+135760X0180Y         S0      
317GND              VIA   -    MD0100PA00X+053754Y+134569X0180Y         S0      
317GND              VIA   -    MD0100PA00X+053026Y+135068X0180Y         S0      
317GND              VIA   -    MD0100PA00X+052530Y+135068X0180Y         S0      
317GND              VIA   -    MD0100PA00X+053754Y+135068X0180Y         S0      
317GND              VIA   -    MD0100PA00X+053026Y+134569X0180Y         S0      
317GND              VIA   -    MD0100PA00X+052530Y+134569X0180Y         S0      
317GND              VIA   -    MD0100PA00X+052705Y+114194X0200Y         S0      
317GND              VIA   -    MD0100PA00X+052705Y+114444X0200Y         S0      
317GND              VIA   -    MD0100PA00X+052705Y+114694X0200Y         S0      
317GND              VIA   -    MD0100PA00X+052827Y+115268X0200Y         S0      
317GND              VIA   -    MD0100PA00X+052705Y+113694X0200Y         S0      
317GND              VIA   -    MD0100PA00X+052705Y+113444X0200Y         S0      
317GND              VIA   -    MD0100PA00X+052705Y+113944X0200Y         S0      
317GND              VIA   -    MD0100PA00X+052705Y+113194X0200Y         S0      
317GND              VIA   -    MD0100PA00X+054574Y+080415X0200Y         S0      
327GND              R917  -2          A18X+054574Y+080172X0198Y0197R270 S2      
317GND              VIA   -    MD0100PA00X+055387Y+081130X0200Y         S0      
327GND              U98   -11         A01X+055436Y+078933X0110Y0540     S1      
327GND              U98   -10         A01X+055239Y+078933X0110Y0540     S1      
327GND              U98   -5   M      A01X+054255Y+078933X0110Y0540     S1      
317GND              VIA   -    MD0100PA00X+053200Y+164498X0200Y         S0      
317GND              VIA   -    MD0100PA00X+052530Y+141099X0180Y         S0      
317GND              VIA   -    MD0100PA00X+053026Y+141099X0180Y         S0      
317GND              VIA   -    MD0100PA00X+051802Y+141099X0180Y         S0      
317GND              VIA   -    MD0100PA00X+051802Y+139908X0180Y         S0      
317GND              VIA   -    MD0100PA00X+051802Y+140600X0180Y         S0      
317GND              VIA   -    MD0100PA00X+052530Y+139908X0180Y         S0      
317GND              VIA   -    MD0100PA00X+052530Y+140600X0180Y         S0      
317GND              VIA   -    MD0100PA00X+051802Y+139409X0180Y         S0      
317GND              VIA   -    MD0100PA00X+052530Y+139409X0180Y         S0      
317GND              VIA   -    MD0080PA00X+051948Y+140850X0160Y         S0      
317GND              VIA   -    MD0080PA00X+051948Y+139658X0160Y         S0      
317GND              VIA   -    MD0100PA00X+053026Y+139908X0180Y         S0      
317GND              VIA   -    MD0100PA00X+053026Y+140600X0180Y         S0      
317GND              VIA   -    MD0100PA00X+053026Y+139409X0180Y         S0      
317GND              VIA   -    MD0100PA00X+055474Y+135068X0180Y         S0      
317GND              VIA   -    MD0100PA00X+054978Y+135068X0180Y         S0      
317GND              VIA   -    MD0100PA00X+054250Y+135068X0180Y         S0      
317GND              VIA   -    MD0100PA00X+054978Y+134560X0180Y         S0      
317GND              VIA   -    MD0100PA00X+054250Y+134569X0180Y         S0      
317GND              VIA   -    MD0100PA00X+055474Y+134560X0180Y         S0      
317GND              VIA   -    M      A01X+055768Y+103509X0200Y         S2      
017GND              VIA   -    M      A18X+055768Y+103509X0260Y         S2      
017GND                    -    MD0100PA00X+055768Y+103509                       
317GND              VIA   -    MD0100PA00X+054177Y+101837X0200Y         S0      
327GND              Q14   -1          A01X+054177Y+101517X0240Y0240R270 S1      
317GND              VIA   -    MD0100PA00X+055292Y+099786X0200Y         S0      
327GND              R1298 -1          A01X+055292Y+099511X0198Y0197R270 S1      
317GND              VIA   -    MD0100PA00X+054822Y+100656X0200Y         S0      
327GND              Q14   -4          A01X+054885Y+100926X0240Y0240R270 S1      
317GND              VIA   -    MD0100PA00X+054479Y+089922X0200Y         S0      
327GND              U66   -8          A18X+054347Y+090483X0140Y0610R180 S2      
317GND              VIA   -    MD0100PA00X+054514Y+090902X0200Y         S0      
317GND              VIA   -    MD0100PA00X+054852Y+087486X0200Y         S0      
317GND              VIA   -    MD0100PA00X+054852Y+087786X0200Y         S0      
317GND              VIA   -    MD0100PA00X+054524Y+085032X0200Y         S0      
317GND              VIA   -    MD0100PA00X+054924Y+084139X0200Y         S0      
327GND              C2595 -2          A01X+055255Y+084139X0198Y0197R180 S1      
317GND              VIA   -    MD0100PA00X+054598Y+084639X0200Y         S0      
327GND              C2596 -2          A01X+054930Y+084639X0280Y0320R090 S1      
317GND              VIA   -    MD0100PA00X+054113Y+083886X0200Y         S0      
327GND              C2588 -2          A18X+054113Y+083539X0198Y0197     S2      
317GND              VIA   -    MD0100PA00X+054113Y+082834X0200Y         S0      
327GND              C2587 -2          A18X+054113Y+083089X0198Y0197     S2      
317GND              VIA   -    MD0100PA00X+054081Y+081656X0200Y         S0      
317GND              VIA   -    MD0100PA00X+054846Y+082316X0200Y         S0      
317GND              VIA   -    MD0100PA00X+053754Y+139409X0180Y         S0      
317GND              VIA   -    MD0100PA00X+054250Y+139409X0180Y         S0      
317GND              VIA   -    MD0100PA00X+054978Y+139908X0180Y         S0      
317GND              VIA   -    MD0100PA00X+054978Y+140600X0180Y         S0      
317GND              VIA   -    MD0100PA00X+054978Y+139399X0180Y         S0      
317GND              VIA   -    MD0100PA00X+053754Y+139908X0180Y         S0      
317GND              VIA   -    MD0100PA00X+053754Y+140600X0180Y         S0      
317GND              VIA   -    MD0100PA00X+054250Y+139908X0180Y         S0      
317GND              VIA   -    MD0100PA00X+054250Y+140600X0180Y         S0      
317GND              VIA   -    MD0080PA00X+053172Y+139658X0160Y         S0      
317GND              VIA   -    MD0080PA00X+053172Y+140850X0160Y         S0      
317GND              VIA   -    MD0080PA00X+054396Y+140850X0160Y         S0      
317GND              VIA   -    MD0080PA00X+054396Y+139658X0160Y         S0      
317GND              VIA   -    MD0100PA00X+054978Y+135760X0180Y         S0      
317GND              VIA   -    MD0100PA00X+054250Y+135760X0180Y         S0      
317GND              VIA   -    MD0100PA00X+054978Y+136260X0180Y         S0      
317GND              VIA   -    MD0100PA00X+054250Y+136260X0180Y         S0      
317GND              VIA   -    MD0100PA00X+055474Y+135760X0180Y         S0      
317GND              VIA   -    MD0100PA00X+055474Y+136260X0180Y         S0      
317GND              VIA   -    MD0100PA00X+056958Y+088691X0200Y         S0      
317GND              VIA   -    MD0100PA00X+055920Y+084630X0200Y         S0      
327GND              C2610 -1          A18X+055824Y+084372X0198Y0197R090 S2      
317GND              VIA   -    MD0100PA00X+057217Y+084235X0200Y         S0      
317GND              VIA   -    MD0100PA00X+055974Y+082215X0200Y         S0      
327GND              U106  -2          A18X+055824Y+082621X0140Y0440     S2      
317GND              VIA   -    MD0100PA00X+056732Y+082772X0200Y         S0      
327GND              C2590 -2          A18X+057024Y+082772X0198Y0197R270 S2      
317GND              VIA   -    MD0100PA00X+056026Y+082999X0200Y    R270 S0      
327GND              U98   -35         A01X+056026Y+083440X0110Y0540     S1      
317GND              VIA   -    MD0100PA00X+056310Y+082994X0200Y         S0      
317GND              VIA   -    MD0100PA00X+056106Y+080361X0200Y         S0      
327GND              C2600 -2          A18X+055760Y+080139X0280Y0320R270 S2      
317GND              VIA   -    MD0100PA00X+056732Y+080622X0200Y         S0      
327GND              C2589 -2          A18X+057024Y+080622X0198Y0197R270 S2      
317GND              VIA   -    MD0100PA00X+056756Y+081285X0200Y    R180 S0      
327GND              U98   -25         A01X+057198Y+081285X0110Y0540R090 S1      
317GND              VIA   -    MD0100PA00X+056140Y+081124X0200Y         S0      
327GND              C2599 -2          A18X+055528Y+079639X0198Y0197R180 S2      
327GND              U98   -15         A01X+056223Y+078933X0110Y0540     S1      
327GND              U98   -13         A01X+055829Y+078933X0110Y0540     S1      
317GND              VIA   -    MD0100PA00X+055200Y+164498X0200Y         S0      
317GND              VIA   -    MD0100PA00X+054978Y+141099X0180Y         S0      
317GND              VIA   -    MD0100PA00X+053754Y+141099X0180Y         S0      
317GND              VIA   -    MD0100PA00X+054250Y+141099X0180Y         S0      
317GND              VIA   -    M      A01X+056650Y+120210X0200Y         S2      
017GND              VIA   -    M      A18X+056650Y+120210X0260Y         S2      
017GND                    -    MD0100PA00X+056650Y+120210                       
327GND              R1319 -1          A01X+056945Y+120505X0198Y0197R045 S1      
317GND              VIA   -    MD0100PA00X+056367Y+120493X0200Y    R315 S0      
327GND              R1282 -1          A01X+056662Y+120788X0198Y0197R045 S1      
317GND              VIA   -    MD0100PA00X+056952Y+117769X0200Y         S0      
317GND              VIA   -    MD0100PA00X+056602Y+117769X0200Y         S0      
317GND              VIA   -    MD0100PA00X+056021Y+117769X0200Y         S0      
317GND              VIA   -    MD0100PA00X+056952Y+116509X0200Y         S0      
317GND              VIA   -    M      A01X+056021Y+116509X0200Y         S2      
017GND              VIA   -    M      A18X+056021Y+116509X0260Y         S2      
017GND                    -    MD0100PA00X+056021Y+116509                       
317GND              VIA   -    MD0100PA00X+056602Y+116509X0200Y         S0      
317GND              VIA   -    MD0100PA00X+056952Y+115249X0200Y         S0      
317GND              VIA   -    MD0100PA00X+056021Y+115249X0200Y         S0      
317GND              VIA   -    MD0100PA00X+056602Y+115249X0200Y         S0      
317GND              VIA   -    MD0100PA00X+056952Y+112729X0200Y         S0      
317GND              VIA   -    MD0100PA00X+056021Y+112729X0200Y         S0      
317GND              VIA   -    MD0100PA00X+056602Y+112729X0200Y         S0      
317GND              VIA   -    MD0100PA00X+056021Y+113989X0200Y         S0      
317GND              VIA   -    MD0100PA00X+056602Y+113989X0200Y         S0      
317GND              VIA   -    MD0100PA00X+056952Y+113989X0200Y         S0      
317GND              VIA   -    MD0100PA00X+056021Y+111469X0200Y         S0      
317GND              VIA   -    MD0100PA00X+056602Y+111469X0200Y         S0      
317GND              VIA   -    MD0100PA00X+056952Y+111469X0200Y         S0      
317GND              VIA   -    MD0100PA00X+056602Y+110209X0200Y         S0      
317GND              VIA   -    MD0100PA00X+056021Y+110209X0200Y         S0      
317GND              VIA   -    MD0100PA00X+056952Y+110209X0200Y         S0      
317GND              VIA   -    MD0100PA00X+056545Y+103510X0200Y         S0      
327GND              C3228 -2          A01X+056320Y+103510X0120Y0150R090 S1      
317GND              VIA   -    MD0100PA00X+056836Y+101176X0200Y    R090 S0      
317GND              VIA   -    MD0100PA00X+057186Y+100935X0200Y         S0      
317GND              VIA   -    MD0100PA00X+056836Y+100826X0200Y    R090 S0      
317GND              VIA   -    MD0100PA00X+055692Y+099786X0200Y         S0      
327GND              R1296 -1          A01X+055692Y+099511X0198Y0197R270 S1      
317GND              VIA   -    MD0100PA00X+056892Y+099786X0200Y         S0      
327GND              R1287 -1          A01X+056892Y+099511X0198Y0197R270 S1      
317GND              VIA   -    MD0100PA00X+056092Y+099786X0200Y         S0      
327GND              R1291 -1          A01X+056092Y+099511X0198Y0197R270 S1      
317GND              VIA   -    MD0100PA00X+056492Y+099786X0200Y         S0      
327GND              R1294 -1          A01X+056492Y+099511X0198Y0197R270 S1      
317GND              VIA   -    MD0100PA00X+056081Y+090102X0200Y         S0      
317GND              VIA   -    MD0080PA00X+056844Y+139658X0160Y         S0      
317GND              VIA   -    MD0100PA00X+055474Y+139399X0180Y         S0      
317GND              VIA   -    MD0100PA00X+056202Y+139409X0180Y         S0      
317GND              VIA   -    MD0100PA00X+056202Y+140600X0180Y         S0      
317GND              VIA   -    MD0100PA00X+056202Y+139908X0180Y         S0      
317GND              VIA   -    MD0100PA00X+056698Y+139409X0180Y         S0      
317GND              VIA   -    MD0100PA00X+056698Y+140600X0180Y         S0      
317GND              VIA   -    MD0100PA00X+056698Y+139908X0180Y         S0      
317GND              VIA   -    MD0100PA00X+055474Y+139908X0180Y         S0      
317GND              VIA   -    MD0100PA00X+055474Y+140600X0180Y         S0      
317GND              VIA   -    MD0100PA00X+056202Y+136260X0180Y         S0      
317GND              VIA   -    MD0100PA00X+056698Y+136260X0180Y         S0      
317GND              VIA   -    MD0100PA00X+056698Y+135760X0180Y         S0      
317GND              VIA   -    MD0100PA00X+056202Y+135760X0180Y         S0      
317GND              VIA   -    MD0080PA00X+056844Y+136010X0160Y         S0      
317GND              VIA   -    MD0100PA00X+056698Y+135068X0180Y         S0      
317GND              VIA   -    MD0100PA00X+056698Y+134569X0180Y         S0      
317GND              VIA   -    MD0100PA00X+056202Y+134569X0180Y         S0      
317GND              VIA   -    MD0100PA00X+056202Y+135068X0180Y         S0      
317GND              VIA   -    MD0080PA00X+056844Y+134819X0160Y         S0      
317GND              VIA   -    MD0100PA00X+056988Y+122375X0200Y         S0      
327GND              R1283 -1          A01X+057229Y+122615X0198Y0197R045 S1      
317GND              VIA   -    MD0100PA00X+057725Y+096544X0200Y    R090 S0      
317GND              VIA   -    MD0100PA00X+059713Y+091339X0200Y         S0      
317GND              VIA   -    MD0100PA00X+058271Y+090896X0200Y         S0      
317GND              VIA   -    MD0100PA00X+057925Y+090336X0200Y         S0      
317GND              VIA   -    MD0100PA00X+059224Y+088061X0200Y         S0      
317GND              VIA   -    MD0100PA00X+057983Y+088400X0200Y         S0      
317GND              VIA   -    MD0100PA00X+057976Y+081775X0200Y         S0      
317GND              VIA   -    MD0100PA00X+058350Y+080083X0200Y    R270 S0      
327GND              U104  -2          A18X+058350Y+079711X0140Y0440     S2      
317GND              VIA   -    MD0100PA00X+058100Y+081412X0200Y         S0      
327GND              C2608 -1          A18X+058350Y+081412X0198Y0197R090 S2      
317GND              VIA   -    MD0100PA00X+056935Y+154195X0200Y         S0      
317GND              VIA   -    MD0100PA00X+056202Y+141099X0180Y         S0      
317GND              VIA   -    MD0100PA00X+056698Y+141099X0180Y         S0      
317GND              VIA   -    MD0100PA00X+055474Y+141099X0180Y         S0      
317GND              VIA   -    MD0080PA00X+055620Y+139658X0160Y         S0      
317GND              VIA   -    MD0080PA00X+055620Y+140850X0160Y         S0      
317GND              VIA   -    MD0080PA00X+056844Y+140850X0160Y         S0      
317GND              VIA   -    M      A01X+060614Y+096566X0200Y    R090 S2      
017GND              VIA   -    M      A18X+060614Y+096566X0260Y    R090 S2      
017GND                    -    MD0100PA00X+060614Y+096566                       
317GND              VIA   -    MD0100PA00X+060238Y+094092X0200Y         S0      
317GND              VIA   -    MD0100PA00X+057764Y+154098X0200Y         S0      
317GND              VIA   -    MD0100PA00X+057378Y+153065X0200Y         S0      
317GND              VIA   -    MD0100PA00X+058366Y+152914X0200Y         S0      
317GND              VIA   -    MD0100PA00X+058402Y+120961X0200Y         S0      
327GND              R1285 -1          A01X+058926Y+120918X0198Y0197R045 S1      
317GND              VIA   -    MD0100PA00X+057830Y+121520X0200Y         S0      
327GND              R1284 -1          A01X+058077Y+121767X0198Y0197R045 S1      
317GND              VIA   -    MD0100PA00X+057767Y+102195X0200Y         S0      
317GND              VIA   -    M      A01X+058117Y+102195X0200Y         S2      
017GND              VIA   -    M      A18X+058117Y+102195X0260Y         S2      
017GND                    -    MD0100PA00X+058117Y+102195                       
317GND              VIA   -    MD0100PA00X+058492Y+099786X0200Y         S0      
327GND              R1297 -1          A01X+058492Y+099511X0198Y0197R270 S1      
317GND              VIA   -    MD0100PA00X+057292Y+099786X0200Y         S0      
327GND              R1292 -1          A01X+057292Y+099511X0198Y0197R270 S1      
317GND              VIA   -    MD0100PA00X+058117Y+100935X0200Y         S0      
317GND              VIA   -    MD0100PA00X+057767Y+100935X0200Y         S0      
317GND              VIA   -    MD0100PA00X+058892Y+099786X0200Y         S0      
317GND              VIA   -    MD0100PA00X+057692Y+099786X0200Y         S0      
327GND              R1289 -1          A01X+057692Y+099511X0198Y0197R270 S1      
317GND              VIA   -    MD0100PA00X+058092Y+099786X0200Y         S0      
327GND              R1293 -1          A01X+058092Y+099511X0198Y0197R270 S1      
327GND              PEX1  -AF2        A01X+060590Y+116122X0180Y         S1      
327GND              PEX1  -AD1        A01X+060216Y+116870X0180Y         S1      
327GND              PEX1  -AF1        A01X+060216Y+116122X0180Y         S1      
317GND              VIA   -    MD0100PA00X+059096Y+116809X0200Y         S0      
317GND              VIA   -    MD0100PA00X+059096Y+114289X0200Y         S0      
317GND              VIA   -    MD0100PA00X+059096Y+115549X0200Y         S0      
327GND              PEX1  -AH2        A01X+060590Y+115374X0180Y         S1      
327GND              PEX1  -AK2        A01X+060590Y+114626X0180Y         S1      
327GND              PEX1  -AH1        A01X+060216Y+115374X0180Y         S1      
327GND              PEX1  -AK1        A01X+060216Y+114626X0180Y         S1      
327GND              PEX1  -AN2        A01X+060590Y+113504X0180Y         S1      
327GND              PEX1  -AR2        A01X+060590Y+112756X0180Y         S1      
327GND              PEX1  -AN1        A01X+060216Y+113504X0180Y         S1      
327GND              PEX1  -AR1        A01X+060216Y+112756X0180Y         S1      
317GND              VIA   -    MD0100PA00X+059096Y+113029X0200Y         S0      
327GND              PEX1  -AU2        A01X+060590Y+112008X0180Y         S1      
327GND              PEX1  -AW2        A01X+060590Y+111260X0180Y         S1      
327GND              PEX1  -AU1        A01X+060216Y+112008X0180Y         S1      
327GND              PEX1  -AW1        A01X+060216Y+111260X0180Y         S1      
317GND              VIA   -    MD0100PA00X+059096Y+111769X0200Y         S0      
327GND              PEX1  -BC2        A01X+060590Y+109764X0180Y         S1      
327GND              PEX1  -BC1        A01X+060216Y+109764X0180Y         S1      
327GND              PEX1  -BA1        A01X+060216Y+110512X0180Y         S1      
317GND              VIA   -    MD0100PA00X+059096Y+110509X0200Y         S0      
327GND              PEX1  -BA2        A01X+060590Y+110512X0180Y         S1      
327GND              PEX1  -BF2        A01X+060590Y+108642X0180Y         S1      
327GND              PEX1  -BH1        A01X+060216Y+107894X0180Y         S1      
327GND              PEX1  -BH2        A01X+060590Y+107894X0180Y         S1      
327GND              PEX1  -BF1        A01X+060216Y+108642X0180Y         S1      
317GND              VIA   -    MD0100PA00X+059190Y+103501X0200Y         S0      
317GND              VIA   -    MD0100PA00X+060440Y+103487X0200Y         S0      
317GND              VIA   -    MD0100PA00X+060260Y+102495X0200Y         S0      
317GND              VIA   -    MD0100PA00X+060260Y+101235X0200Y         S0      
317GND              VIA   -    MD0100PA00X+060092Y+099786X0200Y         S0      
327GND              R1295 -1          A01X+060092Y+099511X0198Y0197R270 S1      
317GND              VIA   -    MD0100PA00X+060492Y+099786X0200Y         S0      
317GND              VIA   -    MD0100PA00X+059292Y+099786X0200Y         S0      
327GND              R1300 -1          A01X+059292Y+099511X0198Y0197R270 S1      
317GND              VIA   -    MD0100PA00X+059692Y+099786X0200Y         S0      
327GND              R1301 -1          A01X+059692Y+099511X0198Y0197R270 S1      
317GND              VIA   -    MD0100PA00X+059096Y+118069X0200Y         S0      
327GND              PEX1  -AY6        A01X+062087Y+110886X0180Y         S1      
327GND              PEX1  -BH6        A01X+062087Y+107894X0180Y         S1      
327GND              PEX1  -BE3        A01X+060965Y+109016X0180Y         S1      
327GND              PEX1  -BE4        A01X+061339Y+109016X0180Y         S1      
327GND              PEX1  -BE5        A01X+061713Y+109016X0180Y         S1      
327GND              PEX1  -BF3        A01X+060965Y+108642X0180Y         S1      
327GND              PEX1  -BF5        A01X+061713Y+108642X0180Y         S1      
327GND              PEX1  -BG3        A01X+060965Y+108268X0180Y         S1      
327GND              PEX1  -BG5        A01X+061713Y+108268X0180Y         S1      
327GND              PEX1  -BH4        A01X+061339Y+107894X0180Y         S1      
327GND              PEX1  -BJ2        A01X+060590Y+107520X0180Y         S1      
327GND              PEX1  -BE6        A01X+062087Y+109016X0180Y         S1      
327GND              PEX1  -BJ6        A01X+062087Y+107520X0180Y         S1      
327GND              PEX1  -BJ4        A01X+061339Y+107520X0180Y         S1      
317GND              VIA   -    MD0100PA00X+062072Y+104678X0200Y         S0      
317GND              VIA   -    MD0100PA00X+061909Y+105645X0200Y         S0      
317GND              VIA   -    MD0100PA00X+062015Y+104036X0200Y         S0      
317GND              VIA   -    MD0100PA00X+060892Y+099786X0200Y         S0      
327GND              R1288 -1          A01X+060892Y+099511X0198Y0197R270 S1      
317GND              VIA   -    MD0100PA00X+061692Y+099786X0200Y         S0      
327GND              R1290 -1          A01X+061692Y+099511X0198Y0197R270 S1      
317GND              VIA   -    MD0100PA00X+061249Y+094102X0200Y         S0      
317GND              VIA   -    MD0100PA00X+064999Y+136260X0180Y         S0      
317GND              VIA   -    MD0100PA00X+064999Y+135760X0180Y         S0      
317GND              VIA   -    MD0100PA00X+064999Y+134569X0180Y         S0      
317GND              VIA   -    MD0100PA00X+064999Y+135068X0180Y         S0      
327GND              PEX1  -AF6        A01X+062087Y+116122X0180Y         S1      
327GND              PEX1  -AD2        A01X+060590Y+116870X0180Y         S1      
327GND              PEX1  -AD3        A01X+060965Y+116870X0180Y         S1      
327GND              PEX1  -AE3        A01X+060965Y+116496X0180Y         S1      
327GND              PEX1  -AE4 M      A01X+061339Y+116496X0180Y         S1      
327GND              PEX1  -AE5        A01X+061713Y+116496X0180Y         S1      
327GND              PEX1  -AF3        A01X+060965Y+116122X0180Y         S1      
327GND              PEX1  -AG3        A01X+060965Y+115748X0180Y         S1      
327GND              PEX1  -AG4        A01X+061339Y+115748X0180Y         S1      
327GND              PEX1  -AG5        A01X+061713Y+115748X0180Y         S1      
327GND              PEX1  -AH3        A01X+060965Y+115374X0180Y         S1      
327GND              PEX1  -AJ3        A01X+060965Y+115000X0180Y         S1      
327GND              PEX1  -AJ4        A01X+061339Y+115000X0180Y         S1      
327GND              PEX1  -AJ5        A01X+061713Y+115000X0180Y         S1      
327GND              PEX1  -AK3        A01X+060965Y+114626X0180Y         S1      
327GND              PEX1  -AG6        A01X+062087Y+115748X0180Y         S1      
327GND              PEX1  -AH6        A01X+062087Y+115374X0180Y         S1      
327GND              PEX1  -AJ6        A01X+062087Y+115000X0180Y         S1      
327GND              PEX1  -AK6        A01X+062087Y+114626X0180Y         S1      
327GND              PEX1  -AN5        A01X+061713Y+113504X0180Y         S1      
327GND              PEX1  -AP6        A01X+062087Y+113130X0180Y         S1      
327GND              PEX1  -AT6        A01X+062087Y+112382X0180Y         S1      
327GND              PEX1  -AM3        A01X+060965Y+113878X0180Y         S1      
327GND              PEX1  -AP3        A01X+060965Y+113130X0180Y         S1      
327GND              PEX1  -AP4        A01X+061339Y+113130X0180Y         S1      
327GND              PEX1  -AP5        A01X+061713Y+113130X0180Y         S1      
327GND              PEX1  -AR5        A01X+061713Y+112756X0180Y         S1      
327GND              PEX1  -AV6        A01X+062087Y+111634X0180Y         S1      
327GND              PEX1  -AT3        A01X+060965Y+112382X0180Y         S1      
327GND              PEX1  -AT4        A01X+061339Y+112382X0180Y         S1      
327GND              PEX1  -AT5        A01X+061713Y+112382X0180Y         S1      
327GND              PEX1  -AU5        A01X+061713Y+112008X0180Y         S1      
327GND              PEX1  -AV3        A01X+060965Y+111634X0180Y         S1      
327GND              PEX1  -AV4        A01X+061339Y+111634X0180Y         S1      
327GND              PEX1  -AV5        A01X+061713Y+111634X0180Y         S1      
327GND              PEX1  -AW5        A01X+061713Y+111260X0180Y         S1      
327GND              PEX1  -BC6        A01X+062087Y+109764X0180Y         S1      
327GND              PEX1  -AY5        A01X+061713Y+110886X0180Y         S1      
327GND              PEX1  -BA3        A01X+060965Y+110512X0180Y         S1      
327GND              PEX1  -BA5        A01X+061713Y+110512X0180Y         S1      
327GND              PEX1  -BB3        A01X+060965Y+110138X0180Y         S1      
327GND              PEX1  -BB5        A01X+061713Y+110138X0180Y         S1      
327GND              PEX1  -BC4        A01X+061339Y+109764X0180Y         S1      
327GND              PEX1  -AY3        A01X+060965Y+110886X0180Y         S1      
327GND              PEX1  -AY4        A01X+061339Y+110886X0180Y         S1      
317GND              VIA   -    MD0100PA00X+066719Y+136260X0180Y         S0      
317GND              VIA   -    MD0100PA00X+066719Y+135760X0180Y         S0      
317GND              VIA   -    MD0100PA00X+066223Y+136260X0180Y         S0      
317GND              VIA   -    MD0100PA00X+066223Y+135760X0180Y         S0      
317GND              VIA   -    MD0100PA00X+065495Y+136260X0180Y         S0      
317GND              VIA   -    MD0100PA00X+065495Y+135760X0180Y         S0      
317GND              VIA   -    MD0100PA00X+066223Y+134569X0180Y         S0      
317GND              VIA   -    MD0100PA00X+065495Y+134569X0180Y         S0      
317GND              VIA   -    MD0100PA00X+066719Y+134569X0180Y         S0      
317GND              VIA   -    MD0100PA00X+066719Y+135068X0180Y         S0      
317GND              VIA   -    MD0100PA00X+066223Y+135068X0180Y         S0      
317GND              VIA   -    MD0100PA00X+065495Y+135068X0180Y         S0      
327GND              PEX1  -BE7        A01X+062461Y+109016X0180Y         S1      
327GND              PEX1  -BG7        A01X+062461Y+108268X0180Y         S1      
317GND              VIA   -    MD0100PA00X+061200Y+164498X0200Y         S0      
317GND              VIA   -    MD0100PA00X+063047Y+141099X0180Y         S0      
317GND              VIA   -    MD0100PA00X+063775Y+138679X0180Y         S0      
317GND              VIA   -    MD0100PA00X+062551Y+141099X0180Y         S0      
317GND              VIA   -    MD0100PA00X+063047Y+140600X0180Y         S0      
317GND              VIA   -    MD0100PA00X+063047Y+139908X0180Y         S0      
317GND              VIA   -    MD0100PA00X+063775Y+136989X0180Y         S0      
317GND              VIA   -    MD0100PA00X+063775Y+138180X0180Y         S0      
317GND              VIA   -    MD0100PA00X+063775Y+137488X0180Y         S0      
317GND              VIA   -    MD0100PA00X+062551Y+139409X0180Y         S0      
317GND              VIA   -    MD0100PA00X+062551Y+140600X0180Y         S0      
317GND              VIA   -    MD0100PA00X+062551Y+139908X0180Y         S0      
317GND              VIA   -    MD0100PA00X+063047Y+139409X0180Y         S0      
317GND              VIA   -    MD0080PA00X+063193Y+139658X0160Y         S0      
317GND              VIA   -    MD0080PA00X+063193Y+140850X0160Y         S0      
327GND              PEX1  -AF9        A01X+063209Y+116122X0180Y         S1      
327GND              PEX1  -AD6        A01X+062087Y+116870X0180Y         S1      
327GND              PEX1  -AE6        A01X+062087Y+116496X0180Y         S1      
327GND              PEX1  -AH9        A01X+063209Y+115374X0180Y         S1      
327GND              PEX1  -AG9        A01X+063209Y+115748X0180Y         S1      
327GND              PEX1  -AJ9        A01X+063209Y+115000X0180Y         S1      
327GND              PEX1  -AK8        A01X+062835Y+114626X0180Y         S1      
327GND              PEX1  -AK9        A01X+063209Y+114626X0180Y         S1      
327GND              PEX1  -AN8        A01X+062835Y+113504X0180Y         S1      
327GND              PEX1  -AN9        A01X+063209Y+113504X0180Y         S1      
327GND              PEX1  -AP7        A01X+062461Y+113130X0180Y         S1      
327GND              PEX1  -AR8        A01X+062835Y+112756X0180Y         S1      
327GND              PEX1  -AR9        A01X+063209Y+112756X0180Y         S1      
327GND              PEX1  -AM10       A01X+063583Y+113878X0180Y         S1      
327GND              PEX1  -AP10       A01X+063583Y+113130X0180Y         S1      
327GND              PEX1  -AR10       A01X+063583Y+112756X0180Y         S1      
327GND              PEX1  -AT10       A01X+063583Y+112382X0180Y         S1      
327GND              PEX1  -AU10       A01X+063583Y+112008X0180Y         S1      
327GND              PEX1  -AV10       A01X+063583Y+111634X0180Y         S1      
327GND              PEX1  -AT7        A01X+062461Y+112382X0180Y         S1      
327GND              PEX1  -AU8        A01X+062835Y+112008X0180Y         S1      
327GND              PEX1  -AU9        A01X+063209Y+112008X0180Y         S1      
327GND              PEX1  -AV7        A01X+062461Y+111634X0180Y         S1      
327GND              PEX1  -AW8        A01X+062835Y+111260X0180Y         S1      
327GND              PEX1  -AW9        A01X+063209Y+111260X0180Y         S1      
327GND              PEX1  -AY7        A01X+062461Y+110886X0180Y         S1      
327GND              PEX1  -AY8        A01X+062835Y+110886X0180Y         S1      
327GND              PEX1  -BA7        A01X+062461Y+110512X0180Y         S1      
327GND              PEX1  -BB7        A01X+062461Y+110138X0180Y         S1      
317GND              VIA   -    MD0100PA00X+067447Y+135068X0180Y         S0      
317GND              VIA   -    MD0100PA00X+065495Y+137488X0180Y         S0      
317GND              VIA   -    MD0100PA00X+064999Y+136989X0180Y         S0      
317GND              VIA   -    MD0100PA00X+067943Y+134569X0180Y         S0      
317GND              VIA   -    MD0100PA00X+067447Y+134569X0180Y         S0      
317GND              VIA   -    MD0100PA00X+065495Y+136989X0180Y         S0      
317GND              VIA   -    MD0100PA00X+064999Y+137488X0180Y         S0      
317GND              VIA   -    MD0080PA00X+065641Y+137238X0160Y         S0      
317GND              VIA   -    MD0100PA00X+064271Y+139908X0180Y         S0      
317GND              VIA   -    MD0100PA00X+064271Y+136989X0180Y         S0      
317GND              VIA   -    MD0100PA00X+064271Y+138180X0180Y         S0      
317GND              VIA   -    MD0100PA00X+064271Y+137488X0180Y         S0      
317GND              VIA   -    MD0100PA00X+063775Y+139409X0180Y         S0      
317GND              VIA   -    MD0100PA00X+064271Y+139409X0180Y         S0      
317GND              VIA   -    MD0100PA00X+063775Y+140600X0180Y         S0      
317GND              VIA   -    MD0100PA00X+063775Y+139908X0180Y         S0      
317GND              VIA   -    MD0100PA00X+064271Y+140600X0180Y         S0      
317GND              VIA   -    MD0080PA00X+064417Y+137238X0160Y         S0      
317GND              VIA   -    MD0080PA00X+064417Y+138430X0160Y         S0      
317GND              VIA   -    MD0080PA00X+064417Y+139658X0160Y         S0      
317GND              VIA   -    MD0080PA00X+064417Y+140850X0160Y         S0      
317GND              VIA   -    MD0100PA00X+065495Y+138679X0180Y         S0      
317GND              VIA   -    MD0100PA00X+065495Y+138180X0180Y         S0      
317GND              VIA   -    MD0100PA00X+064999Y+138679X0180Y         S0      
317GND              VIA   -    MD0100PA00X+064999Y+138180X0180Y         S0      
317GND              VIA   -    MD0100PA00X+067943Y+136260X0180Y         S0      
317GND              VIA   -    MD0100PA00X+067943Y+135760X0180Y         S0      
317GND              VIA   -    MD0100PA00X+067447Y+136260X0180Y         S0      
317GND              VIA   -    MD0100PA00X+067447Y+135760X0180Y         S0      
317GND              VIA   -    MD0080PA00X+065641Y+138430X0160Y         S0      
317GND              VIA   -    MD0100PA00X+067943Y+135068X0180Y         S0      
317GND              VIA   -    MD0100PA00X+062735Y+149662X0200Y         S0      
317GND              VIA   -    MD0100PA00X+063602Y+149622X0200Y         S0      
317GND              VIA   -    MD0100PA00X+062735Y+149189X0200Y         S0      
317GND              VIA   -    MD0100PA00X+063602Y+149149X0200Y         S0      
317GND              VIA   -    MD0100PA00X+063602Y+148560X0200Y         S0      
317GND              VIA   -    MD0100PA00X+062735Y+148716X0200Y         S0      
317GND              VIA   -    MD0100PA00X+063602Y+147024X0200Y         S0      
317GND              VIA   -    MD0100PA00X+062735Y+147180X0200Y         S0      
317GND              VIA   -    MD0100PA00X+062735Y+148127X0200Y         S0      
317GND              VIA   -    MD0100PA00X+063602Y+148087X0200Y         S0      
317GND              VIA   -    MD0100PA00X+062735Y+147654X0200Y         S0      
317GND              VIA   -    MD0100PA00X+063602Y+147614X0200Y         S0      
317GND              VIA   -    MD0100PA00X+062735Y+145645X0200Y         S0      
317GND              VIA   -    MD0100PA00X+062735Y+146591X0200Y         S0      
317GND              VIA   -    MD0100PA00X+063602Y+146551X0200Y         S0      
317GND              VIA   -    MD0100PA00X+062735Y+146118X0200Y         S0      
317GND              VIA   -    MD0100PA00X+063602Y+146078X0200Y         S0      
317GND              VIA   -    MD0100PA00X+064271Y+141099X0180Y         S0      
317GND              VIA   -    MD0100PA00X+064271Y+138679X0180Y         S0      
317GND              VIA   -    MD0100PA00X+063775Y+141099X0180Y         S0      
317GND              VIA   -    MD0100PA00X+062735Y+160961X0200Y         S0      
317GND              VIA   -    MD0100PA00X+063602Y+160921X0200Y         S0      
317GND              VIA   -    MD0100PA00X+062735Y+159898X0200Y         S0      
317GND              VIA   -    MD0100PA00X+063602Y+159858X0200Y         S0      
317GND              VIA   -    MD0100PA00X+063602Y+160332X0200Y         S0      
317GND              VIA   -    MD0100PA00X+062735Y+160488X0200Y         S0      
317GND              VIA   -    MD0100PA00X+063602Y+158796X0200Y         S0      
317GND              VIA   -    MD0100PA00X+062735Y+158952X0200Y         S0      
317GND              VIA   -    MD0100PA00X+062735Y+158363X0200Y         S0      
317GND              VIA   -    MD0100PA00X+063602Y+158323X0200Y         S0      
317GND              VIA   -    MD0100PA00X+062735Y+159425X0200Y         S0      
317GND              VIA   -    MD0100PA00X+063602Y+159385X0200Y         S0      
317GND              VIA   -    MD0100PA00X+062735Y+157890X0200Y         S0      
317GND              VIA   -    MD0100PA00X+063602Y+157850X0200Y         S0      
317GND              VIA   -    MD0100PA00X+063602Y+157261X0200Y         S0      
317GND              VIA   -    MD0100PA00X+062735Y+157417X0200Y         S0      
317GND              VIA   -    MD0100PA00X+062735Y+156828X0200Y         S0      
317GND              VIA   -    MD0100PA00X+063602Y+156788X0200Y         S0      
317GND              VIA   -    MD0100PA00X+062735Y+156354X0200Y         S0      
317GND              VIA   -    MD0100PA00X+063602Y+156314X0200Y         S0      
317GND              VIA   -    MD0100PA00X+062735Y+155881X0200Y         S0      
317GND              VIA   -    MD0100PA00X+063602Y+151631X0200Y         S0      
317GND              VIA   -    MD0100PA00X+063602Y+150684X0200Y         S0      
317GND              VIA   -    MD0100PA00X+063602Y+150095X0200Y         S0      
317GND              VIA   -    MD0100PA00X+062735Y+150251X0200Y         S0      
317GND              VIA   -    MD0100PA00X+063602Y+151158X0200Y         S0      
317GND              VIA   -    MD0100PA00X+062735Y+151198X0200Y         S0      
317GND              VIA   -    MD0100PA00X+062735Y+150724X0200Y         S0      
317GND              VIA   -    MD0100PA00X+063200Y+164498X0200Y         S0      
317GND              VIA   -    MD0100PA00X+062735Y+161434X0200Y         S0      
317GND              VIA   -    MD0100PA00X+063602Y+161394X0200Y         S0      
317GND              VIA   -    MD0100PA00X+063602Y+161867X0200Y         S0      
327GND              PEX1  -AN13       A01X+064705Y+113504X0180Y         S1      
327GND              PEX1  -AP11       A01X+063957Y+113130X0180Y         S1      
327GND              PEX1  -AP12       A01X+064331Y+113130X0180Y         S1      
327GND              PEX1  -AP13       A01X+064705Y+113130X0180Y         S1      
327GND              PEX1  -AR11       A01X+063957Y+112756X0180Y         S1      
327GND              PEX1  -AR12       A01X+064331Y+112756X0180Y         S1      
327GND              PEX1  -AR13       A01X+064705Y+112756X0180Y         S1      
327GND              PEX1  -AR14       A01X+065079Y+112756X0180Y         S1      
327GND              PEX1  -AM11       A01X+063957Y+113878X0180Y         S1      
327GND              PEX1  -AT15       A01X+065453Y+112382X0180Y         S1      
327GND              PEX1  -AU15       A01X+065453Y+112008X0180Y         S1      
327GND              PEX1  -AT11       A01X+063957Y+112382X0180Y         S1      
327GND              PEX1  -AT12       A01X+064331Y+112382X0180Y         S1      
327GND              PEX1  -AT13       A01X+064705Y+112382X0180Y         S1      
327GND              PEX1  -AT14       A01X+065079Y+112382X0180Y         S1      
327GND              PEX1  -AU11       A01X+063957Y+112008X0180Y         S1      
327GND              PEX1  -AU12       A01X+064331Y+112008X0180Y         S1      
327GND              PEX1  -AU13       A01X+064705Y+112008X0180Y         S1      
327GND              PEX1  -AU14       A01X+065079Y+112008X0180Y         S1      
327GND              PEX1  -AV11       A01X+063957Y+111634X0180Y         S1      
327GND              C3169 -2          A18X+064518Y+119301X0120Y0150     S2      
327GND              PEX1  -AG10       A01X+063583Y+115748X0180Y         S1      
327GND              PEX1  -AF11       A01X+063957Y+116122X0180Y         S1      
327GND              PEX1  -AF13       A01X+064705Y+116122X0180Y         S1      
327GND              PEX1  -AF15       A01X+065453Y+116122X0180Y         S1      
327GND              PEX1  -AH13M      A01X+064705Y+115374X0180Y         S1      
327GND              PEX1  -AG14M      A01X+065079Y+115748X0180Y         S1      
327GND              PEX1  -AJ11       A01X+063957Y+115000X0180Y         S1      
327GND              PEX1  -AK11       A01X+063957Y+114626X0180Y         S1      
327GND              PEX1  -AK13       A01X+064705Y+114626X0180Y         S1      
327GND              PEX1  -AH11       A01X+063957Y+115374X0180Y         S1      
327GND              PEX1  -AG11       A01X+063957Y+115748X0180Y         S1      
327GND              PEX1  -AM13       A01X+064705Y+113878X0180Y         S1      
327GND              PEX1  -AN10M      A01X+063583Y+113504X0180Y         S1      
327GND              PEX1  -AN11       A01X+063957Y+113504X0180Y         S1      
327GND              PEX1  -AN12       A01X+064331Y+113504X0180Y         S1      
317GND              VIA   -    MD0080PA00X+068089Y+136010X0160Y         S0      
317GND              VIA   -    MD0080PA00X+069313Y+136010X0160Y         S0      
317GND              VIA   -    MD0100PA00X+068671Y+138679X0180Y         S0      
317GND              VIA   -    MD0100PA00X+068671Y+138180X0180Y         S0      
317GND              VIA   -    MD0100PA00X+069167Y+136260X0180Y         S0      
317GND              VIA   -    MD0100PA00X+069167Y+135760X0180Y         S0      
317GND              VIA   -    MD0100PA00X+068671Y+136260X0180Y         S0      
317GND              VIA   -    MD0100PA00X+068671Y+135760X0180Y         S0      
317GND              VIA   -    MD0100PA00X+068671Y+136989X0180Y         S0      
317GND              VIA   -    MD0100PA00X+069167Y+134569X0180Y         S0      
317GND              VIA   -    MD0100PA00X+068671Y+134569X0180Y         S0      
317GND              VIA   -    MD0100PA00X+068671Y+137488X0180Y         S0      
317GND              VIA   -    MD0100PA00X+069167Y+135068X0180Y         S0      
317GND              VIA   -    MD0100PA00X+068671Y+135068X0180Y         S0      
317GND              VIA   -    MD0080PA00X+068089Y+134819X0160Y         S0      
317GND              VIA   -    MD0080PA00X+069313Y+134819X0160Y         S0      
317GND              VIA   -    MD0100PA00X+065334Y+146078X0200Y         S0      
317GND              VIA   -    MD0100PA00X+064468Y+146591X0200Y         S0      
317GND              VIA   -    MD0100PA00X+064468Y+145645X0200Y         S0      
317GND              VIA   -    MD0100PA00X+064468Y+146118X0200Y         S0      
317GND              VIA   -    MD0100PA00X+065334Y+146551X0200Y         S0      
317GND              VIA   -    MD0100PA00X+066223Y+138679X0180Y         S0      
317GND              VIA   -    MD0100PA00X+066719Y+138679X0180Y         S0      
317GND              VIA   -    MD0100PA00X+064999Y+141099X0180Y         S0      
317GND              VIA   -    MD0100PA00X+065505Y+141099X0180Y         S0      
317GND              VIA   -    MD0100PA00X+066223Y+138180X0180Y         S0      
317GND              VIA   -    MD0100PA00X+066223Y+137488X0180Y         S0      
317GND              VIA   -    MD0100PA00X+066719Y+136989X0180Y         S0      
317GND              VIA   -    MD0100PA00X+064999Y+139409X0180Y         S0      
317GND              VIA   -    MD0100PA00X+066719Y+138180X0180Y         S0      
317GND              VIA   -    MD0100PA00X+066719Y+137488X0180Y         S0      
317GND              VIA   -    MD0100PA00X+064999Y+140600X0180Y         S0      
317GND              VIA   -    MD0100PA00X+064999Y+139908X0180Y         S0      
317GND              VIA   -    MD0100PA00X+065505Y+139409X0180Y         S0      
317GND              VIA   -    MD0100PA00X+065505Y+140600X0180Y         S0      
317GND              VIA   -    MD0100PA00X+065505Y+139908X0180Y         S0      
317GND              VIA   -    MD0100PA00X+066223Y+136989X0180Y         S0      
317GND              VIA   -    MD0100PA00X+064468Y+156354X0200Y         S0      
317GND              VIA   -    MD0100PA00X+065334Y+156314X0200Y         S0      
317GND              VIA   -    MD0100PA00X+064468Y+155881X0200Y         S0      
317GND              VIA   -    MD0100PA00X+065334Y+151631X0200Y         S0      
317GND              VIA   -    MD0100PA00X+064468Y+150724X0200Y         S0      
317GND              VIA   -    MD0100PA00X+064468Y+150251X0200Y         S0      
317GND              VIA   -    MD0100PA00X+065334Y+150684X0200Y         S0      
317GND              VIA   -    MD0100PA00X+065334Y+150095X0200Y         S0      
317GND              VIA   -    MD0100PA00X+065334Y+151158X0200Y         S0      
317GND              VIA   -    MD0100PA00X+064468Y+151198X0200Y         S0      
317GND              VIA   -    MD0100PA00X+065334Y+148560X0200Y         S0      
317GND              VIA   -    MD0100PA00X+065334Y+149622X0200Y         S0      
317GND              VIA   -    MD0100PA00X+064468Y+148716X0200Y         S0      
317GND              VIA   -    MD0100PA00X+064468Y+149189X0200Y         S0      
317GND              VIA   -    MD0100PA00X+064468Y+149662X0200Y         S0      
317GND              VIA   -    MD0100PA00X+065334Y+149149X0200Y         S0      
317GND              VIA   -    MD0100PA00X+064468Y+148127X0200Y         S0      
317GND              VIA   -    MD0100PA00X+065334Y+147614X0200Y         S0      
317GND              VIA   -    MD0100PA00X+065334Y+147024X0200Y         S0      
317GND              VIA   -    MD0100PA00X+065334Y+148087X0200Y         S0      
317GND              VIA   -    MD0100PA00X+064468Y+147180X0200Y         S0      
317GND              VIA   -    MD0100PA00X+064468Y+147654X0200Y         S0      
317GND              VIA   -    MD0100PA00X+065334Y+161867X0200Y         S0      
317GND              VIA   -    MD0100PA00X+064468Y+161434X0200Y         S0      
317GND              VIA   -    MD0100PA00X+065334Y+159858X0200Y         S0      
317GND              VIA   -    MD0100PA00X+065334Y+160332X0200Y         S0      
317GND              VIA   -    MD0100PA00X+064468Y+160961X0200Y         S0      
317GND              VIA   -    MD0100PA00X+064468Y+160488X0200Y         S0      
317GND              VIA   -    MD0100PA00X+064468Y+159898X0200Y         S0      
317GND              VIA   -    MD0100PA00X+065334Y+160921X0200Y         S0      
317GND              VIA   -    MD0100PA00X+064468Y+158363X0200Y         S0      
317GND              VIA   -    MD0100PA00X+065334Y+158323X0200Y         S0      
317GND              VIA   -    MD0100PA00X+064468Y+158952X0200Y         S0      
317GND              VIA   -    MD0100PA00X+064468Y+159425X0200Y         S0      
317GND              VIA   -    MD0100PA00X+065334Y+159385X0200Y         S0      
317GND              VIA   -    MD0100PA00X+065334Y+158796X0200Y         S0      
317GND              VIA   -    MD0100PA00X+064468Y+156828X0200Y         S0      
317GND              VIA   -    MD0100PA00X+065334Y+156788X0200Y         S0      
317GND              VIA   -    MD0100PA00X+064468Y+157417X0200Y         S0      
317GND              VIA   -    MD0100PA00X+064468Y+157890X0200Y         S0      
317GND              VIA   -    MD0100PA00X+065334Y+157850X0200Y         S0      
317GND              VIA   -    MD0100PA00X+065334Y+157261X0200Y         S0      
317GND              VIA   -    MD0100PA00X+065200Y+164498X0200Y         S0      
317GND              VIA   -    MD0100PA00X+065334Y+161394X0200Y         S0      
327GND              PEX1  -AF19       A01X+066949Y+116122X0180Y         S1      
327GND              PEX1  -AG18M      A01X+066575Y+115748X0180Y         S1      
327GND              PEX1  -AH15M      A01X+065453Y+115374X0180Y         S1      
327GND              PEX1  -AF17       A01X+066201Y+116122X0180Y         S1      
327GND              PEX1  -AG16M      A01X+065827Y+115748X0180Y         S1      
327GND              PEX1  -AJ14M      A01X+065079Y+115000X0180Y         S1      
327GND              PEX1  -AR16       A01X+065827Y+112756X0180Y         S1      
327GND              PEX1  -AT16       A01X+065827Y+112382X0180Y         S1      
327GND              PEX1  -AU16       A01X+065827Y+112008X0180Y         S1      
317GND              VIA   -    MD0100PA00X+069895Y+135760X0180Y         S0      
317GND              VIA   -    MD0100PA00X+070391Y+136260X0180Y         S0      
317GND              VIA   -    MD0100PA00X+070391Y+135760X0180Y         S0      
317GND              VIA   -    MD0100PA00X+069167Y+138679X0180Y         S0      
317GND              VIA   -    MD0100PA00X+069895Y+136260X0180Y         S0      
317GND              VIA   -    MD0100PA00X+069167Y+138180X0180Y         S0      
317GND              VIA   -    MD0100PA00X+069167Y+137488X0180Y         S0      
317GND              VIA   -    MD0100PA00X+070391Y+134560X0180Y         S0      
317GND              VIA   -    MD0100PA00X+069167Y+136989X0180Y         S0      
317GND              VIA   -    MD0100PA00X+069895Y+134560X0180Y         S0      
317GND              VIA   -    MD0100PA00X+070391Y+135068X0180Y         S0      
317GND              VIA   -    MD0100PA00X+069895Y+135068X0180Y         S0      
317GND              VIA   -    MD0100PA00X+066200Y+147180X0200Y         S0      
317GND              VIA   -    MD0100PA00X+066200Y+147654X0200Y         S0      
317GND              VIA   -    MD0100PA00X+066200Y+148127X0200Y         S0      
317GND              VIA   -    MD0100PA00X+066200Y+146118X0200Y         S0      
317GND              VIA   -    MD0100PA00X+066200Y+146591X0200Y         S0      
317GND              VIA   -    MD0100PA00X+066200Y+145645X0200Y         S0      
317GND              VIA   -    MD0100PA00X+067943Y+138679X0180Y         S0      
317GND              VIA   -    MD0100PA00X+067447Y+138679X0180Y         S0      
317GND              VIA   -    MD0100PA00X+066223Y+141099X0180Y         S0      
317GND              VIA   -    MD0100PA00X+066223Y+139908X0180Y         S0      
317GND              VIA   -    MD0100PA00X+067447Y+136989X0180Y         S0      
317GND              VIA   -    MD0100PA00X+067943Y+136989X0180Y         S0      
317GND              VIA   -    MD0100PA00X+067943Y+138180X0180Y         S0      
317GND              VIA   -    MD0080PA00X+065641Y+139658X0160Y         S0      
317GND              VIA   -    MD0080PA00X+065641Y+140850X0160Y         S0      
317GND              VIA   -    MD0100PA00X+067447Y+138180X0180Y         S0      
317GND              VIA   -    MD0100PA00X+067447Y+137488X0180Y         S0      
317GND              VIA   -    MD0100PA00X+067943Y+137488X0180Y         S0      
317GND              VIA   -    MD0100PA00X+066223Y+139399X0180Y         S0      
317GND              VIA   -    MD0100PA00X+066223Y+140600X0180Y         S0      
317GND              VIA   -    MD0100PA00X+066200Y+155881X0200Y         S0      
317GND              VIA   -    MD0100PA00X+066200Y+156354X0200Y         S0      
317GND              VIA   -    MD0100PA00X+066200Y+150724X0200Y         S0      
317GND              VIA   -    MD0100PA00X+066200Y+150251X0200Y         S0      
317GND              VIA   -    MD0100PA00X+066200Y+151198X0200Y         S0      
317GND              VIA   -    MD0100PA00X+066200Y+148716X0200Y         S0      
317GND              VIA   -    MD0100PA00X+066200Y+149189X0200Y         S0      
317GND              VIA   -    MD0100PA00X+066200Y+149662X0200Y         S0      
317GND              VIA   -    MD0100PA00X+066200Y+161434X0200Y         S0      
317GND              VIA   -    MD0100PA00X+066200Y+160961X0200Y         S0      
317GND              VIA   -    MD0100PA00X+066200Y+160488X0200Y         S0      
317GND              VIA   -    MD0100PA00X+066200Y+159898X0200Y         S0      
317GND              VIA   -    MD0100PA00X+066200Y+158363X0200Y         S0      
317GND              VIA   -    MD0100PA00X+066200Y+158952X0200Y         S0      
317GND              VIA   -    MD0100PA00X+066200Y+159425X0200Y         S0      
317GND              VIA   -    MD0100PA00X+066200Y+157417X0200Y         S0      
317GND              VIA   -    MD0100PA00X+066200Y+157890X0200Y         S0      
317GND              VIA   -    MD0100PA00X+066200Y+156828X0200Y         S0      
327GND              PEX1  -AJ19M      A01X+066949Y+115000X0180Y         S1      
327GND              PEX1  -AJ24       A01X+068819Y+115000X0180Y         S1      
327GND              PEX1  -AJ21M      A01X+067697Y+115000X0180Y         S1      
327GND              PEX1  -AJ23M      A01X+068445Y+115000X0180Y         S1      
327GND              PEX1  -AJ22M      A01X+068071Y+115000X0180Y         S1      
327GND              PEX1  -AJ20M      A01X+067323Y+115000X0180Y         S1      
327GND              PEX1  -AJ18M      A01X+066575Y+115000X0180Y         S1      
327GND              PEX1  -AK15M      A01X+065453Y+114626X0180Y         S1      
327GND              PEX1  -AJ17M      A01X+066201Y+115000X0180Y         S1      
327GND              PEX1  -AJ16M      A01X+065827Y+115000X0180Y         S1      
327GND              PEX1  -AL19M      A01X+066949Y+114252X0180Y         S1      
327GND              PEX1  -AL23M      A01X+068445Y+114252X0180Y         S1      
327GND              PEX1  -AL24       A01X+068819Y+114252X0180Y         S1      
327GND              PEX1  -AL22M      A01X+068071Y+114252X0180Y         S1      
327GND              PEX1  -AL20M      A01X+067323Y+114252X0180Y         S1      
327GND              PEX1  -AL21M      A01X+067697Y+114252X0180Y         S1      
327GND              PEX1  -AL18M      A01X+066575Y+114252X0180Y         S1      
327GND              PEX1  -AL17M      A01X+066201Y+114252X0180Y         S1      
327GND              PEX1  -AL16M      A01X+065827Y+114252X0180Y         S1      
327GND              PEX1  -M21        A01X+067697Y+121358X0180Y         S1      
327GND              PEX1  -AF21       A01X+067697Y+116122X0180Y         S1      
327GND              PEX1  -AG20M      A01X+067323Y+115748X0180Y         S1      
327GND              PEX1  -AD19M      A01X+066949Y+116870X0180Y         S1      
327GND              PEX1  -AE20       A01X+067323Y+116496X0180Y         S1      
327GND              PEX1  -AC18M      A01X+066575Y+117244X0180Y         S1      
327GND              PEX1  -AE22       A01X+068071Y+116496X0180Y         S1      
327GND              PEX1  -AD21M      A01X+067697Y+116870X0180Y         S1      
327GND              PEX1  -AC20M      A01X+067323Y+117244X0180Y         S1      
327GND              PEX1  -AF23       A01X+068445Y+116122X0180Y         S1      
327GND              PEX1  -AG22M      A01X+068071Y+115748X0180Y         S1      
327GND              PEX1  -AC22M      A01X+068071Y+117244X0180Y         S1      
327GND              PEX1  -AE24       A01X+068819Y+116496X0180Y         S1      
327GND              PEX1  -AD23M      A01X+068445Y+116870X0180Y         S1      
317GND              VIA   -    MD0100PA00X+072343Y+140590X0180Y         S0      
317GND              VIA   -    MD0080PA00X+070537Y+136010X0160Y         S0      
317GND              VIA   -    MD0100PA00X+072343Y+139399X0180Y         S0      
317GND              VIA   -    MD0100PA00X+071119Y+134569X0180Y         S0      
317GND              VIA   -    MD0100PA00X+071615Y+134569X0180Y         S0      
317GND              VIA   -    MD0100PA00X+072343Y+139898X0180Y         S0      
317GND              VIA   -    MD0100PA00X+071119Y+135068X0180Y         S0      
317GND              VIA   -    MD0100PA00X+071615Y+135068X0180Y         S0      
317GND              VIA   -    MD0080PA00X+070537Y+134819X0160Y         S0      
317GND              VIA   -    MD0100PA00X+070391Y+137488X0180Y         S0      
317GND              VIA   -    MD0100PA00X+069895Y+136989X0180Y         S0      
317GND              VIA   -    MD0100PA00X+066719Y+139399X0180Y         S0      
317GND              VIA   -    MD0100PA00X+069895Y+138180X0180Y         S0      
317GND              VIA   -    MD0100PA00X+069895Y+137488X0180Y         S0      
317GND              VIA   -    MD0100PA00X+066719Y+140600X0180Y         S0      
317GND              VIA   -    MD0080PA00X+066865Y+139658X0160Y         S0      
317GND              VIA   -    MD0080PA00X+066865Y+140850X0160Y         S0      
317GND              VIA   -    MD0100PA00X+066719Y+139908X0180Y         S0      
317GND              VIA   -    MD0100PA00X+070391Y+136989X0180Y         S0      
317GND              VIA   -    MD0100PA00X+070391Y+138180X0180Y         S0      
317GND              VIA   -    MD0100PA00X+071615Y+136260X0180Y         S0      
317GND              VIA   -    MD0100PA00X+071119Y+136260X0180Y         S0      
317GND              VIA   -    MD0100PA00X+071119Y+135760X0180Y         S0      
317GND              VIA   -    MD0100PA00X+071615Y+135760X0180Y         S0      
317GND              VIA   -    MD0100PA00X+072343Y+141090X0180Y         S0      
317GND              VIA   -    MD0100PA00X+067066Y+148087X0200Y         S0      
317GND              VIA   -    MD0100PA00X+067932Y+147180X0200Y         S0      
317GND              VIA   -    MD0100PA00X+067932Y+147654X0200Y         S0      
317GND              VIA   -    MD0100PA00X+067932Y+148127X0200Y         S0      
317GND              VIA   -    MD0100PA00X+067066Y+147614X0200Y         S0      
317GND              VIA   -    MD0100PA00X+067066Y+147024X0200Y         S0      
317GND              VIA   -    MD0100PA00X+067066Y+146551X0200Y         S0      
317GND              VIA   -    MD0100PA00X+067066Y+146078X0200Y         S0      
317GND              VIA   -    MD0100PA00X+067932Y+146591X0200Y         S0      
317GND              VIA   -    MD0100PA00X+067932Y+145645X0200Y         S0      
317GND              VIA   -    MD0100PA00X+067932Y+146118X0200Y         S0      
317GND              VIA   -    MD0100PA00X+069895Y+138679X0180Y         S0      
317GND              VIA   -    MD0100PA00X+066719Y+141099X0180Y         S0      
317GND              VIA   -    MD0100PA00X+070391Y+138679X0180Y         S0      
317GND              VIA   -    MD0100PA00X+067066Y+156788X0200Y         S0      
317GND              VIA   -    MD0100PA00X+067066Y+157850X0200Y         S0      
317GND              VIA   -    MD0100PA00X+067066Y+157261X0200Y         S0      
317GND              VIA   -    MD0100PA00X+067932Y+156828X0200Y         S0      
317GND              VIA   -    MD0100PA00X+067932Y+157417X0200Y         S0      
317GND              VIA   -    MD0100PA00X+067932Y+157890X0200Y         S0      
317GND              VIA   -    MD0100PA00X+067932Y+156354X0200Y         S0      
317GND              VIA   -    MD0100PA00X+067066Y+156314X0200Y         S0      
317GND              VIA   -    MD0100PA00X+067932Y+155881X0200Y         S0      
317GND              VIA   -    MD0100PA00X+067066Y+151631X0200Y         S0      
317GND              VIA   -    MD0100PA00X+067066Y+151158X0200Y         S0      
317GND              VIA   -    MD0100PA00X+067932Y+150724X0200Y         S0      
317GND              VIA   -    MD0100PA00X+067932Y+150251X0200Y         S0      
317GND              VIA   -    MD0100PA00X+067932Y+151198X0200Y         S0      
317GND              VIA   -    MD0100PA00X+067066Y+150684X0200Y         S0      
317GND              VIA   -    MD0100PA00X+067066Y+150095X0200Y         S0      
317GND              VIA   -    MD0100PA00X+067932Y+149189X0200Y         S0      
317GND              VIA   -    MD0100PA00X+067932Y+149662X0200Y         S0      
317GND              VIA   -    MD0100PA00X+067066Y+149149X0200Y         S0      
317GND              VIA   -    MD0100PA00X+067066Y+148560X0200Y         S0      
317GND              VIA   -    MD0100PA00X+067066Y+149622X0200Y         S0      
317GND              VIA   -    MD0100PA00X+067932Y+148716X0200Y         S0      
317GND              VIA   -    MD0100PA00X+067200Y+164498X0200Y         S0      
317GND              VIA   -    MD0100PA00X+067066Y+161394X0200Y         S0      
317GND              VIA   -    MD0100PA00X+067066Y+161867X0200Y         S0      
317GND              VIA   -    MD0100PA00X+067932Y+161434X0200Y         S0      
317GND              VIA   -    MD0100PA00X+067932Y+159898X0200Y         S0      
317GND              VIA   -    MD0100PA00X+067066Y+160921X0200Y         S0      
317GND              VIA   -    MD0100PA00X+067066Y+159858X0200Y         S0      
317GND              VIA   -    MD0100PA00X+067066Y+160332X0200Y         S0      
317GND              VIA   -    MD0100PA00X+067932Y+160961X0200Y         S0      
317GND              VIA   -    MD0100PA00X+067932Y+160488X0200Y         S0      
317GND              VIA   -    MD0100PA00X+067932Y+158952X0200Y         S0      
317GND              VIA   -    MD0100PA00X+067932Y+159425X0200Y         S0      
317GND              VIA   -    MD0100PA00X+067066Y+158323X0200Y         S0      
317GND              VIA   -    MD0100PA00X+067066Y+159385X0200Y         S0      
317GND              VIA   -    MD0100PA00X+067066Y+158796X0200Y         S0      
317GND              VIA   -    MD0100PA00X+067932Y+158363X0200Y         S0      
327GND              PEX1  -AD25       A01X+069193Y+116870X0180Y         S1      
327GND              PEX1  -AC26M      A01X+069567Y+117244X0180Y         S1      
327GND              PEX1  -AF25       A01X+069193Y+116122X0180Y         S1      
327GND              PEX1  -AG26M      A01X+069567Y+115748X0180Y         S1      
327GND              PEX1  -AN18M      A01X+066575Y+113504X0180Y         S1      
327GND              PEX1  -AN17M      A01X+066201Y+113504X0180Y         S1      
327GND              PEX1  -AN16M      A01X+065827Y+113504X0180Y         S1      
327GND              PEX1  -AN15M      A01X+065453Y+113504X0180Y         S1      
327GND              PEX1  -AN19M      A01X+066949Y+113504X0180Y         S1      
327GND              PEX1  -AN21M      A01X+067697Y+113504X0180Y         S1      
327GND              PEX1  -AN22M      A01X+068071Y+113504X0180Y         S1      
327GND              PEX1  -AN23M      A01X+068445Y+113504X0180Y         S1      
327GND              PEX1  -AN24       A01X+068819Y+113504X0180Y         S1      
327GND              PEX1  -AN20M      A01X+067323Y+113504X0180Y         S1      
327GND              PEX1  -AP15M      A01X+065453Y+113130X0180Y         S1      
327GND              PEX1  -AR15M      A01X+065453Y+112756X0180Y         S1      
327GND              PEX1  -AM15       A01X+065453Y+113878X0180Y         S1      
317GND              VIA   -    MD0100PA00X+072839Y+140590X0180Y         S0      
317GND              VIA   -    MD0100PA00X+072343Y+136260X0180Y         S0      
317GND              VIA   -    MD0100PA00X+072343Y+135760X0180Y         S0      
317GND              VIA   -    MD0100PA00X+072839Y+136260X0180Y         S0      
317GND              VIA   -    MD0100PA00X+072839Y+135760X0180Y         S0      
317GND              VIA   -    MD0100PA00X+072839Y+141090X0180Y         S0      
317GND              VIA   -    MD0080PA00X+072985Y+140840X0160Y         S0      
317GND              VIA   -    MD0080PA00X+072985Y+139649X0160Y         S0      
317GND              VIA   -    MD0100PA00X+072839Y+135068X0180Y         S0      
317GND              VIA   -    MD0100PA00X+072839Y+139399X0180Y         S0      
317GND              VIA   -    MD0100PA00X+072343Y+134569X0180Y         S0      
317GND              VIA   -    MD0100PA00X+072839Y+134569X0180Y         S0      
317GND              VIA   -    MD0100PA00X+072839Y+139898X0180Y         S0      
317GND              VIA   -    MD0100PA00X+072343Y+135068X0180Y         S0      
317GND              VIA   -    MD0100PA00X+068798Y+148087X0200Y         S0      
317GND              VIA   -    MD0100PA00X+069664Y+147654X0200Y         S0      
317GND              VIA   -    MD0100PA00X+069664Y+147181X0200Y         S0      
317GND              VIA   -    MD0100PA00X+069664Y+148127X0200Y         S0      
317GND              VIA   -    MD0100PA00X+068798Y+147614X0200Y         S0      
317GND              VIA   -    MD0100PA00X+068798Y+147024X0200Y         S0      
317GND              VIA   -    MD0100PA00X+068798Y+146551X0200Y         S0      
317GND              VIA   -    MD0100PA00X+068798Y+146078X0200Y         S0      
317GND              VIA   -    MD0100PA00X+069664Y+146591X0200Y         S0      
317GND              VIA   -    MD0100PA00X+069664Y+145645X0200Y         S0      
317GND              VIA   -    MD0100PA00X+069664Y+146118X0200Y         S0      
317GND              VIA   -    MD0100PA00X+071119Y+138679X0180Y         S0      
317GND              VIA   -    MD0100PA00X+067943Y+141099X0180Y         S0      
317GND              VIA   -    MD0100PA00X+067447Y+141099X0180Y         S0      
317GND              VIA   -    MD0100PA00X+071119Y+138180X0180Y         S0      
317GND              VIA   -    MD0100PA00X+071119Y+137488X0180Y         S0      
317GND              VIA   -    MD0080PA00X+068089Y+139658X0160Y         S0      
317GND              VIA   -    MD0080PA00X+068089Y+140850X0160Y         S0      
317GND              VIA   -    MD0100PA00X+067447Y+139908X0180Y         S0      
317GND              VIA   -    MD0100PA00X+067943Y+139409X0180Y         S0      
317GND              VIA   -    MD0100PA00X+067447Y+139409X0180Y         S0      
317GND              VIA   -    MD0100PA00X+067943Y+140600X0180Y         S0      
317GND              VIA   -    MD0100PA00X+067943Y+139908X0180Y         S0      
317GND              VIA   -    MD0100PA00X+067447Y+140600X0180Y         S0      
317GND              VIA   -    MD0100PA00X+071119Y+136989X0180Y         S0      
317GND              VIA   -    MD0100PA00X+069664Y+158363X0200Y         S0      
317GND              VIA   -    MD0100PA00X+068798Y+159385X0200Y         S0      
317GND              VIA   -    MD0100PA00X+068798Y+158796X0200Y         S0      
317GND              VIA   -    MD0100PA00X+069664Y+159425X0200Y         S0      
317GND              VIA   -    MD0100PA00X+069664Y+158952X0200Y         S0      
317GND              VIA   -    MD0100PA00X+068798Y+156788X0200Y         S0      
317GND              VIA   -    MD0100PA00X+069664Y+156828X0200Y         S0      
317GND              VIA   -    MD0100PA00X+068798Y+157850X0200Y         S0      
317GND              VIA   -    MD0100PA00X+068798Y+157261X0200Y         S0      
317GND              VIA   -    MD0100PA00X+069664Y+157890X0200Y         S0      
317GND              VIA   -    MD0100PA00X+069664Y+157417X0200Y         S0      
317GND              VIA   -    MD0100PA00X+068798Y+156314X0200Y         S0      
317GND              VIA   -    MD0100PA00X+069664Y+156354X0200Y         S0      
317GND              VIA   -    MD0100PA00X+069664Y+155881X0200Y         S0      
317GND              VIA   -    MD0100PA00X+068798Y+151631X0200Y         S0      
317GND              VIA   -    MD0100PA00X+068798Y+150684X0200Y         S0      
317GND              VIA   -    MD0100PA00X+068798Y+150095X0200Y         S0      
317GND              VIA   -    MD0100PA00X+068798Y+151158X0200Y         S0      
317GND              VIA   -    MD0100PA00X+069664Y+150725X0200Y         S0      
317GND              VIA   -    MD0100PA00X+069664Y+150252X0200Y         S0      
317GND              VIA   -    MD0100PA00X+069664Y+151198X0200Y         S0      
317GND              VIA   -    MD0100PA00X+069664Y+148716X0200Y         S0      
317GND              VIA   -    MD0100PA00X+069664Y+149662X0200Y         S0      
317GND              VIA   -    MD0100PA00X+068798Y+149149X0200Y         S0      
317GND              VIA   -    MD0100PA00X+068798Y+148560X0200Y         S0      
317GND              VIA   -    MD0100PA00X+068798Y+149622X0200Y         S0      
317GND              VIA   -    MD0100PA00X+069664Y+149189X0200Y         S0      
317GND              VIA   -    MD0100PA00X+069200Y+164498X0200Y         S0      
317GND              VIA   -    MD0100PA00X+068798Y+161867X0200Y         S0      
317GND              VIA   -    MD0100PA00X+069664Y+161434X0200Y         S0      
317GND              VIA   -    MD0100PA00X+068798Y+161394X0200Y         S0      
317GND              VIA   -    MD0100PA00X+069664Y+160488X0200Y         S0      
317GND              VIA   -    MD0100PA00X+068798Y+160921X0200Y         S0      
317GND              VIA   -    MD0100PA00X+068798Y+159858X0200Y         S0      
317GND              VIA   -    MD0100PA00X+068798Y+160332X0200Y         S0      
317GND              VIA   -    MD0100PA00X+069664Y+160961X0200Y         S0      
317GND              VIA   -    MD0100PA00X+069664Y+159898X0200Y         S0      
317GND              VIA   -    MD0100PA00X+068798Y+158323X0200Y         S0      
327GND              PEX1  -AC28M      A01X+070315Y+117244X0180Y         S1      
327GND              PEX1  -AD27M      A01X+069941Y+116870X0180Y         S1      
327GND              PEX1  -AE26       A01X+069567Y+116496X0180Y         S1      
327GND              PEX1  -AC30M      A01X+071063Y+117244X0180Y         S1      
327GND              PEX1  -AD29M      A01X+070689Y+116870X0180Y         S1      
327GND              PEX1  -AE28       A01X+070315Y+116496X0180Y         S1      
327GND              PEX1  -AF27       A01X+069941Y+116122X0180Y         S1      
327GND              PEX1  -AG28M      A01X+070315Y+115748X0180Y         S1      
327GND              PEX1  -AG30M      A01X+071063Y+115748X0180Y         S1      
327GND              PEX1  -AF29       A01X+070689Y+116122X0180Y         S1      
317GND              VIA   -    MD0100PA00X+073567Y+137488X0180Y         S0      
317GND              VIA   -    MD0100PA00X+073567Y+136989X0180Y         S0      
317GND              VIA   -    MD0100PA00X+074063Y+134569X0180Y         S0      
317GND              VIA   -    MD0100PA00X+073567Y+134569X0180Y         S0      
317GND              VIA   -    MD0100PA00X+074063Y+135068X0180Y         S0      
317GND              VIA   -    MD0100PA00X+073567Y+135068X0180Y         S0      
317GND              VIA   -    MD0100PA00X+069167Y+139908X0180Y         S0      
317GND              VIA   -    MD0100PA00X+069167Y+140600X0180Y         S0      
317GND              VIA   -    MD0100PA00X+069167Y+139409X0180Y         S0      
317GND              VIA   -    MD0100PA00X+071615Y+136989X0180Y         S0      
317GND              VIA   -    MD0100PA00X+071615Y+138180X0180Y         S0      
317GND              VIA   -    MD0100PA00X+071615Y+137488X0180Y         S0      
317GND              VIA   -    MD0100PA00X+068671Y+139908X0180Y         S0      
317GND              VIA   -    MD0100PA00X+068671Y+140600X0180Y         S0      
317GND              VIA   -    MD0100PA00X+068671Y+139409X0180Y         S0      
317GND              VIA   -    MD0100PA00X+073567Y+138180X0180Y         S0      
317GND              VIA   -    MD0100PA00X+073567Y+138679X0180Y         S0      
317GND              VIA   -    MD0100PA00X+074063Y+136260X0180Y         S0      
317GND              VIA   -    MD0100PA00X+074063Y+135760X0180Y         S0      
317GND              VIA   -    MD0100PA00X+073567Y+136260X0180Y         S0      
317GND              VIA   -    MD0100PA00X+073567Y+135760X0180Y         S0      
317GND              VIA   -    MD0100PA00X+072455Y+095829X0200Y         S0      
317GND              VIA   -    MD0100PA00X+072037Y+094031X0200Y         S0      
317GND              VIA   -    MD0100PA00X+072532Y+089035X0200Y         S0      
317GND              VIA   -    MD0100PA00X+071200Y+164498X0200Y         S0      
317GND              VIA   -    MD0100PA00X+069167Y+141099X0180Y         S0      
317GND              VIA   -    MD0100PA00X+071615Y+138679X0180Y         S0      
317GND              VIA   -    MD0100PA00X+068671Y+141099X0180Y         S0      
327GND              PEX1  -AD31M      A01X+071437Y+116870X0180Y         S1      
327GND              PEX1  -AE30       A01X+071063Y+116496X0180Y         S1      
327GND              PEX1  -AC32M      A01X+071811Y+117244X0180Y         S1      
327GND              C3187 -2          A18X+073494Y+118179X0120Y0150     S2      
327GND              PEX1  -AA30M      A01X+071063Y+117992X0180Y         S1      
327GND              PEX1  -AA32M      A01X+071811Y+117992X0180Y         S1      
327GND              PEX1  -Y34 M      A01X+072559Y+118366X0180Y         S1      
327GND              PEX1  -AA33M      A01X+072185Y+117992X0180Y         S1      
327GND              PEX1  -AA31M      A01X+071437Y+117992X0180Y         S1      
327GND              PEX1  -AA29M      A01X+070689Y+117992X0180Y         S1      
327GND              PEX1  -AA28M      A01X+070315Y+117992X0180Y         S1      
327GND              PEX1  -AA27M      A01X+069941Y+117992X0180Y         S1      
327GND              PEX1  -AA25       A01X+069193Y+117992X0180Y         S1      
327GND              PEX1  -AA26M      A01X+069567Y+117992X0180Y         S1      
327GND              PEX1  -AE32       A01X+071811Y+116496X0180Y         S1      
327GND              PEX1  -AF31       A01X+071437Y+116122X0180Y         S1      
327GND              PEX1  -AG32M      A01X+071811Y+115748X0180Y         S1      
327GND              PEX1  -AN30M      A01X+071063Y+113504X0180Y         S1      
327GND              PEX1  -AN31M      A01X+071437Y+113504X0180Y         S1      
327GND              PEX1  -AN35M      A01X+072933Y+113504X0180Y         S1      
327GND              PEX1  -AN34M      A01X+072559Y+113504X0180Y         S1      
327GND              PEX1  -AN33M      A01X+072185Y+113504X0180Y         S1      
327GND              PEX1  -AM34       A01X+072559Y+113878X0180Y         S1      
327GND              PEX1  -AN32M      A01X+071811Y+113504X0180Y         S1      
327GND              PEX1  -AN29M      A01X+070689Y+113504X0180Y         S1      
327GND              PEX1  -AN28M      A01X+070315Y+113504X0180Y         S1      
327GND              PEX1  -AN25       A01X+069193Y+113504X0180Y         S1      
327GND              PEX1  -AN26M      A01X+069567Y+113504X0180Y         S1      
327GND              PEX1  -AN27M      A01X+069941Y+113504X0180Y         S1      
317GND              VIA   -    MD0100PA00X+075287Y+135068X0180Y         S0      
317GND              VIA   -    MD0100PA00X+075287Y+134569X0180Y         S0      
317GND              VIA   -    MD0080PA00X+074209Y+137238X0160Y         S0      
317GND              VIA   -    MD0100PA00X+074063Y+137488X0180Y         S0      
317GND              VIA   -    MD0100PA00X+074791Y+135068X0180Y         S0      
317GND              VIA   -    MD0100PA00X+074063Y+136989X0180Y         S0      
317GND              VIA   -    MD0100PA00X+074791Y+134569X0180Y         S0      
317GND              VIA   -    MD0100PA00X+069895Y+141099X0180Y         S0      
317GND              VIA   -    MD0100PA00X+072343Y+138679X0180Y         S0      
317GND              VIA   -    MD0100PA00X+072839Y+138679X0180Y         S0      
317GND              VIA   -    MD0100PA00X+069895Y+139409X0180Y         S0      
317GND              VIA   -    MD0100PA00X+069895Y+140600X0180Y         S0      
317GND              VIA   -    MD0100PA00X+069895Y+139908X0180Y         S0      
317GND              VIA   -    MD0100PA00X+072343Y+137488X0180Y         S0      
317GND              VIA   -    MD0100PA00X+072343Y+138180X0180Y         S0      
317GND              VIA   -    MD0100PA00X+072343Y+136989X0180Y         S0      
317GND              VIA   -    MD0100PA00X+072839Y+136989X0180Y         S0      
317GND              VIA   -    MD0100PA00X+072839Y+137488X0180Y         S0      
317GND              VIA   -    MD0100PA00X+072839Y+138180X0180Y         S0      
317GND              VIA   -    MD0080PA00X+069313Y+139658X0160Y         S0      
317GND              VIA   -    MD0080PA00X+069313Y+140850X0160Y         S0      
317GND              VIA   -    MD0080PA00X+072985Y+138430X0160Y         S0      
317GND              VIA   -    MD0080PA00X+072985Y+137238X0160Y         S0      
317GND              VIA   -    MD0100PA00X+074791Y+136260X0180Y         S0      
317GND              VIA   -    MD0100PA00X+074791Y+135760X0180Y         S0      
317GND              VIA   -    MD0080PA00X+074209Y+138430X0160Y         S0      
317GND              VIA   -    MD0100PA00X+075287Y+136260X0180Y         S0      
317GND              VIA   -    MD0100PA00X+075287Y+135760X0180Y         S0      
317GND              VIA   -    MD0100PA00X+074063Y+138679X0180Y         S0      
317GND              VIA   -    MD0100PA00X+074063Y+138180X0180Y         S0      
317GND              VIA   -    M      A01X+074567Y+100701X0200Y         S2      
017GND              VIA   -    M      A18X+074567Y+100701X0260Y         S2      
017GND                    -    MD0100PA00X+074567Y+100701                       
317GND              VIA   -    M      A01X+073871Y+098795X0200Y         S2      
017GND              VIA   -    M      A18X+073871Y+098795X0260Y         S2      
017GND                    -    MD0100PA00X+073871Y+098795                       
317GND              VIA   -    MD0100PA00X+073200Y+164498X0200Y         S0      
327GND              PEX1  -W38        A01X+074055Y+118740X0180Y         S1      
327GND              R1312 -2          A18X+074853Y+117648X0198Y0197R090 S2      
327GND              PEX1  -AF37       A01X+073681Y+116122X0180Y         S1      
327GND              PEX1  -AC35M      A01X+072933Y+117244X0180Y         S1      
327GND              PEX1  -AC34       A01X+072559Y+117244X0180Y         S1      
327GND              PEX1  -AB34M      A01X+072559Y+117618X0180Y         S1      
327GND              PEX1  -AD35M      A01X+072933Y+116870X0180Y         S1      
327GND              PEX1  -AE35       A01X+072933Y+116496X0180Y         S1      
327GND              PEX1  -W36 M      A01X+073307Y+118740X0180Y         S1      
327GND              PEX1  -AA36M      A01X+073307Y+117992X0180Y         S1      
327GND              PEX1  -AB36M      A01X+073307Y+117618X0180Y         S1      
327GND              PEX1  -V36 M      A01X+073307Y+119114X0180Y         S1      
327GND              PEX1  -AE37       A01X+073681Y+116496X0180Y         S1      
327GND              PEX1  -AD37M      A01X+073681Y+116870X0180Y         S1      
327GND              PEX1  -AC37M      A01X+073681Y+117244X0180Y         S1      
327GND              PEX1  -AB38M      A01X+074055Y+117618X0180Y         S1      
327GND              PEX1  -AB37M      A01X+073681Y+117618X0180Y         S1      
327GND              PEX1  -AA38M      A01X+074055Y+117992X0180Y         S1      
327GND              PEX1  -Y37 M      A01X+073681Y+118366X0180Y         S1      
327GND              PEX1  -Y38 M      A01X+074055Y+118366X0180Y         S1      
327GND              PEX1  -W37 M      A01X+073681Y+118740X0180Y         S1      
327GND              PEX1  -T37        A01X+073681Y+119862X0180Y         S1      
327GND              PEX1  -V37 M      A01X+073681Y+119114X0180Y         S1      
327GND              PEX1  -V38 M      A01X+074055Y+119114X0180Y         S1      
327GND              PEX1  -U37 M      A01X+073681Y+119488X0180Y         S1      
327GND              PEX1  -Y36 M      A01X+073307Y+118366X0180Y         S1      
327GND              PEX1  -AG37       A01X+073681Y+115748X0180Y         S1      
317GND              VIA   -    MD0080PA00X+070537Y+139658X0160Y         S0      
317GND              VIA   -    MD0080PA00X+070537Y+140850X0160Y         S0      
317GND              VIA   -    MD0100PA00X+075287Y+136989X0180Y         S0      
317GND              VIA   -    MD0100PA00X+075287Y+138180X0180Y         S0      
317GND              VIA   -    MD0100PA00X+075287Y+137488X0180Y         S0      
317GND              VIA   -    MD0100PA00X+074063Y+141090X0180Y         S0      
317GND              VIA   -    MD0100PA00X+074063Y+140590X0180Y         S0      
317GND              VIA   -    MD0100PA00X+073567Y+141090X0180Y         S0      
317GND              VIA   -    MD0100PA00X+073567Y+140590X0180Y         S0      
317GND              VIA   -    MD0080PA00X+074209Y+140840X0160Y         S0      
317GND              VIA   -    MD0100PA00X+076015Y+136260X0180Y         S0      
317GND              VIA   -    MD0100PA00X+076015Y+135760X0180Y         S0      
317GND              VIA   -    MD0100PA00X+073567Y+139898X0180Y         S0      
317GND              VIA   -    MD0100PA00X+074063Y+139898X0180Y         S0      
317GND              VIA   -    MD0100PA00X+074063Y+139399X0180Y         S0      
317GND              VIA   -    MD0100PA00X+073567Y+139399X0180Y         S0      
317GND              VIA   -    MD0080PA00X+074209Y+139649X0160Y         S0      
317GND              VIA   -    MD0100PA00X+076015Y+135068X0180Y         S0      
317GND              VIA   -    MD0100PA00X+076015Y+134560X0180Y         S0      
317GND              VIA   -    MD0100PA00X+070391Y+141099X0180Y         S0      
317GND              VIA   -    MD0100PA00X+074791Y+138679X0180Y         S0      
317GND              VIA   -    MD0100PA00X+075287Y+138679X0180Y         S0      
317GND              VIA   -    MD0100PA00X+074791Y+136989X0180Y         S0      
317GND              VIA   -    MD0100PA00X+070391Y+140600X0180Y         S0      
317GND              VIA   -    MD0100PA00X+070391Y+139908X0180Y         S0      
317GND              VIA   -    MD0100PA00X+074791Y+138180X0180Y         S0      
317GND              VIA   -    MD0100PA00X+074791Y+137488X0180Y         S0      
317GND              VIA   -    MD0100PA00X+070391Y+139409X0180Y         S0      
327GND              PEX1  -AF44       A01X+076299Y+116122X0180Y         S1      
317GND              VIA   -    MD0100PA00X+076511Y+135760X0180Y         S0      
317GND              VIA   -    MD0080PA00X+076657Y+136010X0160Y         S0      
317GND              VIA   -    MD0080PA00X+077881Y+136010X0160Y         S0      
317GND              VIA   -    MD0100PA00X+077239Y+134569X0180Y         S0      
317GND              VIA   -    MD0100PA00X+077735Y+134569X0180Y         S0      
317GND              VIA   -    MD0100PA00X+076511Y+134560X0180Y         S0      
317GND              VIA   -    MD0100PA00X+077735Y+135068X0180Y         S0      
317GND              VIA   -    MD0100PA00X+077239Y+135068X0180Y         S0      
317GND              VIA   -    MD0100PA00X+076511Y+135068X0180Y         S0      
317GND              VIA   -    MD0080PA00X+076657Y+134819X0160Y         S0      
317GND              VIA   -    MD0080PA00X+077881Y+134819X0160Y         S0      
317GND              VIA   -    MD0100PA00X+071119Y+141099X0180Y         S0      
317GND              VIA   -    MD0100PA00X+071615Y+141099X0180Y         S0      
317GND              VIA   -    MD0100PA00X+076015Y+138679X0180Y         S0      
317GND              VIA   -    MD0100PA00X+071119Y+139399X0180Y         S0      
317GND              VIA   -    MD0100PA00X+071615Y+139399X0180Y         S0      
317GND              VIA   -    MD0100PA00X+071119Y+140600X0180Y         S0      
317GND              VIA   -    MD0100PA00X+071119Y+139908X0180Y         S0      
317GND              VIA   -    MD0100PA00X+071615Y+140600X0180Y         S0      
317GND              VIA   -    MD0100PA00X+071615Y+139908X0180Y         S0      
317GND              VIA   -    MD0100PA00X+076015Y+136989X0180Y         S0      
317GND              VIA   -    MD0100PA00X+076015Y+138180X0180Y         S0      
317GND              VIA   -    MD0100PA00X+076015Y+137488X0180Y         S0      
317GND              VIA   -    MD0080PA00X+071761Y+139658X0160Y         S0      
317GND              VIA   -    MD0080PA00X+071761Y+140850X0160Y         S0      
317GND              VIA   -    MD0100PA00X+077735Y+136260X0180Y         S0      
317GND              VIA   -    MD0100PA00X+077735Y+135760X0180Y         S0      
317GND              VIA   -    MD0100PA00X+077239Y+136260X0180Y         S0      
317GND              VIA   -    MD0100PA00X+077239Y+135760X0180Y         S0      
317GND              VIA   -    MD0100PA00X+076511Y+136260X0180Y         S0      
317GND              VIA   -    MD0100PA00X+075200Y+164498X0200Y         S0      
317GND              VIA   -    MD0100PA00X+077200Y+164498X0200Y         S0      
317GND              VIA   -    MD0100PA00X+076511Y+138679X0180Y         S0      
317GND              VIA   -    MD0100PA00X+076511Y+136989X0180Y         S0      
317GND              VIA   -    MD0100PA00X+076511Y+138180X0180Y         S0      
317GND              VIA   -    MD0100PA00X+076511Y+137488X0180Y         S0      
317GND              VIA   -    MD0100PA00X+081298Y+082417X0200Y         S0      
317GND              VIA   -    MD0100PA00X+081357Y+074419X0200Y         S0      
317GND              VIA   -    MD0100PA00X+079356Y+164268X0200Y         S0      
317GND              VIA   -    MD0100PA00X+079451Y+141131X0200Y         S0      
317GND              VIA   -    MD0100PA00X+080939Y+118725X0200Y         S0      
317GND              VIA   -    MD0100PA00X+082043Y+080053X0200Y         S0      
317GND              VIA   -    MD0100PA00X+082055Y+078031X0200Y         S0      
317GND              VIA   -    MD0100PA00X+081999Y+075411X0200Y         S0      
317GND              VIA   -    MD0100PA00X+083048Y+074670X0200Y         S0      
327GND              R5416 -2          A01X+083448Y+074430X0198Y0197R090 S1      
327GND              R5417 -2   M      A01X+083048Y+074430X0198Y0197R090 S1      
317GND              VIA   -    M      A01X+083228Y+073122X0200Y         S2      
017GND              VIA   -    M      A18X+083228Y+073122X0260Y         S2      
017GND                    -    MD0100PA00X+083228Y+073122                       
317GND              VIA   -    MD0100PA00X+082384Y+073211X0200Y    R090 S0      
317GND              VIA   -    MD0100PA00X+082978Y+071394X0200Y         S0      
327GND              C3626 -2          A01X+083228Y+071344X0198Y0197R270 S1      
317GND              VIA   -    MD0100PA00X+082379Y+071338X0200Y    R090 S0      
317GND              VIA   -    MD0100PA00X+081146Y+163980X0200Y         S0      
317GND              VIA   -    M      A01X+081745Y+121009X0200Y         S2      
017GND              VIA   -    M      A18X+081745Y+121009X0260Y         S2      
017GND                    -    MD0100PA00X+081745Y+121009                       
317GND              VIA   -    MD0100PA00X+081149Y+119302X0200Y         S0      
327GND              R1315 -1          A01X+081149Y+119542X0198Y0197R090 S1      
317GND              VIA   -    MD0100PA00X+081549Y+119302X0200Y         S0      
327GND              R1317 -1          A01X+081549Y+119542X0198Y0197R090 S1      
317GND              VIA   -    MD0100PA00X+080749Y+119302X0200Y         S0      
327GND              R1314 -1          A01X+080749Y+119542X0198Y0197R090 S1      
317GND              VIA   -    MD0100PA00X+080962Y+116017X0200Y         S0      
317GND              VIA   -    MD0100PA00X+081503Y+115946X0200Y         S0      
317GND              VIA   -    MD0100PA00X+080968Y+113328X0200Y         S0      
317GND              VIA   -    MD0100PA00X+081281Y+090816X0200Y         S0      
317GND              VIA   -    MD0100PA00X+081473Y+088936X0200Y         S0      
327GND              U356  -3          A01X+081480Y+088553X0160Y0360R180 S1      
317GND              VIA   -    MD0100PA00X+081318Y+085280X0200Y         S0      
327GND              R5919 -1          A01X+080875Y+084092X0198Y0197     S1      
317GND              VIA   -    MD0100PA00X+081602Y+083804X0200Y         S0      
317GND              VIA   -    MD0100PA00X+082182Y+121446X0200Y         S0      
317GND              VIA   -    MD0100PA00X+081952Y+121216X0200Y         S0      
317GND              VIA   -    MD0100PA00X+082661Y+121925X0200Y         S0      
327GND              R1313 -1          A01X+082179Y+122407X0198Y0197R135 S1      
317GND              VIA   -    MD0100PA00X+081949Y+119302X0200Y         S0      
327GND              R1320 -1          A01X+081949Y+119542X0198Y0197R090 S1      
317GND              VIA   -    MD0100PA00X+082349Y+119302X0200Y         S0      
327GND              R4178 -1          A01X+082349Y+119542X0198Y0197R090 S1      
317GND              VIA   -    MD0100PA00X+082322Y+116282X0200Y         S0      
327GND              C2757 -1          A01X+082322Y+116522X0198Y0197R090 S1      
317GND              VIA   -    M      A01X+082574Y+114694X0200Y         S2      
017GND              VIA   -    M      A18X+082574Y+114694X0260Y         S2      
017GND                    -    MD0100PA00X+082574Y+114694                       
317GND              VIA   -    MD0100PA00X+082201Y+113021X0200Y         S0      
317GND              VIA   -    MD0100PA00X+081701Y+113303X0200Y         S0      
317GND              VIA   -    MD0100PA00X+082838Y+112060X0200Y         S0      
317GND              VIA   -    M      A01X+083243Y+097798X0200Y         S2      
017GND              VIA   -    M      A18X+083243Y+097798X0260Y         S2      
017GND                    -    MD0100PA00X+083243Y+097798                       
317GND              VIA   -    MD0100PA00X+082842Y+096473X0200Y    R090 S0      
317GND              VIA   -    MD0100PA00X+082819Y+094932X0200Y         S0      
317GND              VIA   -    MD0100PA00X+081835Y+093961X0200Y         S0      
317GND              VIA   -    MD0100PA00X+082551Y+091387X0200Y         S0      
317GND              VIA   -    MD0100PA00X+082246Y+091510X0200Y         S0      
317GND              VIA   -    MD0100PA00X+082577Y+089555X0200Y    R270 S0      
327GND              C2569 -1          A01X+082864Y+089616X0198Y0197R270 S1      
317GND              VIA   -    MD0100PA00X+082680Y+088376X0200Y         S0      
317GND              VIA   -    MD0100PA00X+082323Y+086768X0200Y    R270 S0      
327GND              C3644 -1          A01X+082003Y+086768X0198Y0197R090 S1      
317GND              VIA   -    MD0100PA00X+082569Y+086950X0200Y         S0      
317GND              VIA   -    MD0100PA00X+081913Y+086361X0200Y         S0      
327GND              U88   -4          A01X+081407Y+085920X0110Y0280R180 S1      
317GND              VIA   -    MD0100PA00X+082616Y+086300X0200Y         S0      
327GND              U89   -4          A01X+082616Y+085928X0110Y0280R180 S1      
317GND              VIA   -    MD0100PA00X+082572Y+083667X0200Y    R270 S0      
327GND              C2570 -1   M      A01X+082283Y+083667X0198Y0197R090 S1      
317GND              VIA   -    MD0100PA00X+082692Y+082300X0200Y         S0      
327GND              C2706 -1          A01X+082692Y+082050X0198Y0197     S1      
317GND              VIA   -    MD0100PA00X+081850Y+081400X0200Y         S0      
317GND              VIA   -    MD0100PA00X+081266Y+081003X0200Y         S0      
317GND              VIA   -    MD0100PA00X+083868Y+083299X0200Y         S0      
327GND              R5533 -1   M      A18X+084273Y+083546X0198Y0197R180 S2      
317GND              VIA   -    MD0100PA00X+082979Y+083902X0200Y    R270 S0      
317GND              VIA   -    MD0100PA00X+084950Y+081500X0200Y         S0      
317GND              VIA   -    MD0100PA00X+084150Y+081216X0200Y         S0      
317GND              VIA   -    MD0100PA00X+084648Y+074670X0200Y         S0      
327GND              R5414 -2          A01X+085048Y+074430X0198Y0197R090 S1      
327GND              R5415 -2   M      A01X+084648Y+074430X0198Y0197R090 S1      
317GND              VIA   -    M      A01X+084828Y+073118X0200Y         S2      
017GND              VIA   -    M      A18X+084828Y+073118X0260Y         S2      
017GND                    -    MD0100PA00X+084828Y+073118                       
317GND              VIA   -    MD0100PA00X+084578Y+071394X0200Y         S0      
327GND              C3625 -2          A01X+084828Y+071344X0198Y0197R270 S1      
317GND              VIA   -    MD0100PA00X+083146Y+163980X0200Y         S0      
317GND              VIA   -    MD0100PA00X+085565Y+068523X0200Y         S0      
327GND              U360  -3          A01X+085984Y+068523X0220Y0530R270 S1      
317GND              VIA   -    MD0100PA00X+085614Y+067789X0200Y         S0      
317GND              VIA   -    M      A01X+084373Y+100878X0200Y         S2      
017GND              VIA   -    M      A18X+084373Y+100878X0260Y         S2      
017GND                    -    MD0100PA00X+084373Y+100878                       
317GND              VIA   -    MD0100PA00X+083912Y+093966X0200Y         S0      
317GND              VIA   -    MD0100PA00X+083938Y+091584X0200Y         S0      
327GND              R4555 -1          A01X+084863Y+091266X0198Y0197R270 S1      
317GND              VIA   -    MD0100PA00X+084960Y+091527X0200Y         S0      
317GND              VIA   -    MD0100PA00X+083387Y+088186X0200Y         S0      
327GND              U302  -3          A01X+083192Y+087850X0160Y0360     S1      
317GND              VIA   -    MD0100PA00X+084565Y+089544X0200Y         S0      
317GND              VIA   -    MD0100PA00X+085225Y+100953X0200Y         S0      
317GND              VIA   -    MD0100PA00X+084909Y+095108X0200Y         S0      
317GND              VIA   -    MD0100PA00X+085587Y+093554X0200Y         S0      
317GND              VIA   -    MD0100PA00X+086425Y+091524X0200Y         S0      
327GND              R4549 -1          A01X+086463Y+091266X0198Y0197R270 S1      
317GND              VIA   -    MD0100PA00X+085663Y+091524X0200Y         S0      
327GND              R4553 -1          A01X+085663Y+091266X0198Y0197R270 S1      
317GND              VIA   -    MD0100PA00X+085116Y+085520X0200Y         S0      
327GND              R4861 -1          A18X+085373Y+085192X0198Y0197R180 S2      
327GND              C3621 -1   M      A18X+085368Y+085546X0198Y0197R180 S2      
317GND              VIA   -    MD0100PA00X+086458Y+082450X0200Y         S0      
327GND              C2555 -1          A01X+086458Y+082200X0198Y0197R180 S1      
317GND              VIA   -    MD0100PA00X+086446Y+082850X0200Y         S0      
317GND              VIA   -    MD0100PA00X+086500Y+083127X0200Y         S0      
317GND              VIA   -    M      A01X+086723Y+072206X0200Y         S2      
017GND              VIA   -    M      A18X+086723Y+072206X0260Y         S2      
017GND                    -    MD0100PA00X+086723Y+072206                       
317GND              VIA   -    M      A01X+085819Y+071317X0200Y         S2      
017GND              VIA   -    M      A18X+085819Y+071317X0260Y         S2      
017GND                    -    MD0100PA00X+085819Y+071317                       
327GND              R5497 -2          A01X+086069Y+071317X0198Y0197R180 S1      
317GND              VIA   -    MD0100PA00X+087332Y+074460X0200Y         S0      
317GND              VIA   -    MD0100PA00X+087861Y+074717X0200Y    R270 S0      
317GND              VIA   -    MD0100PA00X+087762Y+074948X0200Y         S0      
317GND              VIA   -    M      A01X+087302Y+071573X0200Y         S2      
017GND              VIA   -    M      A18X+087302Y+071573X0260Y         S2      
017GND                    -    MD0100PA00X+087302Y+071573                       
327GND              Q58   -1          A01X+087032Y+071573X0170Y0240R270 S1      
317GND              VIA   -    M      A01X+088050Y+071061X0200Y         S2      
017GND              VIA   -    M      A18X+088050Y+071061X0260Y         S2      
017GND                    -    MD0100PA00X+088050Y+071061                       
327GND              Q58   -4          A01X+087780Y+071061X0170Y0240R270 S1      
317GND              VIA   -    MD0100PA00X+087629Y+068697X0200Y         S0      
327GND              R3147 -2          A01X+087869Y+068697X0198Y0197R180 S1      
317GND              VIA   -    MD0100PA00X+087207Y+070089X0200Y         S0      
327GND              C3649 -1          A01X+087207Y+069839X0198Y0197R180 S1      
317GND              VIA   -    MD0100PA00X+086931Y+068849X0200Y         S0      
317GND              VIA   -    MD0100PA00X+085146Y+163980X0200Y         S0      
317GND              VIA   -    MD0100PA00X+086344Y+113934X0200Y         S0      
317GND              VIA   -    MD0100PA00X+086094Y+113934X0200Y         S0      
317GND              VIA   -    MD0100PA00X+086094Y+113034X0200Y         S0      
317GND              VIA   -    MD0100PA00X+085564Y+113034X0200Y         S0      
317GND              VIA   -    MD0100PA00X+085824Y+113034X0200Y         S0      
317GND              VIA   -    MD0100PA00X+086344Y+113034X0200Y         S0      
317GND              VIA   -    MD0100PA00X+086084Y+112064X0200Y         S0      
317GND              VIA   -    MD0100PA00X+085814Y+112064X0200Y         S0      
317GND              VIA   -    MD0100PA00X+085554Y+112064X0200Y         S0      
317GND              VIA   -    MD0100PA00X+086334Y+112064X0200Y         S0      
317GND              VIA   -    MD0100PA00X+086939Y+097800X0200Y         S0      
317GND              VIA   -    MD0100PA00X+086720Y+094937X0200Y         S0      
317GND              VIA   -    MD0100PA00X+086891Y+093364X0200Y         S0      
317GND              VIA   -    M      A01X+087648Y+094113X0200Y         S2      
017GND              VIA   -    M      A18X+087648Y+094113X0260Y         S2      
017GND                    -    MD0100PA00X+087648Y+094113                       
327GND              U418  -3          A01X+088643Y+094090X0220Y0530R270 S1      
327GND              R6218 -2   M      A01X+087974Y+094113X0198Y0197R270 S1      
317GND              VIA   -    MD0100PA00X+088063Y+091524X0200Y         S0      
327GND              R4547 -1          A01X+088063Y+091266X0198Y0197R270 S1      
317GND              VIA   -    MD0100PA00X+087263Y+091524X0200Y         S0      
327GND              R4548 -1          A01X+087263Y+091266X0198Y0197R270 S1      
317GND              VIA   -    MD0100PA00X+087270Y+081662X0200Y         S0      
327GND              R5537 -1          A01X+087592Y+081662X0198Y0197R270 S1      
317GND              VIA   -    MD0100PA00X+087592Y+080896X0200Y    R090 S0      
327GND              R5528 -1          A18X+087592Y+081346X0198Y0197R270 S2      
317GND              VIA   -    MD0100PA00X+087325Y+079875X0200Y         S0      
317GND              VIA   -    MD0100PA00X+087129Y+077181X0200Y    R270 S0      
327GND              U305  -4          A01X+087235Y+077590X0140Y0520R180 S1      
317GND              VIA   -    M      A01X+088314Y+125994X0200Y         S2      
017GND              VIA   -    M      A18X+088314Y+125994X0260Y         S2      
017GND                    -    MD0100PA00X+088314Y+125994                       
317GND              VIA   -    MD0100PA00X+087244Y+125078X0200Y    R180 S0      
317GND              VIA   -    MD0100PA00X+087244Y+124828X0200Y    R180 S0      
317GND              VIA   -    MD0100PA00X+087244Y+124138X0200Y    R180 S0      
317GND              VIA   -    MD0100PA00X+087244Y+124388X0200Y    R180 S0      
317GND              VIA   -    MD0100PA00X+087800Y+122441X0200Y         S0      
317GND              VIA   -    MD0100PA00X+087244Y+123698X0200Y    R180 S0      
317GND              VIA   -    MD0100PA00X+087244Y+123448X0200Y    R180 S0      
317GND              VIA   -    MD0100PA00X+087462Y+122451X0200Y    R270 S0      
317GND              VIA   -    MD0100PA00X+087162Y+122451X0200Y    R270 S0      
317GND              VIA   -    MD0100PA00X+087244Y+122758X0200Y    R180 S0      
317GND              VIA   -    MD0100PA00X+087244Y+123008X0200Y    R180 S0      
317GND              VIA   -    MD0100PA00X+087462Y+121611X0200Y    R270 S0      
317GND              VIA   -    MD0100PA00X+087462Y+121891X0200Y    R270 S0      
317GND              VIA   -    MD0100PA00X+087462Y+122171X0200Y    R270 S0      
317GND              VIA   -    MD0100PA00X+087162Y+121611X0200Y    R270 S0      
317GND              VIA   -    MD0100PA00X+087162Y+121891X0200Y    R270 S0      
317GND              VIA   -    MD0100PA00X+087162Y+122171X0200Y    R270 S0      
317GND              VIA   -    MD0100PA00X+087462Y+121331X0200Y    R270 S0      
317GND              VIA   -    MD0100PA00X+087162Y+121331X0200Y    R270 S0      
317GND              VIA   -    MD0100PA00X+089397Y+086734X0180Y    R270 S0      
327GND              U5    -K11        A01X+089554Y+086576X0160Y    R180 S1      
317GND              VIA   -    MD0100PA00X+089397Y+087364X0180Y    R270 S0      
327GND              U5    -M11        A01X+089554Y+087206X0160Y    R180 S1      
317GND              VIA   -    MD0100PA00X+089397Y+087049X0180Y    R270 S0      
327GND              U5    -L11        A01X+089554Y+086891X0160Y    R180 S1      
317GND              VIA   -    MD0100PA00X+089397Y+085474X0180Y    R270 S0      
327GND              U5    -G11        A01X+089554Y+085632X0160Y    R180 S1      
317GND              VIA   -    MD0100PA00X+089397Y+085789X0180Y    R270 S0      
327GND              U5    -H11        A01X+089554Y+085946X0160Y    R180 S1      
317GND              VIA   -    MD0100PA00X+089397Y+086419X0180Y    R270 S0      
327GND              U5    -J11        A01X+089554Y+086262X0160Y    R180 S1      
317GND              VIA   -    MD0100PA00X+089192Y+080896X0200Y         S0      
317GND              VIA   -    MD0100PA00X+088851Y+079760X0200Y         S0      
317GND              VIA   -    MD0100PA00X+088854Y+078553X0200Y         S0      
317GND              VIA   -    MD0100PA00X+088908Y+078037X0200Y         S0      
317GND              VIA   -    M      A01X+088684Y+072978X0200Y         S2      
017GND              VIA   -    M      A18X+088684Y+072978X0260Y         S2      
017GND                    -    MD0100PA00X+088684Y+072978                       
327GND              C2185 -2          A01X+088684Y+072718X0198Y0197     S1      
317GND              VIA   -    MD0100PA00X+088944Y+071597X0200Y    R180 S0      
327GND              Q57   -E          A01X+089332Y+071523X0320Y0360R090 S1      
317GND              VIA   -    MD0100PA00X+088490Y+069412X0200Y         S0      
327GND              U359  -2          A01X+088930Y+069412X0140Y0580R270 S1      
317GND              VIA   -    MD0100PA00X+087146Y+163980X0200Y         S0      
317GND              VIA   -    MD0100PA00X+089074Y+131113X0200Y         S0      
317GND              VIA   -    MD0100PA00X+089100Y+129276X0200Y         S0      
317GND              VIA   -    MD0100PA00X+089489Y+122721X0200Y         S0      
317GND              VIA   -    MD0100PA00X+089333Y+121289X0200Y    R270 S0      
317GND              VIA   -    MD0100PA00X+089319Y+120807X0200Y         S0      
327GND              PC241 -2          A01X+090139Y+120467X0198Y0197R270 S1      
327GND              PR172 -2   M      A01X+089743Y+120583X0198Y0197R270 S1      
317GND              VIA   -    M      A01X+088865Y+119962X0200Y    R270 S2      
017GND              VIA   -    M      A18X+088865Y+119962X0260Y    R270 S2      
017GND                    -    MD0100PA00X+088865Y+119962                       
327GND              PC230 -2          A01X+088865Y+120227X0198Y0197     S1      
317GND              VIA   -    MD0100PA00X+088489Y+109872X0200Y         S0      
327GND              C629  -2          A01X+088739Y+109872X0198Y0197R090 S1      
317GND              VIA   -    MD0100PA00X+088491Y+110276X0200Y         S0      
327GND              C826  -2          A01X+088731Y+110276X0198Y0197R180 S1      
317GND              VIA   -    MD0100PA00X+089706Y+109598X0200Y         S0      
317GND              VIA   -    MD0100PA00X+089106Y+109541X0200Y         S0      
317GND              VIA   -    MD0100PA00X+089706Y+109139X0200Y         S0      
317GND              VIA   -    M      A01X+090691Y+095149X0200Y         S2      
017GND              VIA   -    M      A18X+090691Y+095149X0260Y         S2      
017GND                    -    MD0100PA00X+090691Y+095149                       
327GND              C3988 -2          A01X+090691Y+094861X0198Y0197     S1      
317GND              VIA   -    MD0100PA00X+090671Y+096243X0200Y         S0      
317GND              VIA   -    MD0100PA00X+091136Y+094491X0200Y         S0      
317GND              VIA   -    MD0100PA00X+091263Y+092810X0200Y         S0      
327GND              R6193 -1          A01X+091263Y+092570X0198Y0197R270 S1      
317GND              VIA   -    MD0100PA00X+090483Y+091534X0200Y         S0      
327GND              R4554 -1          A18X+090329Y+091191X0198Y0197R090 S2      
317GND              VIA   -    MD0100PA00X+091286Y+086734X0180Y         S0      
327GND              U5    -K6         A01X+091129Y+086576X0160Y    R180 S1      
317GND              VIA   -    MD0100PA00X+091286Y+087049X0180Y         S0      
327GND              U5    -L6         A01X+091129Y+086891X0160Y    R180 S1      
317GND              VIA   -    MD0100PA00X+091286Y+085474X0180Y    R270 S0      
327GND              U5    -G6         A01X+091129Y+085632X0160Y    R180 S1      
317GND              VIA   -    MD0100PA00X+091286Y+085789X0180Y    R270 S0      
327GND              U5    -H6         A01X+091129Y+085946X0160Y    R180 S1      
317GND              VIA   -    MD0100PA00X+091286Y+086419X0180Y         S0      
327GND              U5    -J6         A01X+091129Y+086262X0160Y    R180 S1      
317GND              VIA   -    MD0100PA00X+091286Y+085159X0180Y    R270 S0      
327GND              U5    -F6         A01X+091129Y+085317X0160Y    R180 S1      
327GND              C2027 -2   M      A18X+091003Y+083688X0164Y0164R180 S2      
317GND              VIA   -    MD0100PA00X+090971Y+083899X0180Y    R180 S0      
327GND              U5    -B7         A01X+090814Y+084057X0160Y    R180 S1      
317GND              VIA   -    MD0100PA00X+091105Y+080051X0200Y    R090 S0      
317GND              VIA   -    MD0100PA00X+089992Y+080082X0200Y    R090 S0      
317GND              VIA   -    MD0100PA00X+091372Y+080082X0200Y    R090 S0      
317GND              VIA   -    MD0100PA00X+090505Y+072027X0200Y    R090 S0      
317GND              VIA   -    MD0100PA00X+091075Y+071586X0200Y         S0      
317GND              VIA   -    MD0100PA00X+090531Y+070926X0200Y    R090 S0      
317GND              VIA   -    MD0100PA00X+091004Y+070228X0200Y         S0      
327GND              C3646 -1          A01X+091004Y+069977X0198Y0197R180 S1      
327GND              Q56   -E          A01X+090732Y+070603X0320Y0360R090 S1      
317GND              VIA   -    M      A01X+091246Y+069577X0200Y    R270 S2      
017GND              VIA   -    M      A18X+091246Y+069577X0260Y    R270 S2      
017GND                    -    MD0100PA00X+091246Y+069577                       
327GND              R3150 -2          A01X+091004Y+069177X0198Y0197     S1      
327GND              C3647 -1   M      A01X+091004Y+069577X0198Y0197R180 S1      
317GND              VIA   -    MD0100PA00X+089146Y+163980X0200Y         S0      
317GND              VIA   -    MD0100PA00X+092179Y+081096X0200Y    R090 S0      
327GND              R5712 -2          A01X+092179Y+081346X0198Y0197R270 S1      
317GND              VIA   -    MD0100PA00X+091659Y+080064X0200Y    R090 S0      
317GND              VIA   -    MD0100PA00X+092493Y+070105X0200Y         S0      
327GND              U327  -3          A01X+092493Y+069688X0220Y0530R180 S1      
317GND              VIA   -    MD0100PA00X+091729Y+067962X0200Y         S0      
317GND              VIA   -    MD0100PA00X+092804Y+067780X0200Y         S0      
327GND              R4258 -2          A01X+092542Y+067780X0198Y0197R270 S1      
317GND              VIA   -    MD0100PA00X+091146Y+163980X0200Y         S0      
317GND              VIA   -    MD0100PA00X+090470Y+129740X0200Y         S0      
317GND              VIA   -    MD0100PA00X+090194Y+123930X0200Y         S0      
317GND              VIA   -    MD0100PA00X+090194Y+124370X0200Y         S0      
317GND              VIA   -    MD0100PA00X+090194Y+124620X0200Y         S0      
317GND              VIA   -    MD0100PA00X+090194Y+123240X0200Y         S0      
317GND              VIA   -    MD0100PA00X+090194Y+122990X0200Y         S0      
317GND              VIA   -    MD0100PA00X+090194Y+123680X0200Y         S0      
317GND              VIA   -    MD0100PA00X+090406Y+113595X0200Y         S0      
317GND              VIA   -    MD0100PA00X+090391Y+113287X0200Y         S0      
317GND              VIA   -    MD0100PA00X+090143Y+113643X0200Y    R090 S0      
317GND              VIA   -    MD0100PA00X+091164Y+112633X0200Y         S0      
317GND              VIA   -    MD0100PA00X+090904Y+112633X0200Y         S0      
317GND              VIA   -    MD0100PA00X+091170Y+112949X0200Y         S0      
317GND              VIA   -    MD0100PA00X+090567Y+111410X0200Y         S0      
317GND              VIA   -    MD0100PA00X+090307Y+111410X0200Y         S0      
317GND              VIA   -    MD0100PA00X+090827Y+111410X0200Y         S0      
317GND              VIA   -    MD0100PA00X+091097Y+111410X0200Y         S0      
317GND              VIA   -    MD0100PA00X+090837Y+112380X0200Y         S0      
317GND              VIA   -    MD0100PA00X+090317Y+112380X0200Y         S0      
317GND              VIA   -    MD0100PA00X+090577Y+112380X0200Y         S0      
317GND              VIA   -    MD0100PA00X+091107Y+112380X0200Y         S0      
317GND              VIA   -    MD0100PA00X+090169Y+109594X0200Y         S0      
317GND              VIA   -    MD0100PA00X+090174Y+109135X0200Y         S0      
317GND              VIA   -    MD0100PA00X+090930Y+102022X0200Y         S0      
317GND              VIA   -    MD0100PA00X+092490Y+112064X0200Y         S0      
317GND              VIA   -    MD0100PA00X+091711Y+110190X0200Y         S0      
317GND              VIA   -    MD0100PA00X+091675Y+108866X0200Y         S0      
327GND              R785  -2          A01X+091435Y+108866X0198Y0197     S1      
317GND              VIA   -    MD0100PA00X+091675Y+108066X0200Y         S0      
327GND              R784  -2          A01X+091435Y+108066X0198Y0197     S1      
317GND              VIA   -    MD0100PA00X+091549Y+096989X0200Y         S0      
317GND              VIA   -    MD0100PA00X+091865Y+096472X0200Y         S0      
317GND              VIA   -    MD0100PA00X+092449Y+095124X0200Y         S0      
317GND              VIA   -    MD0100PA00X+092463Y+092810X0200Y         S0      
327GND              R6190 -1          A01X+092463Y+092570X0198Y0197R270 S1      
327GND              R6185 -1          A18X+092463Y+092570X0198Y0197R090 S2      
317GND              VIA   -    MD0100PA00X+091663Y+092810X0200Y         S0      
327GND              R6192 -1          A01X+091663Y+092570X0198Y0197R270 S1      
327GND              R6186 -1          A18X+091663Y+092570X0198Y0197R090 S2      
317GND              VIA   -    MD0100PA00X+092863Y+092810X0200Y         S0      
327GND              R6189 -1          A01X+092863Y+092570X0198Y0197R270 S1      
327GND              R6196 -1          A18X+092863Y+092570X0198Y0197R090 S2      
317GND              VIA   -    MD0100PA00X+092063Y+092810X0200Y         S0      
327GND              R6191 -1          A01X+092063Y+092570X0198Y0197R270 S1      
327GND              R6184 -1          A18X+092063Y+092570X0198Y0197R090 S2      
327GND              U5    -A1         A01X+092704Y+083742X0160Y    R180 S1      
317GND              VIA   -    MD0100PA00X+092861Y+083584X0180Y    R270 S0      
327GND              C195  -2          A18X+092576Y+083438X0198Y0197R090 S2      
317GND              VIA   -    MD0100PA00X+094563Y+078976X0200Y         S0      
327GND              C3620 -2          A01X+094366Y+079233X0198Y0197     S1      
317GND              VIA   -    MD0100PA00X+093603Y+073060X0200Y    R090 S0      
327GND              C3645 -1          A01X+093853Y+073060X0198Y0197R270 S1      
317GND              VIA   -    MD0100PA00X+093124Y+072047X0200Y    R090 S0      
317GND              VIA   -    M      A01X+093931Y+070785X0200Y    R090 S2      
017GND              VIA   -    M      A18X+093931Y+070785X0260Y    R090 S2      
017GND                    -    MD0100PA00X+093931Y+070785                       
327GND              U358  -1          A01X+093931Y+071215X0380Y0560     S1      
317GND              VIA   -    M      A01X+093528Y+067780X0200Y         S2      
017GND              VIA   -    M      A18X+093528Y+067780X0260Y         S2      
017GND                    -    MD0100PA00X+093528Y+067780                       
327GND              C2808 -2          A01X+093241Y+067780X0198Y0197R270 S1      
317GND              VIA   -    MD0100PA00X+092715Y+132364X0200Y         S0      
317GND              VIA   -    MD0100PA00X+092715Y+132860X0200Y         S0      
317GND              VIA   -    MD0100PA00X+091464Y+121057X0200Y         S0      
327GND              PJ12  -2          A01X+091222Y+121057X0180Y0200R180 S1      
317GND              VIA   -    MD0100PA00X+092742Y+113934X0200Y         S0      
317GND              VIA   -    MD0100PA00X+092492Y+113934X0200Y         S0      
317GND              VIA   -    MD0100PA00X+092762Y+113034X0200Y         S0      
317GND              VIA   -    MD0100PA00X+092492Y+113034X0200Y         S0      
317GND              VIA   -    MD0100PA00X+091424Y+112633X0200Y         S0      
317GND              VIA   -    MD0100PA00X+091430Y+112949X0200Y         S0      
317GND              VIA   -    MD0100PA00X+091466Y+113261X0200Y         S0      
317GND              VIA   -    MD0100PA00X+092760Y+112064X0200Y         S0      
317GND              VIA   -    M      A01X+093381Y+097243X0200Y    R270 S2      
017GND              VIA   -    M      A18X+093381Y+097243X0260Y    R270 S2      
017GND                    -    MD0100PA00X+093381Y+097243                       
327GND              U419  -12         A01X+093381Y+096746X0240Y0540R180 S1      
317GND              VIA   -    MD0100PA00X+094050Y+092810X0200Y         S0      
327GND              R6182 -1          A01X+094063Y+092570X0198Y0197R270 S1      
317GND              VIA   -    MD0100PA00X+093663Y+092810X0200Y         S0      
327GND              R6187 -1          A01X+093663Y+092570X0198Y0197R270 S1      
327GND              R6195 -1          A18X+093663Y+092570X0198Y0197R090 S2      
317GND              VIA   -    MD0100PA00X+093263Y+092810X0200Y         S0      
327GND              R6188 -1          A01X+093263Y+092570X0198Y0197R270 S1      
327GND              R6197 -1          A18X+093263Y+092570X0198Y0197R090 S2      
317GND              VIA   -    M      A01X+094463Y+092810X0200Y         S2      
017GND              VIA   -    M      A18X+094463Y+092810X0260Y         S2      
017GND                    -    MD0100PA00X+094463Y+092810                       
327GND              R6183 -1          A01X+094463Y+092570X0198Y0197R270 S1      
317GND              VIA   -    MD0100PA00X+094670Y+084920X0200Y         S0      
317GND              VIA   -    MD0100PA00X+093200Y+083100X0200Y         S0      
327GND              R478  -2          A18X+093112Y+083438X0198Y0197R090 S2      
317GND              VIA   -    MD0100PA00X+094192Y+080896X0200Y    R090 S0      
327GND              C3609 -2          A01X+093592Y+081146X0198Y0197R270 S1      
327GND              R4851 -2   M      A01X+093992Y+081146X0198Y0197R270 S1      
327GND              OSC2  -2          A01X+094348Y+080489X0400Y0480R180 S1      
317GND              VIA   -    MD0100PA00X+095747Y+076443X0200Y         S0      
317GND              VIA   -    MD0100PA00X+095632Y+074841X0200Y         S0      
317GND              VIA   -    MD0100PA00X+095268Y+073526X0200Y         S0      
317GND              VIA   -    MD0100PA00X+095120Y+072716X0200Y         S0      
317GND              VIA   -    MD0100PA00X+095402Y+072534X0200Y         S0      
327GND              U325  -3          A01X+095402Y+072080X0220Y0530R180 S1      
317GND              VIA   -    MD0100PA00X+095755Y+069825X0200Y         S0      
327GND              C2147 -2          A01X+096150Y+070126X0198Y0197R270 S1      
327GND              R4251 -2   M      A01X+095755Y+070126X0198Y0197R270 S1      
317GND              VIA   -    MD0100PA00X+093146Y+163980X0200Y         S0      
317GND              VIA   -    MD0100PA00X+094085Y+131018X0200Y         S0      
317GND              VIA   -    MD0100PA00X+093325Y+130827X0200Y         S0      
317GND              VIA   -    M      A01X+094712Y+125994X0200Y         S2      
017GND              VIA   -    M      A18X+094712Y+125994X0260Y         S2      
017GND                    -    MD0100PA00X+094712Y+125994                       
317GND              VIA   -    MD0100PA00X+093642Y+125078X0200Y    R180 S0      
317GND              VIA   -    MD0100PA00X+093642Y+124828X0200Y    R180 S0      
317GND              VIA   -    MD0100PA00X+093642Y+124138X0200Y    R180 S0      
317GND              VIA   -    MD0100PA00X+093642Y+124388X0200Y    R180 S0      
317GND              VIA   -    MD0100PA00X+094198Y+122441X0200Y         S0      
317GND              VIA   -    MD0100PA00X+093860Y+122451X0200Y    R270 S0      
317GND              VIA   -    MD0100PA00X+093560Y+122451X0200Y    R270 S0      
317GND              VIA   -    MD0100PA00X+093642Y+122758X0200Y    R180 S0      
317GND              VIA   -    MD0100PA00X+093642Y+123008X0200Y    R180 S0      
317GND              VIA   -    MD0100PA00X+093642Y+123698X0200Y    R180 S0      
317GND              VIA   -    MD0100PA00X+093642Y+123448X0200Y    R180 S0      
317GND              VIA   -    MD0100PA00X+093860Y+121331X0200Y    R270 S0      
317GND              VIA   -    MD0100PA00X+093860Y+121611X0200Y    R270 S0      
317GND              VIA   -    MD0100PA00X+093860Y+121891X0200Y    R270 S0      
317GND              VIA   -    MD0100PA00X+093860Y+122171X0200Y    R270 S0      
317GND              VIA   -    MD0100PA00X+093560Y+121331X0200Y    R270 S0      
317GND              VIA   -    MD0100PA00X+093560Y+121611X0200Y    R270 S0      
317GND              VIA   -    MD0100PA00X+093560Y+121891X0200Y    R270 S0      
317GND              VIA   -    MD0100PA00X+093560Y+122171X0200Y    R270 S0      
317GND              VIA   -    M      A01X+095263Y+119962X0200Y    R270 S2      
017GND              VIA   -    M      A18X+095263Y+119962X0260Y    R270 S2      
017GND                    -    MD0100PA00X+095263Y+119962                       
327GND              PC248 -2          A01X+095263Y+120212X0198Y0197     S1      
317GND              VIA   -    MD0100PA00X+096103Y+109598X0200Y         S0      
317GND              VIA   -    MD0100PA00X+095503Y+109541X0200Y         S0      
317GND              VIA   -    MD0100PA00X+094887Y+109872X0200Y         S0      
327GND              C632  -2          A01X+095137Y+109872X0198Y0197R090 S1      
317GND              VIA   -    MD0100PA00X+094888Y+110276X0200Y         S0      
327GND              C628  -2          A01X+095128Y+110276X0198Y0197R180 S1      
317GND              VIA   -    MD0100PA00X+096103Y+109139X0200Y         S0      
317GND              VIA   -    MD0100PA00X+094664Y+099136X0200Y         S0      
317GND              VIA   -    M      A01X+095767Y+099156X0200Y         S2      
017GND              VIA   -    M      A18X+095767Y+099156X0260Y         S2      
017GND                    -    MD0100PA00X+095767Y+099156                       
327GND              R6238 -2          A01X+095767Y+098882X0198Y0197R090 S1      
317GND              VIA   -    MD0100PA00X+096148Y+092764X0200Y         S0      
317GND              VIA   -    MD0100PA00X+095057Y+092765X0200Y    R270 S0      
327GND              R6237 -2          A01X+095057Y+093024X0198Y0197R270 S1      
317GND              VIA   -    MD0100PA00X+095029Y+086624X0200Y         S0      
327GND              R4852 -2          A01X+094770Y+086486X0198Y0197     S1      
327GND              C3619 -2          A18X+094818Y+086472X0164Y0164R180 S2      
317GND              VIA   -    MD0100PA00X+095029Y+087024X0200Y         S0      
327GND              R4853 -2          A01X+095312Y+087028X0198Y0197R180 S1      
327GND              C3617 -2          A18X+094830Y+086817X0164Y0164R180 S2      
317GND              VIA   -    MD0100PA00X+095025Y+087427X0200Y         S0      
327GND              C3613 -2          A01X+094784Y+087427X0164Y0164     S1      
317GND              VIA   -    MD0100PA00X+095597Y+086038X0200Y         S0      
317GND              VIA   -    MD0100PA00X+095322Y+086144X0200Y         S0      
327GND              C3616 -2          A01X+095069Y+086144X0164Y0164     S1      
317GND              VIA   -    MD0100PA00X+095309Y+085744X0200Y         S0      
327GND              C3614 -2          A01X+095069Y+085744X0164Y0164     S1      
317GND              VIA   -    MD0100PA00X+094774Y+085494X0200Y         S0      
327GND              C3612 -2          A18X+094827Y+086067X0164Y0164R180 S2      
317GND              VIA   -    MD0100PA00X+095470Y+084270X0200Y         S0      
317GND              VIA   -    MD0100PA00X+094894Y+083580X0200Y         S0      
317GND              VIA   -    MD0100PA00X+094774Y+082492X0200Y         S0      
317GND              VIA   -    MD0100PA00X+095605Y+079394X0200Y         S0      
317GND              VIA   -    MD0100PA00X+095509Y+077980X0200Y         S0      
317GND              VIA   -    MD0100PA00X+097114Y+090897X0200Y    R090 S0      
317GND              VIA   -    MD0100PA00X+097820Y+089750X0200Y         S0      
317GND              VIA   -    MD0100PA00X+097592Y+085478X0200Y         S0      
317GND              VIA   -    MD0100PA00X+097181Y+085124X0200Y         S0      
317GND              VIA   -    MD0100PA00X+096832Y+082619X0200Y         S0      
317GND              VIA   -    MD0100PA00X+096404Y+081896X0200Y         S0      
317GND              VIA   -    MD0100PA00X+097722Y+080218X0200Y         S0      
317GND              VIA   -    MD0100PA00X+096407Y+081301X0200Y         S0      
317GND              VIA   -    MD0100PA00X+096407Y+080769X0200Y         S0      
317GND              VIA   -    MD0100PA00X+097676Y+078656X0200Y         S0      
317GND              VIA   -    MD0100PA00X+097806Y+074744X0200Y         S0      
317GND              VIA   -    MD0100PA00X+095146Y+163980X0200Y         S0      
317GND              VIA   -    MD0100PA00X+095886Y+122721X0200Y         S0      
317GND              VIA   -    MD0100PA00X+095717Y+120807X0200Y         S0      
327GND              PC261 -2          A01X+096537Y+120467X0198Y0197R270 S1      
327GND              PR177 -2   M      A01X+096140Y+120583X0198Y0197R270 S1      
317GND              VIA   -    MD0100PA00X+095730Y+121289X0200Y    R270 S0      
317GND              VIA   -    MD0100PA00X+097873Y+128491X0200Y         S0      
317GND              VIA   -    MD0100PA00X+096592Y+123930X0200Y         S0      
317GND              VIA   -    MD0100PA00X+096592Y+124370X0200Y         S0      
317GND              VIA   -    MD0100PA00X+096592Y+124620X0200Y         S0      
317GND              VIA   -    MD0100PA00X+096592Y+123240X0200Y         S0      
317GND              VIA   -    MD0100PA00X+096592Y+122990X0200Y         S0      
317GND              VIA   -    MD0100PA00X+096592Y+123680X0200Y         S0      
317GND              VIA   -    MD0100PA00X+096788Y+113287X0200Y         S0      
317GND              VIA   -    MD0100PA00X+097048Y+113287X0200Y         S0      
317GND              VIA   -    MD0100PA00X+096540Y+113643X0200Y    R090 S0      
317GND              VIA   -    MD0100PA00X+097495Y+111410X0200Y         S0      
317GND              VIA   -    MD0100PA00X+097225Y+111410X0200Y         S0      
317GND              VIA   -    MD0100PA00X+097505Y+112380X0200Y         S0      
317GND              VIA   -    MD0100PA00X+097235Y+112380X0200Y         S0      
317GND              VIA   -    MD0100PA00X+096705Y+111410X0200Y         S0      
317GND              VIA   -    MD0100PA00X+096965Y+111410X0200Y         S0      
317GND              VIA   -    MD0100PA00X+096975Y+112380X0200Y         S0      
317GND              VIA   -    MD0100PA00X+096715Y+112380X0200Y         S0      
317GND              VIA   -    MD0100PA00X+096567Y+109594X0200Y         S0      
317GND              VIA   -    MD0100PA00X+096572Y+109135X0200Y         S0      
317GND              VIA   -    MD0100PA00X+097228Y+093443X0200Y    R270 S0      
327GND              C3989 -2          A01X+096675Y+093022X0198Y0197R270 S1      
317GND              VIA   -    MD0100PA00X+098109Y+110190X0200Y         S0      
317GND              VIA   -    MD0100PA00X+098073Y+108866X0200Y         S0      
327GND              R796  -2          A01X+097833Y+108866X0198Y0197     S1      
317GND              VIA   -    MD0100PA00X+098073Y+108066X0200Y         S0      
327GND              R794  -2          A01X+097833Y+108066X0198Y0197     S1      
317GND              VIA   -    MD0100PA00X+098846Y+101384X0200Y         S0      
317GND              VIA   -    MD0100PA00X+098279Y+089976X0200Y         S0      
327GND              U319  -10  M      A01X+097283Y+090030X0320Y0750R270 S1      
317GND              VIA   -    MD0100PA00X+099513Y+088850X0200Y         S0      
317GND              VIA   -    MD0100PA00X+098779Y+089660X0200Y         S0      
317GND              VIA   -    MD0100PA00X+098489Y+086872X0200Y         S0      
317GND              VIA   -    MD0100PA00X+098823Y+087820X0200Y         S0      
317GND              VIA   -    MD0100PA00X+098053Y+087910X0200Y         S0      
327GND              R3478 -2          A18X+097777Y+088007X0198Y0197R090 S2      
317GND              VIA   -    MD0100PA00X+098882Y+085890X0200Y         S0      
317GND              VIA   -    MD0100PA00X+099306Y+083314X0200Y         S0      
317GND              VIA   -    MD0100PA00X+098790Y+081864X0200Y         S0      
327GND              C2494 -2          A01X+099005Y+081692X0198Y0197R090 S1      
317GND              VIA   -    MD0100PA00X+097931Y+081432X0200Y         S0      
317GND              VIA   -    MD0100PA00X+098496Y+078539X0200Y         S0      
317GND              VIA   -    MD0100PA00X+099199Y+077397X0200Y         S0      
327GND              R875  -2          A01X+099199Y+077155X0198Y0197R090 S1      
317GND              VIA   -    MD0100PA00X+098833Y+078144X0200Y         S0      
317GND              VIA   -    MD0100PA00X+098503Y+078120X0200Y         S0      
317GND              VIA   -    MD0100PA00X+098431Y+074843X0200Y         S0      
317GND              VIA   -    MD0100PA00X+098371Y+072206X0200Y    R090 S0      
317GND              VIA   -    MD0100PA00X+097146Y+163980X0200Y         S0      
317GND              VIA   -    MD0100PA00X+098839Y+130256X0200Y         S0      
317GND              VIA   -    MD0100PA00X+101804Y+079359X0200Y         S0      
317GND              VIA   -    MD0100PA00X+101938Y+078306X0200Y         S0      
317GND              VIA   -    MD0100PA00X+102190Y+077197X0200Y    R270 S0      
327GND              R2619 -2          A01X+101947Y+077197X0198Y0197     S1      
317GND              VIA   -    MD0100PA00X+101580Y+076045X0200Y         S0      
317GND              VIA   -    MD0100PA00X+099970Y+101840X0200Y         S0      
327GND              Q15   -1          A01X+099885Y+101517X0240Y0240R270 S1      
317GND              VIA   -    MD0100PA00X+100530Y+100656X0200Y         S0      
327GND              Q15   -4          A01X+100594Y+100926X0240Y0240R270 S1      
317GND              VIA   -    MD0100PA00X+101001Y+099810X0200Y         S0      
327GND              R1365 -1          A01X+101001Y+099511X0198Y0197R270 S1      
317GND              VIA   -    MD0100PA00X+100293Y+090678X0200Y         S0      
327GND              U67   -8          A18X+100055Y+090483X0140Y0610R180 S2      
317GND              VIA   -    MD0100PA00X+100561Y+087786X0200Y         S0      
317GND              VIA   -    MD0100PA00X+100561Y+087486X0200Y         S0      
317GND              VIA   -    MD0100PA00X+099982Y+081949X0200Y         S0      
317GND              VIA   -    M      A01X+100605Y+078774X0200Y         S2      
017GND              VIA   -    M      A18X+100605Y+078774X0260Y         S2      
017GND                    -    MD0100PA00X+100605Y+078774                       
327GND              U294  -7          A01X+100605Y+078330X0140Y0590     S1      
317GND              VIA   -    MD0100PA00X+100283Y+077739X0200Y         S0      
317GND              VIA   -    MD0100PA00X+100354Y+076263X0200Y         S0      
317GND              VIA   -    MD0100PA00X+100834Y+076174X0200Y         S0      
317GND              VIA   -    MD0100PA00X+099146Y+163980X0200Y         S0      
317GND              VIA   -    MD0100PA00X+102311Y+115249X0200Y         S0      
317GND              VIA   -    MD0100PA00X+101730Y+115249X0200Y         S0      
317GND              VIA   -    MD0100PA00X+101730Y+112729X0200Y         S0      
317GND              VIA   -    MD0100PA00X+102661Y+113989X0200Y         S0      
317GND              VIA   -    MD0100PA00X+102311Y+113989X0200Y         S0      
317GND              VIA   -    MD0100PA00X+101730Y+113989X0200Y         S0      
317GND              VIA   -    MD0100PA00X+102661Y+112729X0200Y         S0      
317GND              VIA   -    MD0100PA00X+102311Y+112729X0200Y         S0      
317GND              VIA   -    MD0100PA00X+102661Y+111469X0200Y         S0      
317GND              VIA   -    MD0100PA00X+102311Y+111469X0200Y         S0      
317GND              VIA   -    MD0100PA00X+101730Y+111469X0200Y         S0      
317GND              VIA   -    MD0100PA00X+102311Y+110209X0200Y         S0      
317GND              VIA   -    MD0100PA00X+102661Y+110259X0200Y         S0      
317GND              VIA   -    MD0100PA00X+101730Y+110209X0200Y         S0      
317GND              VIA   -    MD0100PA00X+102259Y+103511X0200Y         S0      
327GND              C3412 -2          A01X+102029Y+103510X0120Y0150R090 S1      
317GND              VIA   -    M      A01X+101477Y+103509X0200Y         S2      
017GND              VIA   -    M      A18X+101477Y+103509X0260Y         S2      
017GND                    -    MD0100PA00X+101477Y+103509                       
317GND              VIA   -    MD0100PA00X+102545Y+101176X0200Y    R090 S0      
317GND              VIA   -    MD0100PA00X+101401Y+099786X0200Y         S0      
327GND              R1363 -1          A01X+101401Y+099511X0198Y0197R270 S1      
317GND              VIA   -    MD0100PA00X+102545Y+100826X0200Y    R090 S0      
317GND              VIA   -    MD0100PA00X+102601Y+099786X0200Y         S0      
327GND              R1354 -1          A01X+102601Y+099511X0198Y0197R270 S1      
317GND              VIA   -    MD0100PA00X+101801Y+099786X0200Y         S0      
327GND              R1358 -1          A01X+101801Y+099511X0198Y0197R270 S1      
317GND              VIA   -    MD0100PA00X+102201Y+099786X0200Y         S0      
327GND              R1361 -1          A01X+102201Y+099511X0198Y0197R270 S1      
317GND              VIA   -    MD0100PA00X+102634Y+091776X0200Y    R090 S0      
317GND              VIA   -    MD0100PA00X+101632Y+082848X0200Y    R090 S0      
327GND              C2811 -1          A01X+101632Y+082598X0198Y0197     S1      
317GND              VIA   -    MD0100PA00X+102586Y+080228X0200Y         S0      
317GND              VIA   -    MD0100PA00X+101459Y+080279X0200Y         S0      
317GND              VIA   -    MD0100PA00X+101580Y+080754X0200Y         S0      
317GND              VIA   -    MD0100PA00X+103075Y+073221X0200Y    R090 S0      
317GND              VIA   -    MD0100PA00X+102697Y+122375X0200Y         S0      
327GND              R1350 -1          A01X+102937Y+122615X0198Y0197R045 S1      
317GND              VIA   -    M      A01X+102242Y+120320X0200Y         S2      
017GND              VIA   -    M      A18X+102242Y+120320X0260Y         S2      
017GND                    -    MD0100PA00X+102242Y+120320                       
327GND              R1388 -1          A01X+102654Y+120505X0198Y0197R045 S1      
317GND              VIA   -    MD0100PA00X+102043Y+120558X0200Y    R315 S0      
327GND              R1349 -1          A01X+102371Y+120788X0198Y0197R045 S1      
317GND              VIA   -    MD0100PA00X+102661Y+117769X0200Y         S0      
317GND              VIA   -    MD0100PA00X+102311Y+117769X0200Y         S0      
317GND              VIA   -    MD0100PA00X+101730Y+117769X0200Y         S0      
317GND              VIA   -    MD0100PA00X+102661Y+116509X0200Y         S0      
317GND              VIA   -    MD0100PA00X+102311Y+116509X0200Y         S0      
317GND              VIA   -    MD0100PA00X+101730Y+116509X0200Y         S0      
317GND              VIA   -    MD0100PA00X+102661Y+115249X0200Y         S0      
317GND              VIA   -    MD0100PA00X+104411Y+077884X0200Y         S0      
317GND              VIA   -    MD0100PA00X+103538Y+121520X0200Y         S0      
327GND              R1351 -1          A01X+103786Y+121767X0198Y0197R045 S1      
317GND              VIA   -    MD0100PA00X+104060Y+121060X0200Y         S0      
327GND              R1352 -1          A01X+104634Y+120918X0198Y0197R045 S1      
317GND              VIA   -    MD0100PA00X+104355Y+103538X0200Y         S0      
317GND              VIA   -    M      A01X+103825Y+102195X0200Y         S2      
017GND              VIA   -    M      A18X+103825Y+102195X0260Y         S2      
017GND                    -    MD0100PA00X+103825Y+102195                       
317GND              VIA   -    MD0100PA00X+103475Y+102195X0200Y         S0      
317GND              VIA   -    MD0100PA00X+103801Y+099786X0200Y         S0      
327GND              R1360 -1          A01X+103801Y+099511X0198Y0197R270 S1      
317GND              VIA   -    MD0100PA00X+104201Y+099786X0200Y         S0      
327GND              R1364 -1          A01X+104201Y+099511X0198Y0197R270 S1      
317GND              VIA   -    MD0100PA00X+102894Y+100935X0200Y         S0      
317GND              VIA   -    MD0100PA00X+103475Y+100935X0200Y         S0      
317GND              VIA   -    MD0100PA00X+103825Y+100935X0200Y         S0      
317GND              VIA   -    MD0100PA00X+103401Y+099786X0200Y         S0      
327GND              R1356 -1          A01X+103401Y+099511X0198Y0197R270 S1      
317GND              VIA   -    MD0100PA00X+103001Y+099786X0200Y         S0      
327GND              R1359 -1          A01X+103001Y+099511X0198Y0197R270 S1      
317GND              VIA   -    MD0100PA00X+104325Y+090250X0200Y         S0      
317GND              VIA   -    MD0100PA00X+103030Y+088140X0200Y         S0      
317GND              VIA   -    MD0100PA00X+102816Y+087941X0200Y         S0      
317GND              VIA   -    MD0100PA00X+104288Y+079492X0200Y         S0      
317GND              VIA   -    MD0100PA00X+102609Y+077094X0200Y         S0      
317GND              VIA   -    MD0100PA00X+103880Y+076327X0200Y         S0      
317GND              VIA   -    MD0100PA00X+104804Y+118069X0200Y         S0      
317GND              VIA   -    MD0100PA00X+104804Y+116809X0200Y         S0      
317GND              VIA   -    MD0100PA00X+104804Y+114289X0200Y         S0      
317GND              VIA   -    MD0100PA00X+104804Y+115549X0200Y         S0      
317GND              VIA   -    MD0100PA00X+104804Y+113029X0200Y         S0      
317GND              VIA   -    MD0100PA00X+104804Y+111769X0200Y         S0      
317GND              VIA   -    MD0100PA00X+104804Y+110509X0200Y         S0      
317GND              VIA   -    MD0100PA00X+105001Y+099786X0200Y         S0      
327GND              R1367 -1          A01X+105001Y+099511X0198Y0197R270 S1      
317GND              VIA   -    MD0100PA00X+105401Y+099786X0200Y         S0      
327GND              R1368 -1          A01X+105401Y+099511X0198Y0197R270 S1      
317GND              VIA   -    MD0100PA00X+104601Y+099786X0200Y         S0      
327GND              R1353 -1          A01X+104601Y+099511X0198Y0197R270 S1      
317GND              VIA   -    MD0100PA00X+104833Y+080817X0200Y         S0      
327GND              C3991 -1          A01X+105323Y+081166X0280Y0320     S1      
317GND              VIA   -    MD0100PA00X+104574Y+080084X0200Y         S0      
327GND              C3606 -2   M      A18X+091129Y+084687X0164Y0164     S2      
327GND              C3607 -2          A18X+092074Y+085317X0164Y0164R180 S2      
317GND              H133  -1   MD1260PA00X+001378Y+122602X2560Y         S3      
317GND              H138  -1   MD1260PA00X+007933Y+118665X2560Y         S3      
317GND              J3    -Z9  MD0197PA00X+017917Y+145350X0357Y    R180 S3      
317GND              J3    -Y10 MD0197PA00X+018784Y+145784X0357Y    R180 S3      
317GND              J3    -W9  MD0197PA00X+017917Y+146886X0357Y    R180 S3      
317GND              J3    -V10 MD0197PA00X+018784Y+147319X0357Y    R180 S3      
317GND              J3    -T9  MD0197PA00X+017917Y+148421X0357Y    R180 S3      
317GND              J3    -S10 MD0197PA00X+018784Y+148854X0357Y    R180 S3      
317GND              J3    -Q9  MD0197PA00X+017917Y+149957X0357Y    R180 S3      
317GND              J3    -P10 MD0197PA00X+018784Y+150390X0357Y    R180 S3      
317GND              J3    -N2_9MD0197PA00X+017917Y+151492X0357Y    R180 S3      
317GND              J3    -N1_9MD0197PA00X+017917Y+155587X0357Y    R180 S3      
317GND              J3    -M2_1MD0197PA00X+018784Y+151925X0357Y    R180 S3      
317GND              J3    -M1_1MD0197PA00X+018784Y+156020X0357Y    R180 S3      
317GND              J3    -K9  MD0197PA00X+017917Y+157122X0357Y    R180 S3      
317GND              J3    -J10 MD0197PA00X+018784Y+157555X0357Y    R180 S3      
317GND              J3    -H9  MD0197PA00X+017917Y+158658X0357Y    R180 S3      
317GND              J3    -G10 MD0197PA00X+018784Y+159091X0357Y    R180 S3      
317GND              J3    -E9  MD0197PA00X+017917Y+160193X0357Y    R180 S3      
317GND              J3    -D10 MD0197PA00X+018784Y+160626X0357Y    R180 S3      
317GND              J3    -B9  MD0197PA00X+017917Y+161728X0357Y    R180 S3      
317GND              J3    -A10 MD0197PA00X+018784Y+162162X0357Y    R180 S3      
317GND              J3    -Z7  MD0197PA00X+016185Y+145350X0357Y    R180 S3      
317GND              J3    -Y8  MD0197PA00X+017051Y+145784X0357Y    R180 S3      
317GND              J3    -W7  MD0197PA00X+016185Y+146886X0357Y    R180 S3      
317GND              J3    -V8  MD0197PA00X+017051Y+147319X0357Y    R180 S3      
317GND              J3    -T7  MD0197PA00X+016185Y+148421X0357Y    R180 S3      
317GND              J3    -S8  MD0197PA00X+017051Y+148854X0357Y    R180 S3      
317GND              J3    -Q7  MD0197PA00X+016185Y+149957X0357Y    R180 S3      
317GND              J3    -P8  MD0197PA00X+017051Y+150390X0357Y    R180 S3      
317GND              J3    -N2_7MD0197PA00X+016185Y+151492X0357Y    R180 S3      
317GND              J3    -N1_7MD0197PA00X+016185Y+155587X0357Y    R180 S3      
317GND              J3    -M2_8MD0197PA00X+017051Y+151925X0357Y    R180 S3      
317GND              J3    -M1_8MD0197PA00X+017051Y+156020X0357Y    R180 S3      
317GND              J3    -K7  MD0197PA00X+016185Y+157122X0357Y    R180 S3      
317GND              J3    -J8  MD0197PA00X+017051Y+157555X0357Y    R180 S3      
317GND              J3    -H7  MD0197PA00X+016185Y+158658X0357Y    R180 S3      
317GND              J3    -G8  MD0197PA00X+017051Y+159091X0357Y    R180 S3      
317GND              J3    -E7  MD0197PA00X+016185Y+160193X0357Y    R180 S3      
317GND              J3    -D8  MD0197PA00X+017051Y+160626X0357Y    R180 S3      
317GND              J3    -B7  MD0197PA00X+016185Y+161728X0357Y    R180 S3      
317GND              J3    -A8  MD0197PA00X+017051Y+162162X0357Y    R180 S3      
317GND              J3    -Z5  MD0197PA00X+014453Y+145350X0357Y    R180 S3      
317GND              J3    -Y6  MD0197PA00X+015319Y+145784X0357Y    R180 S3      
317GND              J3    -W5  MD0197PA00X+014453Y+146886X0357Y    R180 S3      
317GND              J3    -V6  MD0197PA00X+015319Y+147319X0357Y    R180 S3      
317GND              J3    -T5  MD0197PA00X+014453Y+148421X0357Y    R180 S3      
317GND              J3    -S6  MD0197PA00X+015319Y+148854X0357Y    R180 S3      
317GND              J3    -Q5  MD0197PA00X+014453Y+149957X0357Y    R180 S3      
317GND              J3    -P6  MD0197PA00X+015319Y+150390X0357Y    R180 S3      
317GND              J3    -N2_5MD0197PA00X+014453Y+151492X0357Y    R180 S3      
317GND              J3    -N1_5MD0197PA00X+014453Y+155587X0357Y    R180 S3      
317GND              J3    -M2_6MD0197PA00X+015319Y+151925X0357Y    R180 S3      
317GND              J3    -M1_6MD0197PA00X+015319Y+156020X0357Y    R180 S3      
317GND              J3    -K5  MD0197PA00X+014453Y+157122X0357Y    R180 S3      
317GND              J3    -J6  MD0197PA00X+015319Y+157555X0357Y    R180 S3      
317GND              J3    -H5  MD0197PA00X+014453Y+158658X0357Y    R180 S3      
317GND              J3    -G6  MD0197PA00X+015319Y+159091X0357Y    R180 S3      
317GND              J3    -E5  MD0197PA00X+014453Y+160193X0357Y    R180 S3      
317GND              J3    -D6  MD0197PA00X+015319Y+160626X0357Y    R180 S3      
317GND              J3    -B5  MD0197PA00X+014453Y+161728X0357Y    R180 S3      
317GND              J3    -A6  MD0197PA00X+015319Y+162162X0357Y    R180 S3      
317GND              J3    -Z3  MD0197PA00X+012720Y+145350X0357Y    R180 S3      
317GND              J3    -Y4  MD0197PA00X+013587Y+145784X0357Y    R180 S3      
317GND              J3    -W3  MD0197PA00X+012720Y+146886X0357Y    R180 S3      
317GND              J3    -V4  MD0197PA00X+013587Y+147319X0357Y    R180 S3      
317GND              J3    -T3  MD0197PA00X+012720Y+148421X0357Y    R180 S3      
317GND              J3    -S4  MD0197PA00X+013587Y+148854X0357Y    R180 S3      
317GND              J3    -Q3  MD0197PA00X+012720Y+149957X0357Y    R180 S3      
317GND              J3    -P4  MD0197PA00X+013587Y+150390X0357Y    R180 S3      
317GND              J3    -N2_3MD0197PA00X+012720Y+151492X0357Y    R180 S3      
317GND              J3    -N1_3MD0197PA00X+012720Y+155587X0357Y    R180 S3      
317GND              J3    -M2_4MD0197PA00X+013587Y+151925X0357Y    R180 S3      
317GND              J3    -M1_4MD0197PA00X+013587Y+156020X0357Y    R180 S3      
317GND              J3    -K3  MD0197PA00X+012720Y+157122X0357Y    R180 S3      
317GND              J3    -J4  MD0197PA00X+013587Y+157555X0357Y    R180 S3      
317GND              J3    -H3  MD0197PA00X+012720Y+158658X0357Y    R180 S3      
317GND              J3    -G4  MD0197PA00X+013587Y+159091X0357Y    R180 S3      
317GND              J3    -E3  MD0197PA00X+012720Y+160193X0357Y    R180 S3      
317GND              J3    -D4  MD0197PA00X+013587Y+160626X0357Y    R180 S3      
317GND              J3    -B3  MD0197PA00X+012720Y+161728X0357Y    R180 S3      
317GND              J3    -A4  MD0197PA00X+013587Y+162162X0357Y    R180 S3      
317GND              J3    -Z1  MD0197PA00X+010988Y+145350X0357Y    R180 S3      
317GND              J3    -Y2  MD0197PA00X+011854Y+145784X0357Y    R180 S3      
317GND              J3    -W1  MD0197PA00X+010988Y+146886X0357Y    R180 S3      
317GND              J3    -V2  MD0197PA00X+011854Y+147319X0357Y    R180 S3      
317GND              J3    -T1  MD0197PA00X+010988Y+148421X0357Y    R180 S3      
317GND              J3    -S2  MD0197PA00X+011854Y+148854X0357Y    R180 S3      
317GND              J3    -Q1  MD0197PA00X+010988Y+149957X0357Y    R180 S3      
317GND              J3    -P2  MD0197PA00X+011854Y+150390X0357Y    R180 S3      
317GND              J3    -N2_1MD0197PA00X+010988Y+151492X0357Y    R180 S3      
317GND              J3    -N1_1MD0197PA00X+010988Y+155587X0357Y    R180 S3      
317GND              J3    -M2_2MD0197PA00X+011854Y+151925X0357Y    R180 S3      
317GND              J3    -M1_2MD0197PA00X+011854Y+156020X0357Y    R180 S3      
317GND              J3    -K1  MD0197PA00X+010988Y+157122X0357Y    R180 S3      
317GND              J3    -J2  MD0197PA00X+011854Y+157555X0357Y    R180 S3      
317GND              J3    -H1  MD0197PA00X+010988Y+158658X0357Y    R180 S3      
317GND              J3    -G2  MD0197PA00X+011854Y+159091X0357Y    R180 S3      
317GND              J3    -E1  MD0197PA00X+010988Y+160193X0357Y    R180 S3      
317GND              J3    -D2  MD0197PA00X+011854Y+160626X0357Y    R180 S3      
317GND              J3    -B1  MD0197PA00X+010988Y+161728X0357Y    R180 S3      
317GND              J3    -A2  MD0197PA00X+011854Y+162162X0357Y    R180 S3      
317GND              H91   -9   MD0220PA00X+012684Y+125327X0300Y         S3      
317GND              H91   -8   MD0220PA00X+011673Y+124909X0300Y         S3      
317GND              H91   -7   MD0220PA00X+010662Y+125327X0300Y         S3      
317GND              H91   -6   MD0220PA00X+010243Y+126339X0300Y         S3      
317GND              H91   -5   MD0220PA00X+010662Y+127350X0300Y         S3      
317GND              H91   -4   MD0220PA00X+011673Y+127769X0300Y         S3      
317GND              H91   -3   MD0220PA00X+012684Y+127350X0300Y         S3      
317GND              H91   -2   MD0220PA00X+013103Y+126339X0300Y         S3      
317GND              H94   -9   MD0220PA00X+012684Y+105642X0300Y         S3      
317GND              H94   -8   MD0220PA00X+011673Y+105224X0300Y         S3      
317GND              H94   -7   MD0220PA00X+010662Y+105642X0300Y         S3      
317GND              H94   -6   MD0220PA00X+010243Y+106654X0300Y         S3      
317GND              H94   -5   MD0220PA00X+010662Y+107665X0300Y         S3      
317GND              H94   -4   MD0220PA00X+011673Y+108084X0300Y         S3      
317GND              H94   -3   MD0220PA00X+012684Y+107665X0300Y         S3      
317GND              H94   -2   MD0220PA00X+013103Y+106654X0300Y         S3      
317GND              J11   -Z9  MD0197PA00X+035240Y+145350X0357Y    R180 S3      
317GND              J11   -Y10 MD0197PA00X+036106Y+145784X0357Y    R180 S3      
317GND              J11   -W9  MD0197PA00X+035240Y+146886X0357Y    R180 S3      
317GND              J11   -V10 MD0197PA00X+036106Y+147319X0357Y    R180 S3      
317GND              J11   -T9  MD0197PA00X+035240Y+148421X0357Y    R180 S3      
317GND              J11   -S10 MD0197PA00X+036106Y+148854X0357Y    R180 S3      
317GND              J11   -Q9  MD0197PA00X+035240Y+149957X0357Y    R180 S3      
317GND              J11   -P10 MD0197PA00X+036106Y+150390X0357Y    R180 S3      
317GND              J11   -N2_9MD0197PA00X+035240Y+151492X0357Y    R180 S3      
317GND              J11   -N1_9MD0197PA00X+035240Y+155587X0357Y    R180 S3      
317GND              J11   -M2_1MD0197PA00X+036106Y+151925X0357Y    R180 S3      
317GND              J11   -M1_1MD0197PA00X+036106Y+156020X0357Y    R180 S3      
317GND              J11   -K9  MD0197PA00X+035240Y+157122X0357Y    R180 S3      
317GND              J11   -J10 MD0197PA00X+036106Y+157555X0357Y    R180 S3      
317GND              J11   -H9  MD0197PA00X+035240Y+158658X0357Y    R180 S3      
317GND              J11   -G10 MD0197PA00X+036106Y+159091X0357Y    R180 S3      
317GND              J11   -E9  MD0197PA00X+035240Y+160193X0357Y    R180 S3      
317GND              J11   -D10 MD0197PA00X+036106Y+160626X0357Y    R180 S3      
317GND              J11   -B9  MD0197PA00X+035240Y+161728X0357Y    R180 S3      
317GND              J11   -A10 MD0197PA00X+036106Y+162162X0357Y    R180 S3      
317GND              J11   -Z7  MD0197PA00X+033508Y+145350X0357Y    R180 S3      
317GND              J11   -Y8  MD0197PA00X+034374Y+145784X0357Y    R180 S3      
317GND              J11   -W7  MD0197PA00X+033508Y+146886X0357Y    R180 S3      
317GND              J11   -V8  MD0197PA00X+034374Y+147319X0357Y    R180 S3      
317GND              J11   -T7  MD0197PA00X+033508Y+148421X0357Y    R180 S3      
317GND              J11   -S8  MD0197PA00X+034374Y+148854X0357Y    R180 S3      
317GND              J11   -Q7  MD0197PA00X+033508Y+149957X0357Y    R180 S3      
317GND              J11   -P8  MD0197PA00X+034374Y+150390X0357Y    R180 S3      
317GND              J11   -N2_7MD0197PA00X+033508Y+151492X0357Y    R180 S3      
317GND              J11   -N1_7MD0197PA00X+033508Y+155587X0357Y    R180 S3      
317GND              J11   -M2_8MD0197PA00X+034374Y+151925X0357Y    R180 S3      
317GND              J11   -M1_8MD0197PA00X+034374Y+156020X0357Y    R180 S3      
317GND              J11   -K7  MD0197PA00X+033508Y+157122X0357Y    R180 S3      
317GND              J11   -J8  MD0197PA00X+034374Y+157555X0357Y    R180 S3      
317GND              J11   -H7  MD0197PA00X+033508Y+158658X0357Y    R180 S3      
317GND              J11   -G8  MD0197PA00X+034374Y+159091X0357Y    R180 S3      
317GND              J11   -E7  MD0197PA00X+033508Y+160193X0357Y    R180 S3      
317GND              J11   -D8  MD0197PA00X+034374Y+160626X0357Y    R180 S3      
317GND              J11   -B7  MD0197PA00X+033508Y+161728X0357Y    R180 S3      
317GND              J11   -A8  MD0197PA00X+034374Y+162162X0357Y    R180 S3      
317GND              J11   -Z5  MD0197PA00X+031776Y+145350X0357Y    R180 S3      
317GND              J11   -Y6  MD0197PA00X+032642Y+145784X0357Y    R180 S3      
317GND              J11   -W5  MD0197PA00X+031776Y+146886X0357Y    R180 S3      
317GND              J11   -V6  MD0197PA00X+032642Y+147319X0357Y    R180 S3      
317GND              J11   -T5  MD0197PA00X+031776Y+148421X0357Y    R180 S3      
317GND              J11   -S6  MD0197PA00X+032642Y+148854X0357Y    R180 S3      
317GND              J11   -Q5  MD0197PA00X+031776Y+149957X0357Y    R180 S3      
317GND              J11   -P6  MD0197PA00X+032642Y+150390X0357Y    R180 S3      
317GND              J11   -N2_5MD0197PA00X+031776Y+151492X0357Y    R180 S3      
317GND              J11   -N1_5MD0197PA00X+031776Y+155587X0357Y    R180 S3      
317GND              J11   -M2_6MD0197PA00X+032642Y+151925X0357Y    R180 S3      
317GND              J11   -M1_6MD0197PA00X+032642Y+156020X0357Y    R180 S3      
317GND              J11   -K5  MD0197PA00X+031776Y+157122X0357Y    R180 S3      
317GND              J11   -J6  MD0197PA00X+032642Y+157555X0357Y    R180 S3      
317GND              J11   -H5  MD0197PA00X+031776Y+158658X0357Y    R180 S3      
317GND              J11   -G6  MD0197PA00X+032642Y+159091X0357Y    R180 S3      
317GND              J11   -E5  MD0197PA00X+031776Y+160193X0357Y    R180 S3      
317GND              J11   -D6  MD0197PA00X+032642Y+160626X0357Y    R180 S3      
317GND              J11   -B5  MD0197PA00X+031776Y+161728X0357Y    R180 S3      
317GND              J11   -A6  MD0197PA00X+032642Y+162162X0357Y    R180 S3      
317GND              J11   -Z3  MD0197PA00X+030043Y+145350X0357Y    R180 S3      
317GND              J11   -Y4  MD0197PA00X+030909Y+145784X0357Y    R180 S3      
317GND              J11   -W3  MD0197PA00X+030043Y+146886X0357Y    R180 S3      
317GND              J11   -V4  MD0197PA00X+030909Y+147319X0357Y    R180 S3      
317GND              J11   -T3  MD0197PA00X+030043Y+148421X0357Y    R180 S3      
317GND              J11   -S4  MD0197PA00X+030909Y+148854X0357Y    R180 S3      
317GND              J11   -Q3  MD0197PA00X+030043Y+149957X0357Y    R180 S3      
317GND              J11   -P4  MD0197PA00X+030909Y+150390X0357Y    R180 S3      
317GND              J11   -N2_3MD0197PA00X+030043Y+151492X0357Y    R180 S3      
317GND              J11   -N1_3MD0197PA00X+030043Y+155587X0357Y    R180 S3      
317GND              J11   -M2_4MD0197PA00X+030909Y+151925X0357Y    R180 S3      
317GND              J11   -M1_4MD0197PA00X+030909Y+156020X0357Y    R180 S3      
317GND              J11   -K3  MD0197PA00X+030043Y+157122X0357Y    R180 S3      
317GND              J11   -J4  MD0197PA00X+030909Y+157555X0357Y    R180 S3      
317GND              J11   -H3  MD0197PA00X+030043Y+158658X0357Y    R180 S3      
317GND              J11   -G4  MD0197PA00X+030909Y+159091X0357Y    R180 S3      
317GND              J11   -E3  MD0197PA00X+030043Y+160193X0357Y    R180 S3      
317GND              J11   -D4  MD0197PA00X+030909Y+160626X0357Y    R180 S3      
317GND              J11   -B3  MD0197PA00X+030043Y+161728X0357Y    R180 S3      
317GND              J11   -A4  MD0197PA00X+030909Y+162162X0357Y    R180 S3      
317GND              J11   -Z1  MD0197PA00X+028311Y+145350X0357Y    R180 S3      
317GND              J11   -Y2  MD0197PA00X+029177Y+145784X0357Y    R180 S3      
317GND              J11   -W1  MD0197PA00X+028311Y+146886X0357Y    R180 S3      
317GND              J11   -V2  MD0197PA00X+029177Y+147319X0357Y    R180 S3      
317GND              J11   -T1  MD0197PA00X+028311Y+148421X0357Y    R180 S3      
317GND              J11   -S2  MD0197PA00X+029177Y+148854X0357Y    R180 S3      
317GND              J11   -Q1  MD0197PA00X+028311Y+149957X0357Y    R180 S3      
317GND              J11   -P2  MD0197PA00X+029177Y+150390X0357Y    R180 S3      
317GND              J11   -N2_1MD0197PA00X+028311Y+151492X0357Y    R180 S3      
317GND              J11   -N1_1MD0197PA00X+028311Y+155587X0357Y    R180 S3      
317GND              J11   -M2_2MD0197PA00X+029177Y+151925X0357Y    R180 S3      
317GND              J11   -M1_2MD0197PA00X+029177Y+156020X0357Y    R180 S3      
317GND              J11   -K1  MD0197PA00X+028311Y+157122X0357Y    R180 S3      
317GND              J11   -J2  MD0197PA00X+029177Y+157555X0357Y    R180 S3      
317GND              J11   -H1  MD0197PA00X+028311Y+158658X0357Y    R180 S3      
317GND              J11   -G2  MD0197PA00X+029177Y+159091X0357Y    R180 S3      
317GND              J11   -E1  MD0197PA00X+028311Y+160193X0357Y    R180 S3      
317GND              J11   -D2  MD0197PA00X+029177Y+160626X0357Y    R180 S3      
317GND              J11   -B1  MD0197PA00X+028311Y+161728X0357Y    R180 S3      
317GND              J11   -A2  MD0197PA00X+029177Y+162162X0357Y    R180 S3      
317GND              H88   -9   MD0220PA00X+036306Y+125327X0300Y         S3      
317GND              H88   -8   MD0220PA00X+035295Y+124909X0300Y         S3      
317GND              H88   -7   MD0220PA00X+034284Y+125327X0300Y         S3      
317GND              H88   -6   MD0220PA00X+033865Y+126339X0300Y         S3      
317GND              H88   -5   MD0220PA00X+034284Y+127350X0300Y         S3      
317GND              H88   -4   MD0220PA00X+035295Y+127769X0300Y         S3      
317GND              H88   -3   MD0220PA00X+036306Y+127350X0300Y         S3      
317GND              H88   -2   MD0220PA00X+036725Y+126339X0300Y         S3      
317GND              H96   -9   MD0220PA00X+036306Y+105642X0300Y         S3      
317GND              H96   -8   MD0220PA00X+035295Y+105224X0300Y         S3      
317GND              H96   -7   MD0220PA00X+034284Y+105642X0300Y         S3      
317GND              H96   -6   MD0220PA00X+033865Y+106654X0300Y         S3      
317GND              H96   -5   MD0220PA00X+034284Y+107665X0300Y         S3      
317GND              H96   -4   MD0220PA00X+035295Y+108084X0300Y         S3      
317GND              H96   -3   MD0220PA00X+036306Y+107665X0300Y         S3      
317GND              H96   -2   MD0220PA00X+036725Y+106654X0300Y         S3      
317GND              H136  -1   MD1260PA00X+039035Y+114102X2560Y         S3      
327GND              C3632 -2          A18X+040405Y+155037X0198Y0197R090 S2      
327GND              C3630 -2          A18X+040009Y+153520X0198Y0197R180 S2      
327GND              C3633 -2          A18X+040416Y+153706X0198Y0197R270 S2      
327GND              C3631 -2          A18X+040009Y+154720X0198Y0197R180 S2      
327GND              C3629 -2          A18X+040998Y+153706X0198Y0197R270 S2      
327GND              C3627 -2          A18X+040009Y+154070X0198Y0197R180 S2      
327GND              C3634 -2          A18X+041331Y+154720X0198Y0197     S2      
327GND              C3628 -2          A18X+041331Y+154122X0198Y0197     S2      
317GND              J12   -Z9  MD0197PA00X+052563Y+145350X0357Y    R180 S3      
317GND              J12   -Y10 MD0197PA00X+053429Y+145784X0357Y    R180 S3      
317GND              J12   -W9  MD0197PA00X+052563Y+146886X0357Y    R180 S3      
317GND              J12   -V10 MD0197PA00X+053429Y+147319X0357Y    R180 S3      
317GND              J12   -T9  MD0197PA00X+052563Y+148421X0357Y    R180 S3      
317GND              J12   -S10 MD0197PA00X+053429Y+148854X0357Y    R180 S3      
317GND              J12   -Q9  MD0197PA00X+052563Y+149957X0357Y    R180 S3      
317GND              J12   -P10 MD0197PA00X+053429Y+150390X0357Y    R180 S3      
317GND              J12   -N2_9MD0197PA00X+052563Y+151492X0357Y    R180 S3      
317GND              J12   -N1_9MD0197PA00X+052563Y+155587X0357Y    R180 S3      
317GND              J12   -M2_1MD0197PA00X+053429Y+151925X0357Y    R180 S3      
317GND              J12   -M1_1MD0197PA00X+053429Y+156020X0357Y    R180 S3      
317GND              J12   -K9  MD0197PA00X+052563Y+157122X0357Y    R180 S3      
317GND              J12   -J10 MD0197PA00X+053429Y+157555X0357Y    R180 S3      
317GND              J12   -H9  MD0197PA00X+052563Y+158658X0357Y    R180 S3      
317GND              J12   -G10 MD0197PA00X+053429Y+159091X0357Y    R180 S3      
317GND              J12   -E9  MD0197PA00X+052563Y+160193X0357Y    R180 S3      
317GND              J12   -D10 MD0197PA00X+053429Y+160626X0357Y    R180 S3      
317GND              J12   -B9  MD0197PA00X+052563Y+161728X0357Y    R180 S3      
317GND              J12   -A10 MD0197PA00X+053429Y+162162X0357Y    R180 S3      
317GND              J12   -Z7  MD0197PA00X+050831Y+145350X0357Y    R180 S3      
317GND              J12   -Y8  MD0197PA00X+051697Y+145784X0357Y    R180 S3      
317GND              J12   -W7  MD0197PA00X+050831Y+146886X0357Y    R180 S3      
317GND              J12   -V8  MD0197PA00X+051697Y+147319X0357Y    R180 S3      
317GND              J12   -T7  MD0197PA00X+050831Y+148421X0357Y    R180 S3      
317GND              J12   -S8  MD0197PA00X+051697Y+148854X0357Y    R180 S3      
317GND              J12   -Q7  MD0197PA00X+050831Y+149957X0357Y    R180 S3      
317GND              J12   -P8  MD0197PA00X+051697Y+150390X0357Y    R180 S3      
317GND              J12   -N2_7MD0197PA00X+050831Y+151492X0357Y    R180 S3      
317GND              J12   -N1_7MD0197PA00X+050831Y+155587X0357Y    R180 S3      
317GND              J12   -M2_8MD0197PA00X+051697Y+151925X0357Y    R180 S3      
317GND              J12   -M1_8MD0197PA00X+051697Y+156020X0357Y    R180 S3      
317GND              J12   -K7  MD0197PA00X+050831Y+157122X0357Y    R180 S3      
317GND              J12   -J8  MD0197PA00X+051697Y+157555X0357Y    R180 S3      
317GND              J12   -H7  MD0197PA00X+050831Y+158658X0357Y    R180 S3      
317GND              J12   -G8  MD0197PA00X+051697Y+159091X0357Y    R180 S3      
317GND              J12   -E7  MD0197PA00X+050831Y+160193X0357Y    R180 S3      
317GND              J12   -D8  MD0197PA00X+051697Y+160626X0357Y    R180 S3      
317GND              J12   -B7  MD0197PA00X+050831Y+161728X0357Y    R180 S3      
317GND              J12   -A8  MD0197PA00X+051697Y+162162X0357Y    R180 S3      
317GND              J12   -Z5  MD0197PA00X+049098Y+145350X0357Y    R180 S3      
317GND              J12   -Y6  MD0197PA00X+049965Y+145784X0357Y    R180 S3      
317GND              J12   -W5  MD0197PA00X+049098Y+146886X0357Y    R180 S3      
317GND              J12   -V6  MD0197PA00X+049965Y+147319X0357Y    R180 S3      
317GND              J12   -T5  MD0197PA00X+049098Y+148421X0357Y    R180 S3      
317GND              J12   -S6  MD0197PA00X+049965Y+148854X0357Y    R180 S3      
317GND              J12   -Q5  MD0197PA00X+049098Y+149957X0357Y    R180 S3      
317GND              J12   -P6  MD0197PA00X+049965Y+150390X0357Y    R180 S3      
317GND              J12   -N2_5MD0197PA00X+049098Y+151492X0357Y    R180 S3      
317GND              J12   -N1_5MD0197PA00X+049098Y+155587X0357Y    R180 S3      
317GND              J12   -M2_6MD0197PA00X+049965Y+151925X0357Y    R180 S3      
317GND              J12   -M1_6MD0197PA00X+049965Y+156020X0357Y    R180 S3      
317GND              J12   -K5  MD0197PA00X+049098Y+157122X0357Y    R180 S3      
317GND              J12   -J6  MD0197PA00X+049965Y+157555X0357Y    R180 S3      
317GND              J12   -H5  MD0197PA00X+049098Y+158658X0357Y    R180 S3      
317GND              J12   -G6  MD0197PA00X+049965Y+159091X0357Y    R180 S3      
317GND              J12   -E5  MD0197PA00X+049098Y+160193X0357Y    R180 S3      
317GND              J12   -D6  MD0197PA00X+049965Y+160626X0357Y    R180 S3      
317GND              J12   -B5  MD0197PA00X+049098Y+161728X0357Y    R180 S3      
317GND              J12   -A6  MD0197PA00X+049965Y+162162X0357Y    R180 S3      
317GND              J12   -Z3  MD0197PA00X+047366Y+145350X0357Y    R180 S3      
317GND              J12   -Y4  MD0197PA00X+048232Y+145784X0357Y    R180 S3      
317GND              J12   -W3  MD0197PA00X+047366Y+146886X0357Y    R180 S3      
317GND              J12   -V4  MD0197PA00X+048232Y+147319X0357Y    R180 S3      
317GND              J12   -T3  MD0197PA00X+047366Y+148421X0357Y    R180 S3      
317GND              J12   -S4  MD0197PA00X+048232Y+148854X0357Y    R180 S3      
317GND              J12   -Q3  MD0197PA00X+047366Y+149957X0357Y    R180 S3      
317GND              J12   -P4  MD0197PA00X+048232Y+150390X0357Y    R180 S3      
317GND              J12   -N2_3MD0197PA00X+047366Y+151492X0357Y    R180 S3      
317GND              J12   -N1_3MD0197PA00X+047366Y+155587X0357Y    R180 S3      
317GND              J12   -M2_4MD0197PA00X+048232Y+151925X0357Y    R180 S3      
317GND              J12   -M1_4MD0197PA00X+048232Y+156020X0357Y    R180 S3      
317GND              J12   -K3  MD0197PA00X+047366Y+157122X0357Y    R180 S3      
317GND              J12   -J4  MD0197PA00X+048232Y+157555X0357Y    R180 S3      
317GND              J12   -H3  MD0197PA00X+047366Y+158658X0357Y    R180 S3      
317GND              J12   -G4  MD0197PA00X+048232Y+159091X0357Y    R180 S3      
317GND              J12   -E3  MD0197PA00X+047366Y+160193X0357Y    R180 S3      
317GND              J12   -D4  MD0197PA00X+048232Y+160626X0357Y    R180 S3      
317GND              J12   -B3  MD0197PA00X+047366Y+161728X0357Y    R180 S3      
317GND              J12   -A4  MD0197PA00X+048232Y+162162X0357Y    R180 S3      
317GND              J12   -Z1  MD0197PA00X+045634Y+145350X0357Y    R180 S3      
317GND              J12   -Y2  MD0197PA00X+046500Y+145784X0357Y    R180 S3      
317GND              J12   -W1  MD0197PA00X+045634Y+146886X0357Y    R180 S3      
317GND              J12   -V2  MD0197PA00X+046500Y+147319X0357Y    R180 S3      
317GND              J12   -T1  MD0197PA00X+045634Y+148421X0357Y    R180 S3      
317GND              J12   -S2  MD0197PA00X+046500Y+148854X0357Y    R180 S3      
317GND              J12   -Q1  MD0197PA00X+045634Y+149957X0357Y    R180 S3      
317GND              J12   -P2  MD0197PA00X+046500Y+150390X0357Y    R180 S3      
317GND              J12   -N2_1MD0197PA00X+045634Y+151492X0357Y    R180 S3      
317GND              J12   -N1_1MD0197PA00X+045634Y+155587X0357Y    R180 S3      
317GND              J12   -M2_2MD0197PA00X+046500Y+151925X0357Y    R180 S3      
317GND              J12   -M1_2MD0197PA00X+046500Y+156020X0357Y    R180 S3      
317GND              J12   -K1  MD0197PA00X+045634Y+157122X0357Y    R180 S3      
317GND              J12   -J2  MD0197PA00X+046500Y+157555X0357Y    R180 S3      
317GND              J12   -H1  MD0197PA00X+045634Y+158658X0357Y    R180 S3      
317GND              J12   -G2  MD0197PA00X+046500Y+159091X0357Y    R180 S3      
317GND              J12   -E1  MD0197PA00X+045634Y+160193X0357Y    R180 S3      
317GND              J12   -D2  MD0197PA00X+046500Y+160626X0357Y    R180 S3      
317GND              J12   -B1  MD0197PA00X+045634Y+161728X0357Y    R180 S3      
317GND              J12   -A2  MD0197PA00X+046500Y+162162X0357Y    R180 S3      
317GND              H135  -1   MD1260PA00X+053642Y+108665X2560Y         S3      
317GND              H92   -9   MD0220PA00X+058393Y+125327X0300Y         S3      
317GND              H92   -8   MD0220PA00X+057382Y+124909X0300Y         S3      
317GND              H92   -7   MD0220PA00X+056371Y+125327X0300Y         S3      
317GND              H92   -6   MD0220PA00X+055952Y+126339X0300Y         S3      
317GND              H92   -5   MD0220PA00X+056371Y+127350X0300Y         S3      
317GND              H92   -4   MD0220PA00X+057382Y+127769X0300Y         S3      
317GND              H92   -3   MD0220PA00X+058393Y+127350X0300Y         S3      
317GND              H92   -2   MD0220PA00X+058812Y+126339X0300Y         S3      
317GND              H89   -9   MD0220PA00X+058393Y+105642X0300Y         S3      
317GND              H89   -8   MD0220PA00X+057382Y+105224X0300Y         S3      
317GND              H89   -7   MD0220PA00X+056371Y+105642X0300Y         S3      
317GND              H89   -6   MD0220PA00X+055952Y+106654X0300Y         S3      
317GND              H89   -5   MD0220PA00X+056371Y+107665X0300Y         S3      
317GND              H89   -4   MD0220PA00X+057382Y+108084X0300Y         S3      
317GND              H89   -3   MD0220PA00X+058393Y+107665X0300Y         S3      
317GND              H89   -2   MD0220PA00X+058812Y+106654X0300Y         S3      
317GND              J5    -Z9  MD0197PA00X+069886Y+145350X0357Y    R180 S3      
317GND              J5    -Y10 MD0197PA00X+070752Y+145784X0357Y    R180 S3      
317GND              J5    -W9  MD0197PA00X+069886Y+146886X0357Y    R180 S3      
317GND              J5    -V10 MD0197PA00X+070752Y+147319X0357Y    R180 S3      
317GND              J5    -T9  MD0197PA00X+069886Y+148421X0357Y    R180 S3      
317GND              J5    -S10 MD0197PA00X+070752Y+148854X0357Y    R180 S3      
317GND              J5    -Q9  MD0197PA00X+069886Y+149957X0357Y    R180 S3      
317GND              J5    -P10 MD0197PA00X+070752Y+150390X0357Y    R180 S3      
317GND              J5    -N2_9MD0197PA00X+069886Y+151492X0357Y    R180 S3      
317GND              J5    -N1_9MD0197PA00X+069886Y+155587X0357Y    R180 S3      
317GND              J5    -M2_1MD0197PA00X+070752Y+151925X0357Y    R180 S3      
317GND              J5    -M1_1MD0197PA00X+070752Y+156020X0357Y    R180 S3      
317GND              J5    -K9  MD0197PA00X+069886Y+157122X0357Y    R180 S3      
317GND              J5    -J10 MD0197PA00X+070752Y+157555X0357Y    R180 S3      
317GND              J5    -H9  MD0197PA00X+069886Y+158658X0357Y    R180 S3      
317GND              J5    -G10 MD0197PA00X+070752Y+159091X0357Y    R180 S3      
317GND              J5    -E9  MD0197PA00X+069886Y+160193X0357Y    R180 S3      
317GND              J5    -D10 MD0197PA00X+070752Y+160626X0357Y    R180 S3      
317GND              J5    -B9  MD0197PA00X+069886Y+161728X0357Y    R180 S3      
317GND              J5    -A10 MD0197PA00X+070752Y+162162X0357Y    R180 S3      
317GND              J5    -Z7  MD0197PA00X+068154Y+145350X0357Y    R180 S3      
317GND              J5    -Y8  MD0197PA00X+069020Y+145784X0357Y    R180 S3      
317GND              J5    -W7  MD0197PA00X+068154Y+146886X0357Y    R180 S3      
317GND              J5    -V8  MD0197PA00X+069020Y+147319X0357Y    R180 S3      
317GND              J5    -T7  MD0197PA00X+068154Y+148421X0357Y    R180 S3      
317GND              J5    -S8  MD0197PA00X+069020Y+148854X0357Y    R180 S3      
317GND              J5    -Q7  MD0197PA00X+068154Y+149957X0357Y    R180 S3      
317GND              J5    -P8  MD0197PA00X+069020Y+150390X0357Y    R180 S3      
317GND              J5    -N2_7MD0197PA00X+068154Y+151492X0357Y    R180 S3      
317GND              J5    -N1_7MD0197PA00X+068154Y+155587X0357Y    R180 S3      
317GND              J5    -M2_8MD0197PA00X+069020Y+151925X0357Y    R180 S3      
317GND              J5    -M1_8MD0197PA00X+069020Y+156020X0357Y    R180 S3      
317GND              J5    -K7  MD0197PA00X+068154Y+157122X0357Y    R180 S3      
317GND              J5    -J8  MD0197PA00X+069020Y+157555X0357Y    R180 S3      
317GND              J5    -H7  MD0197PA00X+068154Y+158658X0357Y    R180 S3      
317GND              J5    -G8  MD0197PA00X+069020Y+159091X0357Y    R180 S3      
317GND              J5    -E7  MD0197PA00X+068154Y+160193X0357Y    R180 S3      
317GND              J5    -D8  MD0197PA00X+069020Y+160626X0357Y    R180 S3      
317GND              J5    -B7  MD0197PA00X+068154Y+161728X0357Y    R180 S3      
317GND              J5    -A8  MD0197PA00X+069020Y+162162X0357Y    R180 S3      
317GND              J5    -Z5  MD0197PA00X+066421Y+145350X0357Y    R180 S3      
317GND              J5    -Y6  MD0197PA00X+067287Y+145784X0357Y    R180 S3      
317GND              J5    -W5  MD0197PA00X+066421Y+146886X0357Y    R180 S3      
317GND              J5    -V6  MD0197PA00X+067287Y+147319X0357Y    R180 S3      
317GND              J5    -T5  MD0197PA00X+066421Y+148421X0357Y    R180 S3      
317GND              J5    -S6  MD0197PA00X+067287Y+148854X0357Y    R180 S3      
317GND              J5    -Q5  MD0197PA00X+066421Y+149957X0357Y    R180 S3      
317GND              J5    -P6  MD0197PA00X+067287Y+150390X0357Y    R180 S3      
317GND              J5    -N2_5MD0197PA00X+066421Y+151492X0357Y    R180 S3      
317GND              J5    -N1_5MD0197PA00X+066421Y+155587X0357Y    R180 S3      
317GND              J5    -M2_6MD0197PA00X+067287Y+151925X0357Y    R180 S3      
317GND              J5    -M1_6MD0197PA00X+067287Y+156020X0357Y    R180 S3      
317GND              J5    -K5  MD0197PA00X+066421Y+157122X0357Y    R180 S3      
317GND              J5    -J6  MD0197PA00X+067287Y+157555X0357Y    R180 S3      
317GND              J5    -H5  MD0197PA00X+066421Y+158658X0357Y    R180 S3      
317GND              J5    -G6  MD0197PA00X+067287Y+159091X0357Y    R180 S3      
317GND              J5    -E5  MD0197PA00X+066421Y+160193X0357Y    R180 S3      
317GND              J5    -D6  MD0197PA00X+067287Y+160626X0357Y    R180 S3      
317GND              J5    -B5  MD0197PA00X+066421Y+161728X0357Y    R180 S3      
317GND              J5    -A6  MD0197PA00X+067287Y+162162X0357Y    R180 S3      
317GND              J5    -Z3  MD0197PA00X+064689Y+145350X0357Y    R180 S3      
317GND              J5    -Y4  MD0197PA00X+065555Y+145784X0357Y    R180 S3      
317GND              J5    -W3  MD0197PA00X+064689Y+146886X0357Y    R180 S3      
317GND              J5    -V4  MD0197PA00X+065555Y+147319X0357Y    R180 S3      
317GND              J5    -T3  MD0197PA00X+064689Y+148421X0357Y    R180 S3      
317GND              J5    -S4  MD0197PA00X+065555Y+148854X0357Y    R180 S3      
317GND              J5    -Q3  MD0197PA00X+064689Y+149957X0357Y    R180 S3      
317GND              J5    -P4  MD0197PA00X+065555Y+150390X0357Y    R180 S3      
317GND              J5    -N2_3MD0197PA00X+064689Y+151492X0357Y    R180 S3      
317GND              J5    -N1_3MD0197PA00X+064689Y+155587X0357Y    R180 S3      
317GND              J5    -M2_4MD0197PA00X+065555Y+151925X0357Y    R180 S3      
317GND              J5    -M1_4MD0197PA00X+065555Y+156020X0357Y    R180 S3      
317GND              J5    -K3  MD0197PA00X+064689Y+157122X0357Y    R180 S3      
317GND              J5    -J4  MD0197PA00X+065555Y+157555X0357Y    R180 S3      
317GND              J5    -H3  MD0197PA00X+064689Y+158658X0357Y    R180 S3      
317GND              J5    -G4  MD0197PA00X+065555Y+159091X0357Y    R180 S3      
317GND              J5    -E3  MD0197PA00X+064689Y+160193X0357Y    R180 S3      
317GND              J5    -D4  MD0197PA00X+065555Y+160626X0357Y    R180 S3      
317GND              J5    -B3  MD0197PA00X+064689Y+161728X0357Y    R180 S3      
317GND              J5    -A4  MD0197PA00X+065555Y+162162X0357Y    R180 S3      
317GND              J5    -Z1  MD0197PA00X+062957Y+145350X0357Y    R180 S3      
317GND              J5    -Y2  MD0197PA00X+063823Y+145784X0357Y    R180 S3      
317GND              J5    -W1  MD0197PA00X+062957Y+146886X0357Y    R180 S3      
317GND              J5    -V2  MD0197PA00X+063823Y+147319X0357Y    R180 S3      
317GND              J5    -T1  MD0197PA00X+062957Y+148421X0357Y    R180 S3      
317GND              J5    -S2  MD0197PA00X+063823Y+148854X0357Y    R180 S3      
317GND              J5    -Q1  MD0197PA00X+062957Y+149957X0357Y    R180 S3      
317GND              J5    -P2  MD0197PA00X+063823Y+150390X0357Y    R180 S3      
317GND              J5    -N2_1MD0197PA00X+062957Y+151492X0357Y    R180 S3      
317GND              J5    -N1_1MD0197PA00X+062957Y+155587X0357Y    R180 S3      
317GND              J5    -M2_2MD0197PA00X+063823Y+151925X0357Y    R180 S3      
317GND              J5    -M1_2MD0197PA00X+063823Y+156020X0357Y    R180 S3      
317GND              J5    -K1  MD0197PA00X+062957Y+157122X0357Y    R180 S3      
317GND              J5    -J2  MD0197PA00X+063823Y+157555X0357Y    R180 S3      
317GND              J5    -H1  MD0197PA00X+062957Y+158658X0357Y    R180 S3      
317GND              J5    -G2  MD0197PA00X+063823Y+159091X0357Y    R180 S3      
317GND              J5    -E1  MD0197PA00X+062957Y+160193X0357Y    R180 S3      
317GND              J5    -D2  MD0197PA00X+063823Y+160626X0357Y    R180 S3      
317GND              J5    -B1  MD0197PA00X+062957Y+161728X0357Y    R180 S3      
317GND              J5    -A2  MD0197PA00X+063823Y+162162X0357Y    R180 S3      
317GND              H84   -9   MD0220PA00X+082015Y+125327X0300Y         S3      
317GND              H84   -8   MD0220PA00X+081004Y+124909X0300Y         S3      
317GND              H84   -7   MD0220PA00X+079993Y+125327X0300Y         S3      
317GND              H84   -6   MD0220PA00X+079574Y+126339X0300Y         S3      
317GND              H84   -5   MD0220PA00X+079993Y+127350X0300Y         S3      
317GND              H84   -4   MD0220PA00X+081004Y+127769X0300Y         S3      
317GND              H84   -3   MD0220PA00X+082015Y+127350X0300Y         S3      
317GND              H84   -2   MD0220PA00X+082434Y+126339X0300Y         S3      
317GND              H98   -9   MD0220PA00X+082015Y+105642X0300Y         S3      
317GND              H98   -8   MD0220PA00X+081004Y+105224X0300Y         S3      
317GND              H98   -7   MD0220PA00X+079993Y+105642X0300Y         S3      
317GND              H98   -6   MD0220PA00X+079574Y+106654X0300Y         S3      
317GND              H98   -5   MD0220PA00X+079993Y+107665X0300Y         S3      
317GND              H98   -4   MD0220PA00X+081004Y+108084X0300Y         S3      
317GND              H98   -3   MD0220PA00X+082015Y+107665X0300Y         S3      
317GND              H98   -2   MD0220PA00X+082434Y+106654X0300Y         S3      
327GND              U5    -G10        A01X+089869Y+085632X0160Y    R180 S1      
327GND              U5    -G9         A01X+090184Y+085632X0160Y    R180 S1      
327GND              U5    -H9         A01X+090184Y+085946X0160Y    R180 S1      
327GND              U5    -G8         A01X+090499Y+085632X0160Y    R180 S1      
327GND              U5    -C7         A01X+090814Y+084372X0160Y    R180 S1      
327GND              U5    -D7         A01X+090814Y+084687X0160Y    R180 S1      
327GND              U5    -C6         A01X+091129Y+084372X0160Y    R180 S1      
327GND              U5    -D6         A01X+091129Y+084687X0160Y    R180 S1      
327GND              U5    -E6         A01X+091129Y+085002X0160Y    R180 S1      
327GND              U5    -K7         A01X+090814Y+086576X0160Y    R180 S1      
327GND              U5    -J7         A01X+090814Y+086262X0160Y    R180 S1      
327GND              U5    -J8         A01X+090499Y+086262X0160Y    R180 S1      
327GND              U5    -H7         A01X+090814Y+085946X0160Y    R180 S1      
327GND              U5    -H8         A01X+090499Y+085946X0160Y    R180 S1      
327GND              U5    -G7         A01X+090814Y+085632X0160Y    R180 S1      
327GND              U5    -F3         A01X+092074Y+085317X0160Y    R180 S1      
327GND              U5    -K10        A01X+089869Y+086576X0160Y    R180 S1      
327GND              U5    -L10        A01X+089869Y+086891X0160Y    R180 S1      
327GND              U5    -M10        A01X+089869Y+087206X0160Y    R180 S1      
327GND              U5    -J9         A01X+090184Y+086262X0160Y    R180 S1      
327GND              U5    -K9         A01X+090184Y+086576X0160Y    R180 S1      
327GND              U5    -L9         A01X+090184Y+086891X0160Y    R180 S1      
327GND              U5    -M9         A01X+090184Y+087206X0160Y    R180 S1      
327GND              U5    -K8         A01X+090499Y+086576X0160Y    R180 S1      
327GND              U5    -L8         A01X+090499Y+086891X0160Y    R180 S1      
327GND              U5    -M8         A01X+090499Y+087206X0160Y    R180 S1      
327GND              U5    -L7         A01X+090814Y+086891X0160Y    R180 S1      
327GND              U5    -M7         A01X+090814Y+087206X0160Y    R180 S1      
327GND              U5    -J10        A01X+089869Y+086262X0160Y    R180 S1      
327GND              U5    -H10        A01X+089869Y+085946X0160Y    R180 S1      
317GND              VIA   -    MD0100PA00X+089712Y+085474X0180Y    R270 S0      
317GND              VIA   -    MD0100PA00X+090027Y+085474X0180Y    R270 S0      
317GND              VIA   -    MD0100PA00X+090027Y+085789X0180Y    R270 S0      
317GND              VIA   -    MD0100PA00X+090656Y+085474X0180Y    R270 S0      
317GND              VIA   -    MD0100PA00X+090971Y+084214X0180Y    R270 S0      
317GND              VIA   -    MD0100PA00X+090971Y+084529X0180Y    R270 S0      
317GND              VIA   -    MD0100PA00X+091286Y+084214X0180Y    R270 S0      
317GND              VIA   -    MD0100PA00X+091286Y+084529X0180Y    R270 S0      
317GND              VIA   -    MD0100PA00X+091286Y+084844X0180Y    R270 S0      
317GND              VIA   -    MD0100PA00X+090971Y+086734X0180Y    R270 S0      
317GND              VIA   -    MD0100PA00X+090971Y+086419X0180Y    R270 S0      
317GND              VIA   -    MD0100PA00X+090656Y+086419X0180Y    R270 S0      
317GND              VIA   -    MD0100PA00X+090971Y+085789X0180Y    R270 S0      
317GND              VIA   -    MD0100PA00X+090656Y+085789X0180Y    R270 S0      
317GND              VIA   -    MD0100PA00X+090971Y+085474X0180Y    R270 S0      
317GND              VIA   -    MD0100PA00X+092231Y+085159X0180Y    R270 S0      
317GND              VIA   -    MD0100PA00X+089712Y+086734X0180Y    R270 S0      
317GND              VIA   -    MD0100PA00X+089712Y+087049X0180Y    R270 S0      
317GND              VIA   -    MD0100PA00X+089712Y+087364X0180Y    R270 S0      
317GND              VIA   -    MD0100PA00X+090027Y+086419X0180Y    R270 S0      
317GND              VIA   -    MD0100PA00X+090027Y+086734X0180Y    R270 S0      
317GND              VIA   -    MD0100PA00X+090027Y+087049X0180Y    R270 S0      
317GND              VIA   -    MD0100PA00X+090027Y+087364X0180Y    R270 S0      
317GND              VIA   -    MD0100PA00X+090656Y+086734X0180Y    R270 S0      
317GND              VIA   -    MD0100PA00X+090656Y+087049X0180Y    R270 S0      
317GND              VIA   -    MD0100PA00X+090656Y+087364X0180Y    R270 S0      
317GND              VIA   -    MD0100PA00X+090971Y+087049X0180Y    R270 S0      
317GND              VIA   -    MD0100PA00X+090971Y+087364X0180Y    R270 S0      
317GND              VIA   -    MD0100PA00X+089712Y+086419X0180Y    R270 S0      
317GND              VIA   -    MD0100PA00X+089712Y+085789X0180Y    R270 S0      
317GND              H132  -1   MD1260PA00X+085429Y+122512X2560Y         S3      
317GND              H141  -1   MD1260PA00X+099350Y+117075X2560Y         S3      
317GND              JP2   -7   MD0410PA00X+103064Y+076455X0610Y         S3      
317GND              H85   -9   MD0220PA00X+104102Y+125327X0300Y         S3      
317GND              H85   -8   MD0220PA00X+103090Y+124909X0300Y         S3      
317GND              H85   -7   MD0220PA00X+102079Y+125327X0300Y         S3      
317GND              H85   -6   MD0220PA00X+101660Y+126339X0300Y         S3      
317GND              H85   -5   MD0220PA00X+102079Y+127350X0300Y         S3      
317GND              H85   -4   MD0220PA00X+103090Y+127769X0300Y         S3      
317GND              H85   -3   MD0220PA00X+104102Y+127350X0300Y         S3      
317GND              H85   -2   MD0220PA00X+104520Y+126339X0300Y         S3      
317GND              H87   -9   MD0220PA00X+104102Y+105642X0300Y         S3      
317GND              H87   -8   MD0220PA00X+103090Y+105224X0300Y         S3      
317GND              H87   -7   MD0220PA00X+102079Y+105642X0300Y         S3      
317GND              H87   -6   MD0220PA00X+101660Y+106654X0300Y         S3      
317GND              H87   -5   MD0220PA00X+102079Y+107665X0300Y         S3      
317GND              H87   -4   MD0220PA00X+103090Y+108084X0300Y         S3      
317GND              H87   -3   MD0220PA00X+104102Y+107665X0300Y         S3      
317GND              H87   -2   MD0220PA00X+104520Y+106654X0300Y         S3      
327GND              R1357 -1          A01X+107401Y+099511X0198Y0197R270 S1      
327GND              PEX2  -BA1        A01X+105925Y+110512X0180Y         S1      
327GND              PEX2  -BC1        A01X+105925Y+109764X0180Y         S1      
327GND              PEX2  -BF1        A01X+105925Y+108642X0180Y         S1      
327GND              PEX2  -AF1        A01X+105925Y+116122X0180Y         S1      
327GND              PEX2  -AK1        A01X+105925Y+114626X0180Y         S1      
327GND              PEX2  -AH1        A01X+105925Y+115374X0180Y         S1      
327GND              PEX2  -AR1        A01X+105925Y+112756X0180Y         S1      
327GND              PEX2  -AN1        A01X+105925Y+113504X0180Y         S1      
327GND              PEX2  -AW1        A01X+105925Y+111260X0180Y         S1      
327GND              PEX2  -AU1        A01X+105925Y+112008X0180Y         S1      
327GND              PEX2  -BH4        A01X+107047Y+107894X0180Y         S1      
327GND              PEX2  -BH2        A01X+106299Y+107894X0180Y         S1      
327GND              PEX2  -BH1        A01X+105925Y+107894X0180Y         S1      
327GND              PEX2  -BG5        A01X+107421Y+108268X0180Y         S1      
327GND              PEX2  -BG3        A01X+106673Y+108268X0180Y         S1      
327GND              PEX2  -BF5        A01X+107421Y+108642X0180Y         S1      
327GND              PEX2  -BF3        A01X+106673Y+108642X0180Y         S1      
327GND              PEX2  -BF2        A01X+106299Y+108642X0180Y         S1      
327GND              PEX2  -BE5        A01X+107421Y+109016X0180Y         S1      
327GND              PEX2  -BE4        A01X+107047Y+109016X0180Y         S1      
327GND              PEX2  -BE3        A01X+106673Y+109016X0180Y         S1      
327GND              PEX2  -BJ4        A01X+107047Y+107520X0180Y         S1      
327GND              PEX2  -AD1        A01X+105925Y+116870X0180Y         S1      
327GND              PEX2  -AF3        A01X+106673Y+116122X0180Y         S1      
327GND              PEX2  -AF2        A01X+106299Y+116122X0180Y         S1      
327GND              PEX2  -AE5        A01X+107421Y+116496X0180Y         S1      
327GND              PEX2  -AE4 M      A01X+107047Y+116496X0180Y         S1      
327GND              PEX2  -AE3        A01X+106673Y+116496X0180Y         S1      
327GND              PEX2  -AD3        A01X+106673Y+116870X0180Y         S1      
327GND              PEX2  -AD2        A01X+106299Y+116870X0180Y         S1      
327GND              PEX2  -AK3        A01X+106673Y+114626X0180Y         S1      
327GND              PEX2  -AK2        A01X+106299Y+114626X0180Y         S1      
327GND              PEX2  -AJ5        A01X+107421Y+115000X0180Y         S1      
327GND              PEX2  -AJ4        A01X+107047Y+115000X0180Y         S1      
327GND              PEX2  -AJ3        A01X+106673Y+115000X0180Y         S1      
327GND              PEX2  -AH3        A01X+106673Y+115374X0180Y         S1      
327GND              PEX2  -AH2        A01X+106299Y+115374X0180Y         S1      
327GND              PEX2  -AG5        A01X+107421Y+115748X0180Y         S1      
327GND              PEX2  -AG4        A01X+107047Y+115748X0180Y         S1      
327GND              PEX2  -AG3        A01X+106673Y+115748X0180Y         S1      
327GND              PEX2  -AR5        A01X+107421Y+112756X0180Y         S1      
327GND              PEX2  -AR2        A01X+106299Y+112756X0180Y         S1      
327GND              PEX2  -AP5        A01X+107421Y+113130X0180Y         S1      
327GND              PEX2  -AP4        A01X+107047Y+113130X0180Y         S1      
327GND              PEX2  -AP3        A01X+106673Y+113130X0180Y         S1      
327GND              PEX2  -AN2        A01X+106299Y+113504X0180Y         S1      
327GND              PEX2  -AM3        A01X+106673Y+113878X0180Y         S1      
327GND              PEX2  -AN5        A01X+107421Y+113504X0180Y         S1      
327GND              PEX2  -AW5        A01X+107421Y+111260X0180Y         S1      
327GND              PEX2  -AW2        A01X+106299Y+111260X0180Y         S1      
327GND              PEX2  -AV5        A01X+107421Y+111634X0180Y         S1      
327GND              PEX2  -AV4        A01X+107047Y+111634X0180Y         S1      
327GND              PEX2  -AV3        A01X+106673Y+111634X0180Y         S1      
327GND              PEX2  -AU5        A01X+107421Y+112008X0180Y         S1      
327GND              PEX2  -AU2        A01X+106299Y+112008X0180Y         S1      
327GND              PEX2  -AT5        A01X+107421Y+112382X0180Y         S1      
327GND              PEX2  -AT4        A01X+107047Y+112382X0180Y         S1      
327GND              PEX2  -AT3        A01X+106673Y+112382X0180Y         S1      
327GND              PEX2  -BB3        A01X+106673Y+110138X0180Y         S1      
327GND              PEX2  -BA5        A01X+107421Y+110512X0180Y         S1      
327GND              PEX2  -BA3        A01X+106673Y+110512X0180Y         S1      
327GND              PEX2  -BA2        A01X+106299Y+110512X0180Y         S1      
327GND              PEX2  -AY5        A01X+107421Y+110886X0180Y         S1      
327GND              PEX2  -AY4        A01X+107047Y+110886X0180Y         S1      
327GND              PEX2  -AY3        A01X+106673Y+110886X0180Y         S1      
327GND              PEX2  -BC4        A01X+107047Y+109764X0180Y         S1      
327GND              PEX2  -BC2        A01X+106299Y+109764X0180Y         S1      
327GND              PEX2  -BB5        A01X+107421Y+110138X0180Y         S1      
327GND              PEX2  -BJ2        A01X+106299Y+107520X0180Y         S1      
317GND              VIA   -    MD0100PA00X+107146Y+163980X0200Y         S0      
327GND              PEX2  -AP10       A01X+109291Y+113130X0180Y         S1      
327GND              PEX2  -AM10       A01X+109291Y+113878X0180Y         S1      
327GND              PEX2  -AR9        A01X+108917Y+112756X0180Y         S1      
327GND              PEX2  -AR8        A01X+108543Y+112756X0180Y         S1      
327GND              PEX2  -AP7        A01X+108169Y+113130X0180Y         S1      
327GND              PEX2  -AN9        A01X+108917Y+113504X0180Y         S1      
327GND              PEX2  -AN8        A01X+108543Y+113504X0180Y         S1      
327GND              PEX2  -AV10       A01X+109291Y+111634X0180Y         S1      
327GND              PEX2  -AU10       A01X+109291Y+112008X0180Y         S1      
327GND              PEX2  -AT10       A01X+109291Y+112382X0180Y         S1      
327GND              PEX2  -AW9        A01X+108917Y+111260X0180Y         S1      
327GND              PEX2  -AW8        A01X+108543Y+111260X0180Y         S1      
327GND              PEX2  -AV7        A01X+108169Y+111634X0180Y         S1      
327GND              PEX2  -AU9        A01X+108917Y+112008X0180Y         S1      
327GND              PEX2  -AU8        A01X+108543Y+112008X0180Y         S1      
327GND              PEX2  -AT7        A01X+108169Y+112382X0180Y         S1      
327GND              PEX2  -BB7        A01X+108169Y+110138X0180Y         S1      
327GND              PEX2  -BA7        A01X+108169Y+110512X0180Y         S1      
327GND              PEX2  -AY8        A01X+108543Y+110886X0180Y         S1      
327GND              PEX2  -AY7        A01X+108169Y+110886X0180Y         S1      
327GND              PEX2  -BG7        A01X+108169Y+108268X0180Y         S1      
327GND              PEX2  -BE7        A01X+108169Y+109016X0180Y         S1      
327GND              PEX2  -AE6        A01X+107795Y+116496X0180Y         S1      
327GND              PEX2  -AD6        A01X+107795Y+116870X0180Y         S1      
327GND              PEX2  -AF9        A01X+108917Y+116122X0180Y         S1      
327GND              PEX2  -AK9        A01X+108917Y+114626X0180Y         S1      
327GND              PEX2  -AK8        A01X+108543Y+114626X0180Y         S1      
327GND              PEX2  -AJ9        A01X+108917Y+115000X0180Y         S1      
327GND              PEX2  -AG9        A01X+108917Y+115748X0180Y         S1      
327GND              PEX2  -AH9        A01X+108917Y+115374X0180Y         S1      
327GND              PEX2  -AR10       A01X+109291Y+112756X0180Y         S1      
327GND              PEX2  -AF13       A01X+110413Y+116122X0180Y         S1      
327GND              PEX2  -AG10       A01X+109291Y+115748X0180Y         S1      
327GND              PEX2  -AF11       A01X+109665Y+116122X0180Y         S1      
327GND              PEX2  -AK13       A01X+110413Y+114626X0180Y         S1      
327GND              PEX2  -AK11M      A01X+109665Y+114626X0180Y         S1      
327GND              PEX2  -AH11M      A01X+109665Y+115374X0180Y         S1      
327GND              PEX2  -AR14       A01X+110787Y+112756X0180Y         S1      
327GND              PEX2  -AR13       A01X+110413Y+112756X0180Y         S1      
327GND              PEX2  -AR12       A01X+110039Y+112756X0180Y         S1      
327GND              PEX2  -AR11       A01X+109665Y+112756X0180Y         S1      
327GND              PEX2  -AP13       A01X+110413Y+113130X0180Y         S1      
327GND              PEX2  -AP12       A01X+110039Y+113130X0180Y         S1      
327GND              PEX2  -AP11       A01X+109665Y+113130X0180Y         S1      
327GND              PEX2  -AN13       A01X+110413Y+113504X0180Y         S1      
327GND              PEX2  -AN12       A01X+110039Y+113504X0180Y         S1      
327GND              PEX2  -AN10M      A01X+109291Y+113504X0180Y         S1      
327GND              PEX2  -AN11       A01X+109665Y+113504X0180Y         S1      
327GND              PEX2  -AM13       A01X+110413Y+113878X0180Y         S1      
327GND              PEX2  -AM11       A01X+109665Y+113878X0180Y         S1      
327GND              PEX2  -AV11       A01X+109665Y+111634X0180Y         S1      
327GND              PEX2  -AU14       A01X+110787Y+112008X0180Y         S1      
327GND              PEX2  -AU13       A01X+110413Y+112008X0180Y         S1      
327GND              PEX2  -AU12       A01X+110039Y+112008X0180Y         S1      
327GND              PEX2  -AU11       A01X+109665Y+112008X0180Y         S1      
327GND              PEX2  -AT14       A01X+110787Y+112382X0180Y         S1      
327GND              PEX2  -AT13       A01X+110413Y+112382X0180Y         S1      
327GND              PEX2  -AT12       A01X+110039Y+112382X0180Y         S1      
327GND              PEX2  -AT11       A01X+109665Y+112382X0180Y         S1      
327GND              PEX2  -AR16       A01X+111535Y+112756X0180Y         S1      
327GND              PEX2  -AU16       A01X+111535Y+112008X0180Y         S1      
327GND              PEX2  -AU15       A01X+111161Y+112008X0180Y         S1      
327GND              PEX2  -AT16       A01X+111535Y+112382X0180Y         S1      
327GND              PEX2  -AT15       A01X+111161Y+112382X0180Y         S1      
327GND              PEX2  -AF19       A01X+112657Y+116122X0180Y         S1      
327GND              PEX2  -AG18M      A01X+112283Y+115748X0180Y         S1      
327GND              PEX2  -AG14M      A01X+110787Y+115748X0180Y         S1      
327GND              PEX2  -AF15       A01X+111161Y+116122X0180Y         S1      
327GND              PEX2  -AH13M      A01X+110413Y+115374X0180Y         S1      
327GND              PEX2  -AF17       A01X+111909Y+116122X0180Y         S1      
327GND              PEX2  -AG16M      A01X+111535Y+115748X0180Y         S1      
327GND              PEX2  -AH15M      A01X+111161Y+115374X0180Y         S1      
327GND              PEX2  -AJ14M      A01X+110787Y+115000X0180Y         S1      
327GND              PEX2  -AE20       A01X+113031Y+116496X0180Y         S1      
327GND              PEX2  -AD19M      A01X+112657Y+116870X0180Y         S1      
327GND              PEX2  -AC18M      A01X+112283Y+117244X0180Y         S1      
327GND              PEX2  -AE22       A01X+113780Y+116496X0180Y         S1      
327GND              PEX2  -AC20M      A01X+113031Y+117244X0180Y         S1      
327GND              PEX2  -AD21M      A01X+113405Y+116870X0180Y         S1      
327GND              PEX2  -AF23       A01X+114154Y+116122X0180Y         S1      
327GND              PEX2  -AG22M      A01X+113780Y+115748X0180Y         S1      
327GND              PEX2  -AF21       A01X+113405Y+116122X0180Y         S1      
327GND              PEX2  -AG20M      A01X+113031Y+115748X0180Y         S1      
327GND              PEX2  -M21        A01X+113405Y+121358X0180Y         S1      
327GND              PEX2  -AJ22M      A01X+113780Y+115000X0180Y         S1      
327GND              PEX2  -AJ19M      A01X+112657Y+115000X0180Y         S1      
327GND              PEX2  -AJ20M      A01X+113031Y+115000X0180Y         S1      
327GND              PEX2  -AJ21M      A01X+113405Y+115000X0180Y         S1      
327GND              PEX2  -AJ24       A01X+114528Y+115000X0180Y         S1      
327GND              PEX2  -AJ23M      A01X+114154Y+115000X0180Y         S1      
327GND              PEX2  -AJ18M      A01X+112283Y+115000X0180Y         S1      
327GND              PEX2  -AJ17M      A01X+111909Y+115000X0180Y         S1      
327GND              PEX2  -AK15M      A01X+111161Y+114626X0180Y         S1      
327GND              PEX2  -AJ16M      A01X+111535Y+115000X0180Y         S1      
327GND              PEX2  -AG24       A01X+114528Y+115748X0180Y         S1      
327GND              PEX2  -AL21M      A01X+113405Y+114252X0180Y         S1      
327GND              PEX2  -AL22M      A01X+113780Y+114252X0180Y         S1      
327GND              PEX2  -AL24       A01X+114528Y+114252X0180Y         S1      
327GND              PEX2  -AL23M      A01X+114154Y+114252X0180Y         S1      
327GND              PEX2  -AL20M      A01X+113031Y+114252X0180Y         S1      
327GND              PEX2  -AL19M      A01X+112657Y+114252X0180Y         S1      
327GND              PEX2  -AL18M      A01X+112283Y+114252X0180Y         S1      
327GND              PEX2  -AL17M      A01X+111909Y+114252X0180Y         S1      
327GND              PEX2  -AL16M      A01X+111535Y+114252X0180Y         S1      
327GND              PEX2  -AN18M      A01X+112283Y+113504X0180Y         S1      
327GND              PEX2  -AN24       A01X+114528Y+113504X0180Y         S1      
327GND              PEX2  -AN23M      A01X+114154Y+113504X0180Y         S1      
327GND              PEX2  -AN22M      A01X+113780Y+113504X0180Y         S1      
327GND              PEX2  -AN19M      A01X+112657Y+113504X0180Y         S1      
327GND              PEX2  -AN20M      A01X+113031Y+113504X0180Y         S1      
327GND              PEX2  -AN21M      A01X+113405Y+113504X0180Y         S1      
327GND              PEX2  -AM15       A01X+111161Y+113878X0180Y         S1      
327GND              PEX2  -AN17M      A01X+111909Y+113504X0180Y         S1      
327GND              PEX2  -AN16M      A01X+111535Y+113504X0180Y         S1      
327GND              PEX2  -AN15M      A01X+111161Y+113504X0180Y         S1      
327GND              PEX2  -AP15M      A01X+111161Y+113130X0180Y         S1      
327GND              PEX2  -AR15M      A01X+111161Y+112756X0180Y         S1      
327GND              PEX2  -AC24       A01X+114528Y+117244X0180Y         S1      
327GND              PEX2  -AG26M      A01X+115276Y+115748X0180Y         S1      
327GND              PEX2  -AF25       A01X+114902Y+116122X0180Y         S1      
327GND              PEX2  -AC22M      A01X+113780Y+117244X0180Y         S1      
327GND              PEX2  -AD23M      A01X+114154Y+116870X0180Y         S1      
327GND              PEX2  -AE24       A01X+114528Y+116496X0180Y         S1      
327GND              PEX2  -AC26M      A01X+115276Y+117244X0180Y         S1      
327GND              PEX2  -AD25       A01X+114902Y+116870X0180Y         S1      
327GND              PEX2  -AF29       A01X+116398Y+116122X0180Y         S1      
327GND              PEX2  -AG30M      A01X+116772Y+115748X0180Y         S1      
327GND              PEX2  -AF27       A01X+115650Y+116122X0180Y         S1      
327GND              PEX2  -AG28M      A01X+116024Y+115748X0180Y         S1      
327GND              PEX2  -AE28       A01X+116024Y+116496X0180Y         S1      
327GND              PEX2  -AD29M      A01X+116398Y+116870X0180Y         S1      
327GND              PEX2  -AC30M      A01X+116772Y+117244X0180Y         S1      
327GND              PEX2  -AC28M      A01X+116024Y+117244X0180Y         S1      
327GND              PEX2  -AD27M      A01X+115650Y+116870X0180Y         S1      
327GND              PEX2  -AE26       A01X+115276Y+116496X0180Y         S1      
327GND              PEX2  -AF31       A01X+117146Y+116122X0180Y         S1      
327GND              PEX2  -AG32M      A01X+117520Y+115748X0180Y         S1      
327GND              PEX2  -AN30M      A01X+116772Y+113504X0180Y         S1      
327GND              PEX2  -AN31M      A01X+117146Y+113504X0180Y         S1      
327GND              PEX2  -AN35M      A01X+118642Y+113504X0180Y         S1      
327GND              PEX2  -AN34M      A01X+118268Y+113504X0180Y         S1      
327GND              PEX2  -AN33M      A01X+117894Y+113504X0180Y         S1      
327GND              PEX2  -AN32M      A01X+117520Y+113504X0180Y         S1      
327GND              PEX2  -AM34       A01X+118268Y+113878X0180Y         S1      
327GND              PEX2  -AN29M      A01X+116398Y+113504X0180Y         S1      
327GND              PEX2  -AN28M      A01X+116024Y+113504X0180Y         S1      
327GND              PEX2  -AN27M      A01X+115650Y+113504X0180Y         S1      
327GND              PEX2  -AN26M      A01X+115276Y+113504X0180Y         S1      
327GND              PEX2  -AN25       A01X+114902Y+113504X0180Y         S1      
327GND              PEX2  -AA26M      A01X+115276Y+117992X0180Y         S1      
327GND              PEX2  -AA25       A01X+114902Y+117992X0180Y         S1      
327GND              PEX2  -AA30M      A01X+116772Y+117992X0180Y         S1      
327GND              PEX2  -AA31M      A01X+117146Y+117992X0180Y         S1      
327GND              PEX2  -AA33M      A01X+117894Y+117992X0180Y         S1      
327GND              PEX2  -Y34 M      A01X+118268Y+118366X0180Y         S1      
327GND              PEX2  -AA32M      A01X+117520Y+117992X0180Y         S1      
327GND              PEX2  -AA29M      A01X+116398Y+117992X0180Y         S1      
327GND              PEX2  -AA28M      A01X+116024Y+117992X0180Y         S1      
327GND              PEX2  -AA27M      A01X+115650Y+117992X0180Y         S1      
327GND              PEX2  -AC32M      A01X+117520Y+117244X0180Y         S1      
327GND              PEX2  -AE30       A01X+116772Y+116496X0180Y         S1      
327GND              PEX2  -AD31M      A01X+117146Y+116870X0180Y         S1      
327GND              PEX2  -AE32       A01X+117520Y+116496X0180Y         S1      
327GND              PEX2  -AG37       A01X+119390Y+115748X0180Y         S1      
327GND              PEX2  -W38        A01X+119764Y+118740X0180Y         S1      
327GND              PEX2  -AF37       A01X+119390Y+116122X0180Y         S1      
327GND              PEX2  -AF44       A01X+122008Y+116122X0180Y         S1      
317GND              J1    -P3_8MD0400PA00X+094801Y+159279X0705Y    R270 S3      
317GND              J1    -P3_7MD0400PA00X+094801Y+160279X0705Y    R270 S3      
317GND              J1    -P3_6MD0400PA00X+094801Y+161279X0705Y    R270 S3      
317GND              J1    -P3_5MD0400PA00X+094801Y+162279X0705Y    R270 S3      
317GND              J1    -P3_4MD0400PA00X+095801Y+159279X0705Y    R270 S3      
317GND              J1    -P3_3MD0400PA00X+095801Y+160279X0705Y    R270 S3      
317GND              J1    -P3_2MD0400PA00X+095801Y+161279X0705Y    R270 S3      
317GND              J1    -P3_1MD0400PA00X+095801Y+162279X0705Y    R270 S3      
317GND              J1    -P2_8MD0400PA00X+098301Y+159279X0705Y    R270 S3      
317GND              J1    -P2_7MD0400PA00X+098301Y+160279X0705Y    R270 S3      
317GND              J1    -P2_6MD0400PA00X+098301Y+161279X0705Y    R270 S3      
317GND              J1    -P2_5MD0400PA00X+098301Y+162279X0705Y    R270 S3      
317GND              J1    -P2_4MD0400PA00X+099301Y+159279X0705Y    R270 S3      
317GND              J1    -P2_3MD0400PA00X+099301Y+160279X0705Y    R270 S3      
317GND              J1    -P2_2MD0400PA00X+099301Y+161279X0705Y    R270 S3      
317GND              J1    -P2_1MD0400PA00X+099301Y+162279X0705Y    R270 S3      
317GND              J1    -P1_8MD0400PA00X+101801Y+159279X0705Y    R270 S3      
317GND              J1    -P1_7MD0400PA00X+101801Y+160279X0705Y    R270 S3      
317GND              J1    -P1_6MD0400PA00X+101801Y+161279X0705Y    R270 S3      
317GND              J1    -P1_5MD0400PA00X+101801Y+162279X0705Y    R270 S3      
317GND              J1    -P1_4MD0400PA00X+102801Y+159279X0705Y    R270 S3      
317GND              J1    -P1_3MD0400PA00X+102801Y+160279X0705Y    R270 S3      
317GND              J1    -P1_2MD0400PA00X+102801Y+161279X0705Y    R270 S3      
317GND              J1    -P1_1MD0400PA00X+102801Y+162279X0705Y0705R270 S3      
327GND              R5606 -2          A01X+176442Y+163788X0198Y0197R090 S1      
327GND              R5607 -2          A01X+177642Y+163788X0198Y0197R090 S1      
317GND              VIA   -    MD0100PA00X+177642Y+164030X0200Y    R180 S0      
317GND              VIA   -    M      A01X+176442Y+164030X0200Y    R180 S2      
017GND              VIA   -    M      A18X+176442Y+164030X0260Y    R180 S2      
017GND                    -    MD0100PA00X+176442Y+164030                       
327GND              R5605 -2          A01X+175642Y+163788X0198Y0197R090 S1      
317GND              VIA   -    MD0100PA00X+175642Y+164030X0200Y    R180 S0      
327GND              C3653 -2          A01X+175322Y+161850X0198Y0197R270 S1      
317GND              VIA   -    M      A01X+175068Y+161850X0200Y    R180 S2      
017GND              VIA   -    M      A18X+175068Y+161850X0260Y    R180 S2      
017GND                    -    MD0100PA00X+175068Y+161850                       
327GND              U329  -4          A01X+177382Y+160436X0240Y0520     S1      
317GND              VIA   -    M      A01X+177713Y+160436X0200Y         S2      
017GND              VIA   -    M      A18X+177713Y+160436X0260Y         S2      
017GND                    -    MD0100PA00X+177713Y+160436                       
327GND              U328  -4          A01X+008369Y+159786X0240Y0520     S1      
327GND              R5592 -2          A01X+008629Y+163138X0198Y0197R090 S1      
317GND              VIA   -    MD0100PA00X+008629Y+163380X0200Y    R180 S0      
327GND              R5593 -2          A01X+007429Y+163138X0198Y0197R090 S1      
317GND              VIA   -    MD0100PA00X+007429Y+163380X0200Y    R180 S0      
327GND              R5595 -2          A01X+006629Y+163138X0198Y0197R090 S1      
317GND              VIA   -    M      A01X+006629Y+163380X0200Y    R180 S2      
017GND              VIA   -    M      A18X+006629Y+163380X0260Y    R180 S2      
017GND                    -    MD0100PA00X+006629Y+163380                       
327GND              C3652 -2          A01X+006309Y+161200X0198Y0197R270 S1      
317GND              VIA   -    M      A01X+006055Y+161200X0200Y    R180 S2      
017GND              VIA   -    M      A18X+006055Y+161200X0260Y    R180 S2      
017GND                    -    MD0100PA00X+006055Y+161200                       
317GND              VIA   -    M      A01X+008700Y+159786X0200Y         S2      
017GND              VIA   -    M      A18X+008700Y+159786X0260Y         S2      
017GND                    -    MD0100PA00X+008700Y+159786                       
327GND              C2707 -1          A01X+082842Y+096227X0198Y0197R270 S1      
327GND              PEX2  -AB1        A01X+105925Y+117618X0180Y         S1      
327GND              PEX2  -AA3 M      A01X+106673Y+117992X0180Y         S1      
327GND              PEX2  -AB3 M      A01X+106673Y+117618X0180Y         S1      
327GND              PEX2  -AB2 M      A01X+106299Y+117618X0180Y         S1      
327GND              PEX2  -AA4 M      A01X+107047Y+117992X0180Y         S1      
327GND              PEX2  -AA5 M      A01X+107421Y+117992X0180Y         S1      
327GND              PEX2  -AC4 M      A01X+107047Y+117244X0180Y         S1      
327GND              PEX2  -AC3 M      A01X+106673Y+117244X0180Y         S1      
327GND              PEX2  -AC5 M      A01X+107421Y+117244X0180Y         S1      
327GND              PEX2  -AA9 M      A01X+108917Y+117992X0180Y         S1      
327GND              PEX2  -AA8 M      A01X+108543Y+117992X0180Y         S1      
327GND              PEX2  -AA6 M      A01X+107795Y+117992X0180Y         S1      
327GND              PEX2  -AB6 M      A01X+107795Y+117618X0180Y         S1      
327GND              PEX2  -AC6 M      A01X+107795Y+117244X0180Y         S1      
327GND              PEX2  -AA7 M      A01X+108169Y+117992X0180Y         S1      
327GND              PEX2  -AB9 M      A01X+108917Y+117618X0180Y         S1      
327GND              PEX2  -AA14M      A01X+110787Y+117992X0180Y         S1      
327GND              PEX2  -AE18       A01X+112283Y+116496X0180Y         S1      
327GND              PEX2  -AD17M      A01X+111909Y+116870X0180Y         S1      
327GND              PEX2  -AC16M      A01X+111535Y+117244X0180Y         S1      
327GND              PEX2  -AB15M      A01X+111161Y+117618X0180Y         S1      
327GND              PEX2  -T10        A01X+109291Y+119862X0180Y         S1      
327GND              PEX2  -T11 M      A01X+109665Y+119862X0180Y         S1      
327GND              PEX2  -R14 M      A01X+110787Y+120236X0180Y         S1      
327GND              PEX2  -R13 M      A01X+110413Y+120236X0180Y         S1      
327GND              PEX2  -R12 M      A01X+110039Y+120236X0180Y         S1      
327GND              PEX2  -R10        A01X+109291Y+120236X0180Y         S1      
327GND              PEX2  -R11 M      A01X+109665Y+120236X0180Y         S1      
327GND              PEX2  -P12 M      A01X+110039Y+120610X0180Y         S1      
327GND              PEX2  -R18 M      A01X+112283Y+120236X0180Y         S1      
327GND              PEX2  -R17 M      A01X+111909Y+120236X0180Y         S1      
327GND              PEX2  -N18 M      A01X+112283Y+120984X0180Y         S1      
327GND              PEX2  -P18 M      A01X+112283Y+120610X0180Y         S1      
327GND              PEX2  -N17 M      A01X+111909Y+120984X0180Y         S1      
327GND              PEX2  -P17 M      A01X+111909Y+120610X0180Y         S1      
327GND              PEX2  -N16 M      A01X+111535Y+120984X0180Y         S1      
327GND              PEX2  -P15 M      A01X+111161Y+120610X0180Y         S1      
327GND              PEX2  -P16 M      A01X+111535Y+120610X0180Y         S1      
327GND              PEX2  -N15 M      A01X+111161Y+120984X0180Y         S1      
327GND              PEX2  -R16 M      A01X+111535Y+120236X0180Y         S1      
327GND              PEX2  -R15 M      A01X+111161Y+120236X0180Y         S1      
327GND              PEX2  -N20 M      A01X+113031Y+120984X0180Y         S1      
327GND              PEX2  -N21 M      A01X+113405Y+120984X0180Y         S1      
327GND              PEX2  -N22 M      A01X+113780Y+120984X0180Y         S1      
327GND              PEX2  -P20 M      A01X+113031Y+120610X0180Y         S1      
327GND              PEX2  -R20 M      A01X+113031Y+120236X0180Y         S1      
327GND              PEX2  -P21 M      A01X+113405Y+120610X0180Y         S1      
327GND              PEX2  -R21 M      A01X+113405Y+120236X0180Y         S1      
327GND              PEX2  -R22 M      A01X+113780Y+120236X0180Y         S1      
327GND              PEX2  -P22 M      A01X+113780Y+120610X0180Y         S1      
327GND              PEX2  -N24        A01X+114528Y+120984X0180Y         S1      
327GND              PEX2  -N23 M      A01X+114154Y+120984X0180Y         S1      
327GND              PEX2  -P23 M      A01X+114154Y+120610X0180Y         S1      
327GND              PEX2  -P24 M      A01X+114528Y+120610X0180Y         S1      
327GND              PEX2  -R24        A01X+114528Y+120236X0180Y         S1      
327GND              PEX2  -R23 M      A01X+114154Y+120236X0180Y         S1      
327GND              PEX2  -P19 M      A01X+112657Y+120610X0180Y         S1      
327GND              PEX2  -N19 M      A01X+112657Y+120984X0180Y         S1      
327GND              PEX2  -R19 M      A01X+112657Y+120236X0180Y         S1      
327GND              PEX2  -M14 M      A01X+110787Y+121358X0180Y         S1      
327GND              PEX2  -P14 M      A01X+110787Y+120610X0180Y         S1      
327GND              PEX2  -N14 M      A01X+110787Y+120984X0180Y         S1      
327GND              PEX2  -P13 M      A01X+110413Y+120610X0180Y         S1      
327GND              PEX2  -L14        A01X+110787Y+121732X0180Y         S1      
327GND              PEX2  -L21        A01X+113405Y+121732X0180Y         S1      
327GND              PEX2  -AA40M      A01X+120512Y+117992X0180Y         S1      
327GND              PEX2  -AB39M      A01X+120138Y+117618X0180Y         S1      
327GND              PEX2  -AC39M      A01X+120138Y+117244X0180Y         S1      
327GND              PEX2  -AD39M      A01X+120138Y+116870X0180Y         S1      
327GND              PEX2  -AE39       A01X+120138Y+116496X0180Y         S1      
327GND              PEX2  -AB40M      A01X+120512Y+117618X0180Y         S1      
327GND              PEX2  -AC41M      A01X+120886Y+117244X0180Y         S1      
327GND              PEX2  -AD44M      A01X+122008Y+116870X0180Y         S1      
327GND              PEX2  -AE42M      A01X+121260Y+116496X0180Y         S1      
327GND              PEX2  -AD43M      A01X+121634Y+116870X0180Y         S1      
327GND              PEX2  -AC42M      A01X+121260Y+117244X0180Y         S1      
327GND              PEX2  -V44 M      A01X+122008Y+119114X0180Y         S1      
327GND              PEX2  -U42 M      A01X+121260Y+119488X0180Y         S1      
327GND              PEX2  -AB43M      A01X+121634Y+117618X0180Y         S1      
327GND              PEX2  -AA41M      A01X+120886Y+117992X0180Y         S1      
327GND              PEX2  -V43 M      A01X+121634Y+119114X0180Y         S1      
327GND              PEX2  -AA42M      A01X+121260Y+117992X0180Y         S1      
327GND              PEX2  -Y43 M      A01X+121634Y+118366X0180Y         S1      
327GND              PEX2  -W42 M      A01X+121260Y+118740X0180Y         S1      
327GND              PEX2  -Y44 M      A01X+122008Y+118366X0180Y         S1      
327GND              PEX2  -AB44M      A01X+122008Y+117618X0180Y         S1      
327GND              PEX2  -W48 M      A01X+123504Y+118740X0180Y         S1      
327GND              PEX2  -V45 M      A01X+122382Y+119114X0180Y         S1      
327GND              PEX2  -V46 M      A01X+122756Y+119114X0180Y         S1      
327GND              PEX2  -W45 M      A01X+122382Y+118740X0180Y         S1      
327GND              PEX2  -V47 M      A01X+123130Y+119114X0180Y         S1      
327GND              PEX2  -Y45 M      A01X+122382Y+118366X0180Y         S1      
327GND              PEX2  -AA45M      A01X+122382Y+117992X0180Y         S1      
327GND              PEX2  -AB45M      A01X+122382Y+117618X0180Y         S1      
327GND              PEX2  -AB46M      A01X+122756Y+117618X0180Y         S1      
327GND              PEX2  -AD47M      A01X+123130Y+116870X0180Y         S1      
327GND              PEX2  -AE45       A01X+122382Y+116496X0180Y         S1      
327GND              PEX2  -AD45M      A01X+122382Y+116870X0180Y         S1      
327GND              PEX2  -AD46M      A01X+122756Y+116870X0180Y         S1      
327GND              PEX2  -AC45M      A01X+122382Y+117244X0180Y         S1      
327GND              PEX2  -AC48M      A01X+123504Y+117244X0180Y         S1      
327GND              PEX2  -AC49M      A01X+123878Y+117244X0180Y         S1      
327GND              PEX2  -AE48M      A01X+123504Y+116496X0180Y         S1      
327GND              PEX2  -AE49M      A01X+123878Y+116496X0180Y         S1      
327GND              PEX2  -AB47M      A01X+123130Y+117618X0180Y         S1      
327GND              PEX2  -AA48M      A01X+123504Y+117992X0180Y         S1      
327GND              PEX2  -Y46 M      A01X+122756Y+118366X0180Y         S1      
327GND              PEX2  -Y47 M      A01X+123130Y+118366X0180Y         S1      
327GND              PEX2  -W49 M      A01X+123878Y+118740X0180Y         S1      
327GND              PEX2  -AA49M      A01X+123878Y+117992X0180Y         S1      
327GND              PEX2  -U45 M      A01X+122382Y+119488X0180Y         S1      
327GND              PEX2  -W41 M      A01X+120886Y+118740X0180Y         S1      
327GND              PEX2  -U41 M      A01X+120886Y+119488X0180Y         S1      
327GND              PEX2  -AE41M      A01X+120886Y+116496X0180Y         S1      
327GND              PEX2  -V40 M      A01X+120512Y+119114X0180Y         S1      
327GND              PEX2  -U40 M      A01X+120512Y+119488X0180Y         S1      
327GND              PEX2  -AE40M      A01X+120512Y+116496X0180Y         S1      
327GND              PEX2  -AC40M      A01X+120512Y+117244X0180Y         S1      
327GND              PEX2  -AD40M      A01X+120512Y+116870X0180Y         S1      
327GND              PEX2  -W40 M      A01X+120512Y+118740X0180Y         S1      
327GND              PEX2  -Y40 M      A01X+120512Y+118366X0180Y         S1      
327GND              PEX2  -P10        A01X+109291Y+120610X0180Y         S1      
327GND              PEX2  -P11 M      A01X+109665Y+120610X0180Y         S1      
327GND              PEX2  -N12 M      A01X+110039Y+120984X0180Y         S1      
327GND              PEX2  -N10        A01X+109291Y+120984X0180Y         S1      
327GND              PEX2  -N11 M      A01X+109665Y+120984X0180Y         S1      
327GND              PEX2  -M10        A01X+109291Y+121358X0180Y         S1      
327GND              PEX2  -M11        A01X+109665Y+121358X0180Y         S1      
327GND              PEX2  -L10        A01X+109291Y+121732X0180Y         S1      
327GND              PEX2  -L11        A01X+109665Y+121732X0180Y         S1      
327GND              PEX2  -M12 M      A01X+110039Y+121358X0180Y         S1      
327GND              PEX2  -N13 M      A01X+110413Y+120984X0180Y         S1      
327GND              PEX2  -W12 M      A01X+110039Y+118740X0180Y         S1      
327GND              PEX2  -W13        A01X+110413Y+118740X0180Y         S1      
327GND              PEX2  -Y13 M      A01X+110413Y+118366X0180Y         S1      
327GND              PEX2  -V13        A01X+110413Y+119114X0180Y         S1      
327GND              PEX2  -U13 M      A01X+110413Y+119488X0180Y         S1      
327GND              PEX2  -V12 M      A01X+110039Y+119114X0180Y         S1      
327GND              PEX2  -V11 M      A01X+109665Y+119114X0180Y         S1      
327GND              PEX2  -V10        A01X+109291Y+119114X0180Y         S1      
327GND              PEX2  -U10        A01X+109291Y+119488X0180Y         S1      
327GND              PEX2  -U11 M      A01X+109665Y+119488X0180Y         S1      
327GND              PEX2  -U12 M      A01X+110039Y+119488X0180Y         S1      
327GND              PEX2  -T13 M      A01X+110413Y+119862X0180Y         S1      
327GND              PEX2  -T12 M      A01X+110039Y+119862X0180Y         S1      
327GND              PEX2  -AE11       A01X+109665Y+116496X0180Y         S1      
327GND              PEX2  -AD11M      A01X+109665Y+116870X0180Y         S1      
327GND              PEX2  -AE12       A01X+110039Y+116496X0180Y         S1      
327GND              PEX2  -AD10M      A01X+109291Y+116870X0180Y         S1      
327GND              PEX2  -AE14       A01X+110787Y+116496X0180Y         S1      
327GND              PEX2  -AC12M      A01X+110039Y+117244X0180Y         S1      
327GND              PEX2  -AD13M      A01X+110413Y+116870X0180Y         S1      
327GND              PEX2  -AC11M      A01X+109665Y+117244X0180Y         S1      
327GND              PEX2  -AB11M      A01X+109665Y+117618X0180Y         S1      
327GND              PEX2  -AB13M      A01X+110413Y+117618X0180Y         S1      
327GND              PEX2  -AA12M      A01X+110039Y+117992X0180Y         S1      
327GND              PEX2  -AD15M      A01X+111161Y+116870X0180Y         S1      
327GND              PEX2  -AE16       A01X+111535Y+116496X0180Y         S1      
327GND              PEX2  -AC14M      A01X+110787Y+117244X0180Y         S1      
327GND              PEX2  -AA11M      A01X+109665Y+117992X0180Y         S1      
327GND              PEX2  -Y11 M      A01X+109665Y+118366X0180Y         S1      
327GND              PEX2  -W11        A01X+109665Y+118740X0180Y         S1      
327GND              PEX2  -W10        A01X+109291Y+118740X0180Y         S1      
327GND              PEX2  -AC9 M      A01X+108917Y+117244X0180Y         S1      
327GND              PEX2  -AD9 M      A01X+108917Y+116870X0180Y         S1      
327GND              PEX2  -AE9        A01X+108917Y+116496X0180Y         S1      
327GND              PEX2  -BH8        A01X+108543Y+107894X0180Y         S1      
327GND              PEX2  -BJ8 M      A01X+108543Y+107520X0180Y         S1      
327GND              PEX2  -BF7 M      A01X+108169Y+108642X0180Y         S1      
327GND              PEX2  -BE8 M      A01X+108543Y+109016X0180Y         S1      
327GND              PEX2  -AW10       A01X+109291Y+111260X0180Y         S1      
327GND              PEX2  -AY13       A01X+110413Y+110886X0180Y         S1      
327GND              PEX2  -AY12       A01X+110039Y+110886X0180Y         S1      
327GND              PEX2  -AY11       A01X+109665Y+110886X0180Y         S1      
327GND              PEX2  -AW11       A01X+109665Y+111260X0180Y         S1      
327GND              PEX2  -AY10       A01X+109291Y+110886X0180Y         S1      
327GND              PEX2  -AU17M      A01X+111909Y+112008X0180Y         S1      
327GND              PEX2  -AT18M      A01X+112283Y+112382X0180Y         S1      
327GND              PEX2  -AY18       A01X+112283Y+110886X0180Y         S1      
327GND              PEX2  -AY16       A01X+111535Y+110886X0180Y         S1      
327GND              PEX2  -AR17M      A01X+111909Y+112756X0180Y         S1      
327GND              PEX2  -AT17M      A01X+111909Y+112382X0180Y         S1      
327GND              PEX2  -AR18M      A01X+112283Y+112756X0180Y         S1      
327GND              PEX2  -AR22M      A01X+113780Y+112756X0180Y         S1      
327GND              PEX2  -AR19M      A01X+112657Y+112756X0180Y         S1      
327GND              PEX2  -AR20M      A01X+113031Y+112756X0180Y         S1      
327GND              PEX2  -AR21M      A01X+113405Y+112756X0180Y         S1      
327GND              PEX2  -AY22       A01X+113780Y+110886X0180Y         S1      
327GND              PEX2  -AY19       A01X+112657Y+110886X0180Y         S1      
327GND              PEX2  -AW20       A01X+113031Y+111260X0180Y         S1      
327GND              PEX2  -AY21       A01X+113405Y+110886X0180Y         S1      
327GND              PEX2  -AY20       A01X+113031Y+110886X0180Y         S1      
327GND              PEX2  -AU22M      A01X+113780Y+112008X0180Y         S1      
327GND              PEX2  -AT21M      A01X+113405Y+112382X0180Y         S1      
327GND              PEX2  -AU21M      A01X+113405Y+112008X0180Y         S1      
327GND              PEX2  -AV20M      A01X+113031Y+111634X0180Y         S1      
327GND              PEX2  -AT19M      A01X+112657Y+112382X0180Y         S1      
327GND              PEX2  -AU20M      A01X+113031Y+112008X0180Y         S1      
327GND              PEX2  -AU19M      A01X+112657Y+112008X0180Y         S1      
327GND              PEX2  -AT20M      A01X+113031Y+112382X0180Y         S1      
327GND              PEX2  -AT22M      A01X+113780Y+112382X0180Y         S1      
327GND              PEX2  -AR23M      A01X+114154Y+112756X0180Y         S1      
327GND              PEX2  -AR24       A01X+114528Y+112756X0180Y         S1      
327GND              PEX2  -AU24M      A01X+114528Y+112008X0180Y         S1      
327GND              PEX2  -AU23M      A01X+114154Y+112008X0180Y         S1      
327GND              PEX2  -AY24       A01X+114528Y+110886X0180Y         S1      
327GND              PEX2  -AY23       A01X+114154Y+110886X0180Y         S1      
327GND              PEX2  -AW24       A01X+114528Y+111260X0180Y         S1      
327GND              PEX2  -AV24M      A01X+114528Y+111634X0180Y         S1      
327GND              PEX2  -AT23M      A01X+114154Y+112382X0180Y         S1      
327GND              PEX2  -AT24M      A01X+114528Y+112382X0180Y         S1      
327GND              PEX2  -AL26M      A01X+115276Y+114252X0180Y         S1      
327GND              PEX2  -AL25       A01X+114902Y+114252X0180Y         S1      
327GND              PEX2  -AR25       A01X+114902Y+112756X0180Y         S1      
327GND              PEX2  -AR26M      A01X+115276Y+112756X0180Y         S1      
327GND              PEX2  -AR27M      A01X+115650Y+112756X0180Y         S1      
327GND              PEX2  -AU25       A01X+114902Y+112008X0180Y         S1      
327GND              PEX2  -AT25M      A01X+114902Y+112382X0180Y         S1      
327GND              PEX2  -AU26M      A01X+115276Y+112008X0180Y         S1      
327GND              PEX2  -AU27M      A01X+115650Y+112008X0180Y         S1      
327GND              PEX2  -AY27       A01X+115650Y+110886X0180Y         S1      
327GND              PEX2  -AJ28M      A01X+116024Y+115000X0180Y         S1      
327GND              PEX2  -AL30M      A01X+116772Y+114252X0180Y         S1      
327GND              PEX2  -AL29M      A01X+116398Y+114252X0180Y         S1      
327GND              PEX2  -AL28M      A01X+116024Y+114252X0180Y         S1      
327GND              PEX2  -AJ30M      A01X+116772Y+115000X0180Y         S1      
327GND              PEX2  -AL31M      A01X+117146Y+114252X0180Y         S1      
327GND              PEX2  -AJ31M      A01X+117146Y+115000X0180Y         S1      
327GND              PEX2  -AR28M      A01X+116024Y+112756X0180Y         S1      
327GND              PEX2  -AR30M      A01X+116772Y+112756X0180Y         S1      
327GND              PEX2  -AR29M      A01X+116398Y+112756X0180Y         S1      
327GND              PEX2  -AT31M      A01X+117146Y+112382X0180Y         S1      
327GND              PEX2  -AU31M      A01X+117146Y+112008X0180Y         S1      
327GND              PEX2  -AU30M      A01X+116772Y+112008X0180Y         S1      
327GND              PEX2  -AT30M      A01X+116772Y+112382X0180Y         S1      
327GND              PEX2  -AT28M      A01X+116024Y+112382X0180Y         S1      
327GND              PEX2  -AT29M      A01X+116398Y+112382X0180Y         S1      
327GND              PEX2  -AU29M      A01X+116398Y+112008X0180Y         S1      
327GND              PEX2  -AU28M      A01X+116024Y+112008X0180Y         S1      
327GND              PEX2  -AR31M      A01X+117146Y+112756X0180Y         S1      
327GND              PEX2  -AU32M      A01X+117520Y+112008X0180Y         S1      
327GND              PEX2  -AL33M      A01X+117894Y+114252X0180Y         S1      
327GND              PEX2  -AK34M      A01X+118268Y+114626X0180Y         S1      
327GND              PEX2  -AL34M      A01X+118268Y+114252X0180Y         S1      
327GND              PEX2  -AL32M      A01X+117520Y+114252X0180Y         S1      
327GND              PEX2  -AP34       A01X+118268Y+113130X0180Y         S1      
327GND              PEX2  -AR32M      A01X+117520Y+112756X0180Y         S1      
327GND              PEX2  -AR33M      A01X+117894Y+112756X0180Y         S1      
327GND              PEX2  -AR35       A01X+118642Y+112756X0180Y         S1      
327GND              PEX2  -AU33M      A01X+117894Y+112008X0180Y         S1      
327GND              PEX2  -AT33M      A01X+117894Y+112382X0180Y         S1      
327GND              PEX2  -AU34M      A01X+118268Y+112008X0180Y         S1      
327GND              PEX2  -AT34M      A01X+118268Y+112382X0180Y         S1      
327GND              PEX2  -AT35M      A01X+118642Y+112382X0180Y         S1      
327GND              PEX2  -AY35       A01X+118642Y+110886X0180Y         S1      
327GND              PEX2  -AU35M      A01X+118642Y+112008X0180Y         S1      
327GND              PEX2  -AJ34M      A01X+118268Y+115000X0180Y         S1      
327GND              PEX2  -AU37M      A01X+119390Y+112008X0180Y         S1      
327GND              PEX2  -AU36M      A01X+119016Y+112008X0180Y         S1      
327GND              PEX2  -AT37M      A01X+119390Y+112382X0180Y         S1      
327GND              PEX2  -AR37M      A01X+119390Y+112756X0180Y         S1      
327GND              PEX2  -AP37M      A01X+119390Y+113130X0180Y         S1      
327GND              PEX2  -AM40       A01X+120512Y+113878X0180Y         S1      
327GND              PEX2  -AY40       A01X+120512Y+110886X0180Y         S1      
327GND              PEX2  -AT40       A01X+120512Y+112382X0180Y         S1      
327GND              PEX2  -AU40       A01X+120512Y+112008X0180Y         S1      
327GND              PEX2  -AY37       A01X+119390Y+110886X0180Y         S1      
327GND              PEX2  -AY36       A01X+119016Y+110886X0180Y         S1      
327GND              PEX2  -AY39       A01X+120138Y+110886X0180Y         S1      
327GND              PEX2  -AY38       A01X+119764Y+110886X0180Y         S1      
327GND              PEX2  -AK36M      A01X+119016Y+114626X0180Y         S1      
327GND              PEX2  -AL36M      A01X+119016Y+114252X0180Y         S1      
327GND              PEX2  -AN37M      A01X+119390Y+113504X0180Y         S1      
327GND              PEX2  -AM37M      A01X+119390Y+113878X0180Y         S1      
327GND              PEX2  -AM36M      A01X+119016Y+113878X0180Y         S1      
327GND              PEX2  -AL37M      A01X+119390Y+114252X0180Y         S1      
327GND              PEX2  -AJ36M      A01X+119016Y+115000X0180Y         S1      
327GND              PEX2  -AJ37M      A01X+119390Y+115000X0180Y         S1      
327GND              PEX2  -AH36M      A01X+119016Y+115374X0180Y         S1      
327GND              PEX2  -AH37       A01X+119390Y+115374X0180Y         S1      
327GND              PEX2  -AH38M      A01X+119764Y+115374X0180Y         S1      
327GND              PEX2  -AL40M      A01X+120512Y+114252X0180Y         S1      
327GND              PEX2  -AJ40M      A01X+120512Y+115000X0180Y         S1      
327GND              PEX2  -AH40M      A01X+120512Y+115374X0180Y         S1      
327GND              PEX2  -AR40       A01X+120512Y+112756X0180Y         S1      
327GND              PEX2  -AP40       A01X+120512Y+113130X0180Y         S1      
327GND              PEX2  -AN40       A01X+120512Y+113504X0180Y         S1      
327GND              PEX2  -AF39       A01X+120138Y+116122X0180Y         S1      
327GND              PEX2  -AG39M      A01X+120138Y+115748X0180Y         S1      
327GND              PEX2  -AG40M      A01X+120512Y+115748X0180Y         S1      
327GND              PEX2  -AF40M      A01X+120512Y+116122X0180Y         S1      
327GND              PEX2  -AF43       A01X+121634Y+116122X0180Y         S1      
327GND              PEX2  -AH43M      A01X+121634Y+115374X0180Y         S1      
327GND              PEX2  -AG42M      A01X+121260Y+115748X0180Y         S1      
327GND              PEX2  -AH44M      A01X+122008Y+115374X0180Y         S1      
327GND              PEX2  -AK44M      A01X+122008Y+114626X0180Y         S1      
327GND              PEX2  -AL42M      A01X+121260Y+114252X0180Y         S1      
327GND              PEX2  -AN41       A01X+120886Y+113504X0180Y         S1      
327GND              PEX2  -AN42       A01X+121260Y+113504X0180Y         S1      
327GND              PEX2  -AM43M      A01X+121634Y+113878X0180Y         S1      
327GND              PEX2  -AM44M      A01X+122008Y+113878X0180Y         S1      
327GND              PEX2  -AL49M      A01X+123878Y+114252X0180Y         S1      
327GND              PEX2  -AJ49M      A01X+123878Y+115000X0180Y         S1      
327GND              PEX2  -AK45M      A01X+122382Y+114626X0180Y         S1      
327GND              PEX2  -AK46M      A01X+122756Y+114626X0180Y         S1      
327GND              PEX2  -AL45M      A01X+122382Y+114252X0180Y         S1      
327GND              PEX2  -AM45       A01X+122382Y+113878X0180Y         S1      
327GND              PEX2  -AN45       A01X+122382Y+113504X0180Y         S1      
327GND              PEX2  -AM46       A01X+122756Y+113878X0180Y         S1      
327GND              PEX2  -AM47M      A01X+123130Y+113878X0180Y         S1      
327GND              PEX2  -AN48M      A01X+123504Y+113504X0180Y         S1      
327GND              PEX2  -AL48M      A01X+123504Y+114252X0180Y         S1      
327GND              PEX2  -AK47M      A01X+123130Y+114626X0180Y         S1      
327GND              PEX2  -AJ48M      A01X+123504Y+115000X0180Y         S1      
327GND              PEX2  -AH47M      A01X+123130Y+115374X0180Y         S1      
327GND              PEX2  -AJ45M      A01X+122382Y+115000X0180Y         S1      
327GND              PEX2  -AG45M      A01X+122382Y+115748X0180Y         S1      
327GND              PEX2  -AF45       A01X+122382Y+116122X0180Y         S1      
327GND              PEX2  -AG48M      A01X+123504Y+115748X0180Y         S1      
327GND              PEX2  -AF47M      A01X+123130Y+116122X0180Y         S1      
327GND              PEX2  -AF46M      A01X+122756Y+116122X0180Y         S1      
327GND              PEX2  -AH45M      A01X+122382Y+115374X0180Y         S1      
327GND              PEX2  -AH46M      A01X+122756Y+115374X0180Y         S1      
327GND              PEX2  -AG49M      A01X+123878Y+115748X0180Y         S1      
327GND              PEX2  -AJ42M      A01X+121260Y+115000X0180Y         S1      
327GND              PEX2  -AK43M      A01X+121634Y+114626X0180Y         S1      
327GND              PEX2  -AJ41M      A01X+120886Y+115000X0180Y         S1      
327GND              PEX2  -AL41M      A01X+120886Y+114252X0180Y         S1      
327GND              PEX2  -AG41M      A01X+120886Y+115748X0180Y         S1      
327GND              PEX2  -AH39M      A01X+120138Y+115374X0180Y         S1      
327GND              PEX2  -AK40M      A01X+120512Y+114626X0180Y         S1      
327GND              PEX2  -AK37M      A01X+119390Y+114626X0180Y         S1      
327GND              PEX2  -AV40       A01X+120512Y+111634X0180Y         S1      
327GND              PEX2  -AG34       A01X+118268Y+115748X0180Y         S1      
327GND              PEX2  -AG35M      A01X+118642Y+115748X0180Y         S1      
327GND              PEX2  -AH35M      A01X+118642Y+115374X0180Y         S1      
327GND              PEX2  -AH34M      A01X+118268Y+115374X0180Y         S1      
327GND              PEX2  -AJ35M      A01X+118642Y+115000X0180Y         S1      
327GND              PEX2  -AF35       A01X+118642Y+116122X0180Y         S1      
327GND              PEX2  -AT32M      A01X+117520Y+112382X0180Y         S1      
327GND              PEX2  -AR34M      A01X+118268Y+112756X0180Y         S1      
327GND              PEX2  -AJ33M      A01X+117894Y+115000X0180Y         S1      
327GND              PEX2  -AJ32M      A01X+117520Y+115000X0180Y         S1      
327GND              PEX2  -AY34       A01X+118268Y+110886X0180Y         S1      
327GND              PEX2  -AY32       A01X+117520Y+110886X0180Y         S1      
327GND              PEX2  -AY33       A01X+117894Y+110886X0180Y         S1      
327GND              PEX2  -AJ29M      A01X+116398Y+115000X0180Y         S1      
327GND              PEX2  -AY31       A01X+117146Y+110886X0180Y         S1      
327GND              PEX2  -AY30       A01X+116772Y+110886X0180Y         S1      
327GND              PEX2  -AY29       A01X+116398Y+110886X0180Y         S1      
327GND              PEX2  -AY28       A01X+116024Y+110886X0180Y         S1      
327GND              PEX2  -AT26M      A01X+115276Y+112382X0180Y         S1      
327GND              PEX2  -AT27M      A01X+115650Y+112382X0180Y         S1      
327GND              PEX2  -AY26       A01X+115276Y+110886X0180Y         S1      
327GND              PEX2  -AY25       A01X+114902Y+110886X0180Y         S1      
327GND              PEX2  -AJ27M      A01X+115650Y+115000X0180Y         S1      
327GND              PEX2  -AJ26M      A01X+115276Y+115000X0180Y         S1      
327GND              PEX2  -AL27M      A01X+115650Y+114252X0180Y         S1      
327GND              PEX2  -AJ25       A01X+114902Y+115000X0180Y         S1      
327GND              PEX2  -AY17       A01X+111909Y+110886X0180Y         S1      
327GND              PEX2  -AY15       A01X+111161Y+110886X0180Y         S1      
327GND              PEX2  -AU18M      A01X+112283Y+112008X0180Y         S1      
327GND              PEX2  -AY14       A01X+110787Y+110886X0180Y         S1      
327GND              PEX2  -AY9        A01X+108917Y+110886X0180Y         S1      
327GND              PEX2  -BC8 M      A01X+108543Y+109764X0180Y         S1      
327GND              PEX2  -BD8 M      A01X+108543Y+109390X0180Y         S1      
327GND              PEX2  -AB34M      A01X+118268Y+117618X0180Y         S1      
327GND              PEX2  -AB36M      A01X+119016Y+117618X0180Y         S1      
327GND              PEX2  -AE37       A01X+119390Y+116496X0180Y         S1      
327GND              PEX2  -AD37M      A01X+119390Y+116870X0180Y         S1      
327GND              PEX2  -V38 M      A01X+119764Y+119114X0180Y         S1      
327GND              PEX2  -V37 M      A01X+119390Y+119114X0180Y         S1      
327GND              PEX2  -V36 M      A01X+119016Y+119114X0180Y         S1      
327GND              PEX2  -Y36 M      A01X+119016Y+118366X0180Y         S1      
327GND              PEX2  -Y37 M      A01X+119390Y+118366X0180Y         S1      
327GND              PEX2  -AB38M      A01X+119764Y+117618X0180Y         S1      
327GND              PEX2  -AB37M      A01X+119390Y+117618X0180Y         S1      
327GND              PEX2  -AA36M      A01X+119016Y+117992X0180Y         S1      
327GND              PEX2  -AA38M      A01X+119764Y+117992X0180Y         S1      
327GND              PEX2  -Y38 M      A01X+119764Y+118366X0180Y         S1      
327GND              PEX2  -W37 M      A01X+119390Y+118740X0180Y         S1      
327GND              PEX2  -W36 M      A01X+119016Y+118740X0180Y         S1      
327GND              PEX2  -T37        A01X+119390Y+119862X0180Y         S1      
327GND              PEX2  -U37 M      A01X+119390Y+119488X0180Y         S1      
327GND              PEX2  -AC37M      A01X+119390Y+117244X0180Y         S1      
327GND              PEX2  -AC34       A01X+118268Y+117244X0180Y         S1      
327GND              PEX2  -AC35M      A01X+118642Y+117244X0180Y         S1      
327GND              PEX2  -AD35M      A01X+118642Y+116870X0180Y         S1      
327GND              PEX2  -AE35       A01X+118642Y+116496X0180Y         S1      
327GND              PEX2  -W26 M      A01X+115276Y+118740X0180Y         S1      
327GND              PEX2  -W25        A01X+114902Y+118740X0180Y         S1      
327GND              PEX2  -N27 M      A01X+115650Y+120984X0180Y         S1      
327GND              PEX2  -N25        A01X+114902Y+120984X0180Y         S1      
327GND              PEX2  -N26 M      A01X+115276Y+120984X0180Y         S1      
327GND              PEX2  -R25        A01X+114902Y+120236X0180Y         S1      
327GND              PEX2  -R26 M      A01X+115276Y+120236X0180Y         S1      
327GND              PEX2  -U26 M      A01X+115276Y+119488X0180Y         S1      
327GND              PEX2  -U25        A01X+114902Y+119488X0180Y         S1      
327GND              PEX2  -R29 M      A01X+116398Y+120236X0180Y         S1      
327GND              PEX2  -R30 M      A01X+116772Y+120236X0180Y         S1      
327GND              PEX2  -P31 M      A01X+117146Y+120610X0180Y         S1      
327GND              PEX2  -N30 M      A01X+116772Y+120984X0180Y         S1      
327GND              PEX2  -N31 M      A01X+117146Y+120984X0180Y         S1      
327GND              PEX2  -N29 M      A01X+116398Y+120984X0180Y         S1      
327GND              PEX2  -P29 M      A01X+116398Y+120610X0180Y         S1      
327GND              PEX2  -P28 M      A01X+116024Y+120610X0180Y         S1      
327GND              PEX2  -N28 M      A01X+116024Y+120984X0180Y         S1      
327GND              PEX2  -P30 M      A01X+116772Y+120610X0180Y         S1      
327GND              PEX2  -R28 M      A01X+116024Y+120236X0180Y         S1      
327GND              PEX2  -U30 M      A01X+116772Y+119488X0180Y         S1      
327GND              PEX2  -R31        A01X+117146Y+120236X0180Y         S1      
327GND              PEX2  -U31 M      A01X+117146Y+119488X0180Y         S1      
327GND              PEX2  -W30 M      A01X+116772Y+118740X0180Y         S1      
327GND              PEX2  -W31 M      A01X+117146Y+118740X0180Y         S1      
327GND              PEX2  -V34 M      A01X+118268Y+119114X0180Y         S1      
327GND              PEX2  -U35 M      A01X+118642Y+119488X0180Y         S1      
327GND              PEX2  -U32 M      A01X+117520Y+119488X0180Y         S1      
327GND              PEX2  -U34 M      A01X+118268Y+119488X0180Y         S1      
327GND              PEX2  -N36 M      A01X+119016Y+120984X0180Y         S1      
327GND              PEX2  -N37        A01X+119390Y+120984X0180Y         S1      
327GND              PEX2  -P37        A01X+119390Y+120610X0180Y         S1      
327GND              PEX2  -R37        A01X+119390Y+120236X0180Y         S1      
327GND              PEX2  -R32 M      A01X+117520Y+120236X0180Y         S1      
327GND              PEX2  -T34 M      A01X+118268Y+119862X0180Y         S1      
327GND              PEX2  -R33 M      A01X+117894Y+120236X0180Y         S1      
327GND              PEX2  -P34 M      A01X+118268Y+120610X0180Y         S1      
327GND              PEX2  -P33 M      A01X+117894Y+120610X0180Y         S1      
327GND              PEX2  -R34 M      A01X+118268Y+120236X0180Y         S1      
327GND              PEX2  -R35 M      A01X+118642Y+120236X0180Y         S1      
327GND              PEX2  -P35 M      A01X+118642Y+120610X0180Y         S1      
327GND              PEX2  -N32 M      A01X+117520Y+120984X0180Y         S1      
327GND              PEX2  -P32 M      A01X+117520Y+120610X0180Y         S1      
327GND              PEX2  -N33 M      A01X+117894Y+120984X0180Y         S1      
327GND              PEX2  -N34 M      A01X+118268Y+120984X0180Y         S1      
327GND              PEX2  -N35 M      A01X+118642Y+120984X0180Y         S1      
327GND              PEX2  -U33 M      A01X+117894Y+119488X0180Y         S1      
327GND              PEX2  -W34 M      A01X+118268Y+118740X0180Y         S1      
327GND              PEX2  -W33 M      A01X+117894Y+118740X0180Y         S1      
327GND              PEX2  -W32 M      A01X+117520Y+118740X0180Y         S1      
327GND              PEX2  -W29 M      A01X+116398Y+118740X0180Y         S1      
327GND              PEX2  -W28 M      A01X+116024Y+118740X0180Y         S1      
327GND              PEX2  -U29 M      A01X+116398Y+119488X0180Y         S1      
327GND              PEX2  -U28 M      A01X+116024Y+119488X0180Y         S1      
327GND              PEX2  -U27 M      A01X+115650Y+119488X0180Y         S1      
327GND              PEX2  -R27 M      A01X+115650Y+120236X0180Y         S1      
327GND              PEX2  -P27 M      A01X+115650Y+120610X0180Y         S1      
327GND              PEX2  -P26 M      A01X+115276Y+120610X0180Y         S1      
327GND              PEX2  -P25 M      A01X+114902Y+120610X0180Y         S1      
327GND              PEX2  -W27 M      A01X+115650Y+118740X0180Y         S1      
327GND              PEX2  -AA19M      A01X+112657Y+117992X0180Y         S1      
327GND              PEX2  -AA20M      A01X+113031Y+117992X0180Y         S1      
327GND              PEX2  -AA21M      A01X+113405Y+117992X0180Y         S1      
327GND              PEX2  -AA22M      A01X+113780Y+117992X0180Y         S1      
327GND              PEX2  -AA24       A01X+114528Y+117992X0180Y         S1      
327GND              PEX2  -AA23M      A01X+114154Y+117992X0180Y         S1      
327GND              PEX2  -AA18M      A01X+112283Y+117992X0180Y         S1      
327GND              PEX2  -AA17M      A01X+111909Y+117992X0180Y         S1      
327GND              PEX2  -AA16M      A01X+111535Y+117992X0180Y         S1      
327GND              PEX2  -Y15 M      A01X+111161Y+118366X0180Y         S1      
327GND              PEX2  -W14 M      A01X+110787Y+118740X0180Y         S1      
327GND              PEX2  -W24        A01X+114528Y+118740X0180Y         S1      
327GND              PEX2  -W23 M      A01X+114154Y+118740X0180Y         S1      
327GND              PEX2  -W19 M      A01X+112657Y+118740X0180Y         S1      
327GND              PEX2  -W20 M      A01X+113031Y+118740X0180Y         S1      
327GND              PEX2  -W21 M      A01X+113405Y+118740X0180Y         S1      
327GND              PEX2  -W22 M      A01X+113780Y+118740X0180Y         S1      
327GND              PEX2  -W18 M      A01X+112283Y+118740X0180Y         S1      
327GND              PEX2  -W17 M      A01X+111909Y+118740X0180Y         S1      
327GND              PEX2  -W16 M      A01X+111535Y+118740X0180Y         S1      
327GND              PEX2  -W15 M      A01X+111161Y+118740X0180Y         S1      
327GND              PEX2  -U22 M      A01X+113780Y+119488X0180Y         S1      
327GND              PEX2  -U19 M      A01X+112657Y+119488X0180Y         S1      
327GND              PEX2  -U20 M      A01X+113031Y+119488X0180Y         S1      
327GND              PEX2  -U21 M      A01X+113405Y+119488X0180Y         S1      
327GND              PEX2  -U23 M      A01X+114154Y+119488X0180Y         S1      
327GND              PEX2  -U24        A01X+114528Y+119488X0180Y         S1      
327GND              PEX2  -T15 M      A01X+111161Y+119862X0180Y         S1      
327GND              PEX2  -U15 M      A01X+111161Y+119488X0180Y         S1      
327GND              PEX2  -V15 M      A01X+111161Y+119114X0180Y         S1      
327GND              PEX2  -U18 M      A01X+112283Y+119488X0180Y         S1      
327GND              PEX2  -U17 M      A01X+111909Y+119488X0180Y         S1      
327GND              PEX2  -U16 M      A01X+111535Y+119488X0180Y         S1      
327GND              PEX2  -AL12       A01X+110039Y+114252X0180Y         S1      
327GND              PEX2  -AL13       A01X+110413Y+114252X0180Y         S1      
327GND              PEX2  -AL11       A01X+109665Y+114252X0180Y         S1      
327GND              PEX2  -AG11       A01X+109665Y+115748X0180Y         S1      
327GND              PEX2  -AJ11       A01X+109665Y+115000X0180Y         S1      
327GND              PEX2  -AL10       A01X+109291Y+114252X0180Y         S1      
327GND              PEX2  -AL7        A01X+108169Y+114252X0180Y         S1      
327GND              PEX2  -AL8        A01X+108543Y+114252X0180Y         S1      
327GND              PEX2  -AL9        A01X+108917Y+114252X0180Y         S1      
327GND              PEX2  -AY6        A01X+107795Y+110886X0180Y         S1      
327GND              PEX2  -BC6        A01X+107795Y+109764X0180Y         S1      
327GND              PEX2  -AV6        A01X+107795Y+111634X0180Y         S1      
327GND              PEX2  -AP6        A01X+107795Y+113130X0180Y         S1      
327GND              PEX2  -AT6        A01X+107795Y+112382X0180Y         S1      
327GND              PEX2  -AL6        A01X+107795Y+114252X0180Y         S1      
327GND              PEX2  -AL2        A01X+106299Y+114252X0180Y         S1      
327GND              PEX2  -AL3        A01X+106673Y+114252X0180Y         S1      
327GND              PEX2  -AL4        A01X+107047Y+114252X0180Y         S1      
327GND              PEX2  -AL5        A01X+107421Y+114252X0180Y         S1      
327GND              PEX2  -AG6        A01X+107795Y+115748X0180Y         S1      
327GND              PEX2  -AH6        A01X+107795Y+115374X0180Y         S1      
327GND              PEX2  -AJ6        A01X+107795Y+115000X0180Y         S1      
327GND              PEX2  -AK6        A01X+107795Y+114626X0180Y         S1      
327GND              PEX2  -AF6        A01X+107795Y+116122X0180Y         S1      
327GND              PEX2  -BJ6        A01X+107795Y+107520X0180Y         S1      
327GND              PEX2  -BD6        A01X+107795Y+109390X0180Y         S1      
327GND              PEX2  -BE6        A01X+107795Y+109016X0180Y         S1      
327GND              PEX2  -BH6        A01X+107795Y+107894X0180Y         S1      
327GND              PEX2  -BD2        A01X+106299Y+109390X0180Y         S1      
327GND              PEX2  -BD4        A01X+107047Y+109390X0180Y         S1      
327GND              PEX2  -AL1        A01X+105925Y+114252X0180Y         S1      
327GND              PEX2  -BD1        A01X+105925Y+109390X0180Y         S1      
327GND              R3488 -2          A18X+097441Y+089750X0198Y0197R180 S2      
327GND              PC243 -2          A01X+094712Y+125745X0198Y0197R180 S1      
327GND              R5526 -1          A18X+091372Y+080332X0198Y0197R270 S2      
327GND              PC223 -2          A01X+088314Y+125745X0198Y0197R180 S1      
327GND              C2629 -1          A01X+088404Y+074716X0198Y0197R090 S1      
327GND              U362  -3          A01X+087073Y+072206X0400Y0150     S1      
327GND              U351  -2          A01X+084828Y+073505X0140Y0440R180 S1      
327GND              U352  -2          A01X+083228Y+073505X0140Y0440R180 S1      
327GND              PEX1  -AC5 M      A01X+061713Y+117244X0180Y         S1      
327GND              PEX1  -AC4 M      A01X+061339Y+117244X0180Y         S1      
327GND              PEX1  -AC3 M      A01X+060965Y+117244X0180Y         S1      
327GND              PEX1  -AA3        A01X+060965Y+117992X0180Y         S1      
327GND              PEX1  -AB2 M      A01X+060590Y+117618X0180Y         S1      
327GND              PEX1  -AB3 M      A01X+060965Y+117618X0180Y         S1      
327GND              PEX1  -AA5        A01X+061713Y+117992X0180Y         S1      
327GND              PEX1  -AA6        A01X+062087Y+117992X0180Y         S1      
327GND              PEX1  -Y7         A01X+062461Y+118366X0180Y         S1      
327GND              PEX1  -AA8 M      A01X+062835Y+117992X0180Y         S1      
327GND              PEX1  -AB9 M      A01X+063209Y+117618X0180Y         S1      
327GND              PEX1  -AA9 M      A01X+063209Y+117992X0180Y         S1      
327GND              PEX1  -Y8         A01X+062835Y+118366X0180Y         S1      
327GND              PEX1  -W9         A01X+063209Y+118740X0180Y         S1      
327GND              PEX1  -Y9  M      A01X+063209Y+118366X0180Y         S1      
327GND              PEX1  -W10        A01X+063583Y+118740X0180Y         S1      
327GND              PEX1  -Y10 M      A01X+063583Y+118366X0180Y         S1      
327GND              PEX1  -AC9 M      A01X+063209Y+117244X0180Y         S1      
327GND              PEX1  -AD9 M      A01X+063209Y+116870X0180Y         S1      
327GND              PEX1  -AE9        A01X+063209Y+116496X0180Y         S1      
327GND              PEX1  -AD10M      A01X+063583Y+116870X0180Y         S1      
327GND              PEX1  -N10        A01X+063583Y+120984X0180Y         S1      
327GND              PEX1  -P10        A01X+063583Y+120610X0180Y         S1      
327GND              PEX1  -L10        A01X+063583Y+121732X0180Y         S1      
327GND              PEX1  -M10        A01X+063583Y+121358X0180Y         S1      
327GND              PEX1  -R10        A01X+063583Y+120236X0180Y         S1      
327GND              PEX1  -T10        A01X+063583Y+119862X0180Y         S1      
327GND              PEX1  -U10        A01X+063583Y+119488X0180Y         S1      
327GND              PEX1  -V10        A01X+063583Y+119114X0180Y         S1      
327GND              PEX1  -AE16       A01X+065827Y+116496X0180Y         S1      
327GND              PEX1  -AD15M      A01X+065453Y+116870X0180Y         S1      
327GND              PEX1  -AC14M      A01X+065079Y+117244X0180Y         S1      
327GND              PEX1  -AE12       A01X+064331Y+116496X0180Y         S1      
327GND              PEX1  -AD13M      A01X+064705Y+116870X0180Y         S1      
327GND              PEX1  -AC12       A01X+064331Y+117244X0180Y         S1      
327GND              PEX1  -AC11M      A01X+063957Y+117244X0180Y         S1      
327GND              PEX1  -AB13M      A01X+064705Y+117618X0180Y         S1      
327GND              PEX1  -AA12       A01X+064331Y+117992X0180Y         S1      
327GND              PEX1  -AA11M      A01X+063957Y+117992X0180Y         S1      
327GND              PEX1  -Y11 M      A01X+063957Y+118366X0180Y         S1      
327GND              PEX1  -W12 M      A01X+064331Y+118740X0180Y         S1      
327GND              PEX1  -W11 M      A01X+063957Y+118740X0180Y         S1      
327GND              PEX1  -T11 M      A01X+063957Y+119862X0180Y         S1      
327GND              PEX1  -T13 M      A01X+064705Y+119862X0180Y         S1      
327GND              PEX1  -U11 M      A01X+063957Y+119488X0180Y         S1      
327GND              PEX1  -V11 M      A01X+063957Y+119114X0180Y         S1      
327GND              PEX1  -U12 M      A01X+064331Y+119488X0180Y         S1      
327GND              PEX1  -U13 M      A01X+064705Y+119488X0180Y         S1      
327GND              PEX1  -V12 M      A01X+064331Y+119114X0180Y         S1      
327GND              PEX1  -V13        A01X+064705Y+119114X0180Y         S1      
327GND              PEX1  -T12 M      A01X+064331Y+119862X0180Y         S1      
327GND              PEX1  -R11 M      A01X+063957Y+120236X0180Y         S1      
327GND              PEX1  -R12 M      A01X+064331Y+120236X0180Y         S1      
327GND              PEX1  -R13 M      A01X+064705Y+120236X0180Y         S1      
327GND              PEX1  -L21        A01X+067697Y+121732X0180Y         S1      
327GND              PEX1  -Y40 M      A01X+074803Y+118366X0180Y         S1      
327GND              PEX1  -W40 M      A01X+074803Y+118740X0180Y         S1      
327GND              PEX1  -AE39       A01X+074429Y+116496X0180Y         S1      
327GND              PEX1  -AE40M      A01X+074803Y+116496X0180Y         S1      
327GND              PEX1  -AD40M      A01X+074803Y+116870X0180Y         S1      
327GND              PEX1  -V40 M      A01X+074803Y+119114X0180Y         S1      
327GND              PEX1  -U41 M      A01X+075177Y+119488X0180Y         S1      
327GND              PEX1  -U42 M      A01X+075551Y+119488X0180Y         S1      
327GND              PEX1  -W41        A01X+075177Y+118740X0180Y         S1      
327GND              PEX1  -V43 M      A01X+075925Y+119114X0180Y         S1      
327GND              PEX1  -Y43 M      A01X+075925Y+118366X0180Y         S1      
327GND              PEX1  -AA41M      A01X+075177Y+117992X0180Y         S1      
327GND              PEX1  -AA42M      A01X+075551Y+117992X0180Y         S1      
327GND              PEX1  -AB44M      A01X+076299Y+117618X0180Y         S1      
327GND              PEX1  -AB45M      A01X+076673Y+117618X0180Y         S1      
327GND              PEX1  -AA45M      A01X+076673Y+117992X0180Y         S1      
327GND              PEX1  -Y45 M      A01X+076673Y+118366X0180Y         S1      
327GND              PEX1  -Y44 M      A01X+076299Y+118366X0180Y         S1      
327GND              PEX1  -W45        A01X+076673Y+118740X0180Y         S1      
327GND              PEX1  -AB43M      A01X+075925Y+117618X0180Y         S1      
327GND              PEX1  -AE41M      A01X+075177Y+116496X0180Y         S1      
327GND              PEX1  -AC42M      A01X+075551Y+117244X0180Y         S1      
327GND              PEX1  -AC41M      A01X+075177Y+117244X0180Y         S1      
327GND              PEX1  -AE42M      A01X+075551Y+116496X0180Y         S1      
327GND              PEX1  -AD43M      A01X+075925Y+116870X0180Y         S1      
327GND              PEX1  -AD44M      A01X+076299Y+116870X0180Y         S1      
327GND              PEX1  -AD45M      A01X+076673Y+116870X0180Y         S1      
327GND              PEX1  -AE45       A01X+076673Y+116496X0180Y         S1      
327GND              PEX1  -AC45M      A01X+076673Y+117244X0180Y         S1      
327GND              PEX1  -U48 M      A01X+077795Y+119488X0180Y         S1      
327GND              PEX1  -Y46 M      A01X+077047Y+118366X0180Y         S1      
327GND              PEX1  -V46 M      A01X+077047Y+119114X0180Y         S1      
327GND              PEX1  -V47 M      A01X+077421Y+119114X0180Y         S1      
327GND              PEX1  -W48 M      A01X+077795Y+118740X0180Y         S1      
327GND              PEX1  -Y47 M      A01X+077421Y+118366X0180Y         S1      
327GND              PEX1  -AB46M      A01X+077047Y+117618X0180Y         S1      
327GND              PEX1  -AB47M      A01X+077421Y+117618X0180Y         S1      
327GND              PEX1  -AD47M      A01X+077421Y+116870X0180Y         S1      
327GND              PEX1  -AE48M      A01X+077795Y+116496X0180Y         S1      
327GND              PEX1  -AC48M      A01X+077795Y+117244X0180Y         S1      
327GND              PEX1  -AD46M      A01X+077047Y+116870X0180Y         S1      
327GND              PEX1  -AE49M      A01X+078169Y+116496X0180Y         S1      
327GND              PEX1  -AC49M      A01X+078169Y+117244X0180Y         S1      
327GND              PEX1  -AA48M      A01X+077795Y+117992X0180Y         S1      
327GND              PEX1  -W49 M      A01X+078169Y+118740X0180Y         S1      
327GND              PEX1  -AA49M      A01X+078169Y+117992X0180Y         S1      
327GND              PEX1  -U49 M      A01X+078169Y+119488X0180Y         S1      
327GND              PEX1  -W42 M      A01X+075551Y+118740X0180Y         S1      
327GND              PEX1  -V45 M      A01X+076673Y+119114X0180Y         S1      
327GND              PEX1  -V44 M      A01X+076299Y+119114X0180Y         S1      
327GND              PEX1  -U45 M      A01X+076673Y+119488X0180Y         S1      
327GND              PEX1  -U40 M      A01X+074803Y+119488X0180Y         S1      
327GND              PEX1  -AD39M      A01X+074429Y+116870X0180Y         S1      
327GND              PEX1  -AC39M      A01X+074429Y+117244X0180Y         S1      
327GND              PEX1  -AC40M      A01X+074803Y+117244X0180Y         S1      
327GND              PEX1  -AB39M      A01X+074429Y+117618X0180Y         S1      
327GND              PEX1  -AA40M      A01X+074803Y+117992X0180Y         S1      
327GND              PEX1  -AB40M      A01X+074803Y+117618X0180Y         S1      
327GND              PEX1  -N17 M      A01X+066201Y+120984X0180Y         S1      
327GND              PEX1  -R16 M      A01X+065827Y+120236X0180Y         S1      
327GND              PEX1  -R15 M      A01X+065453Y+120236X0180Y         S1      
327GND              PEX1  -R18 M      A01X+066575Y+120236X0180Y         S1      
327GND              PEX1  -R19 M      A01X+066949Y+120236X0180Y         S1      
327GND              PEX1  -N15 M      A01X+065453Y+120984X0180Y         S1      
327GND              PEX1  -P16 M      A01X+065827Y+120610X0180Y         S1      
327GND              PEX1  -R17 M      A01X+066201Y+120236X0180Y         S1      
327GND              PEX1  -P17 M      A01X+066201Y+120610X0180Y         S1      
327GND              PEX1  -P18 M      A01X+066575Y+120610X0180Y         S1      
327GND              PEX1  -N19 M      A01X+066949Y+120984X0180Y         S1      
327GND              PEX1  -P19 M      A01X+066949Y+120610X0180Y         S1      
327GND              PEX1  -R22 M      A01X+068071Y+120236X0180Y         S1      
327GND              PEX1  -P20 M      A01X+067323Y+120610X0180Y         S1      
327GND              PEX1  -N21 M      A01X+067697Y+120984X0180Y         S1      
327GND              PEX1  -N22 M      A01X+068071Y+120984X0180Y         S1      
327GND              PEX1  -P21 M      A01X+067697Y+120610X0180Y         S1      
327GND              PEX1  -P22 M      A01X+068071Y+120610X0180Y         S1      
327GND              PEX1  -P23 M      A01X+068445Y+120610X0180Y         S1      
327GND              PEX1  -R24        A01X+068819Y+120236X0180Y         S1      
327GND              PEX1  -P24 M      A01X+068819Y+120610X0180Y         S1      
327GND              PEX1  -N24        A01X+068819Y+120984X0180Y         S1      
327GND              PEX1  -N23 M      A01X+068445Y+120984X0180Y         S1      
327GND              PEX1  -N20 M      A01X+067323Y+120984X0180Y         S1      
327GND              PEX1  -R23 M      A01X+068445Y+120236X0180Y         S1      
327GND              PEX1  -R21 M      A01X+067697Y+120236X0180Y         S1      
327GND              PEX1  -R20 M      A01X+067323Y+120236X0180Y         S1      
327GND              PEX1  -P15 M      A01X+065453Y+120610X0180Y         S1      
327GND              PEX1  -N18 M      A01X+066575Y+120984X0180Y         S1      
327GND              PEX1  -N16 M      A01X+065827Y+120984X0180Y         S1      
327GND              PEX1  -P11 M      A01X+063957Y+120610X0180Y         S1      
327GND              PEX1  -P12 M      A01X+064331Y+120610X0180Y         S1      
327GND              PEX1  -P13 M      A01X+064705Y+120610X0180Y         S1      
327GND              PEX1  -N11 M      A01X+063957Y+120984X0180Y         S1      
327GND              PEX1  -N12 M      A01X+064331Y+120984X0180Y         S1      
327GND              PEX1  -N14 M      A01X+065079Y+120984X0180Y         S1      
327GND              PEX1  -M14 M      A01X+065079Y+121358X0180Y         S1      
327GND              PEX1  -N13 M      A01X+064705Y+120984X0180Y         S1      
327GND              PEX1  -M12 M      A01X+064331Y+121358X0180Y         S1      
327GND              PEX1  -M11        A01X+063957Y+121358X0180Y         S1      
327GND              PEX1  -P14 M      A01X+065079Y+120610X0180Y         S1      
327GND              PEX1  -L11        A01X+063957Y+121732X0180Y         S1      
327GND              PEX1  -R14 M      A01X+065079Y+120236X0180Y         S1      
327GND              PEX1  -L14        A01X+065079Y+121732X0180Y         S1      
327GND              PEX1  -W13        A01X+064705Y+118740X0180Y         S1      
327GND              PEX1  -Y13 M      A01X+064705Y+118366X0180Y         S1      
327GND              PEX1  -AB11M      A01X+063957Y+117618X0180Y         S1      
327GND              PEX1  -AA14M      A01X+065079Y+117992X0180Y         S1      
327GND              PEX1  -AE18       A01X+066575Y+116496X0180Y         S1      
327GND              PEX1  -AD17M      A01X+066201Y+116870X0180Y         S1      
327GND              PEX1  -AC16M      A01X+065827Y+117244X0180Y         S1      
327GND              PEX1  -AB15M      A01X+065453Y+117618X0180Y         S1      
327GND              PEX1  -AD11M      A01X+063957Y+116870X0180Y         S1      
327GND              PEX1  -AE11       A01X+063957Y+116496X0180Y         S1      
327GND              PEX1  -AE14       A01X+065079Y+116496X0180Y         S1      
327GND              PEX1  -AB6 M      A01X+062087Y+117618X0180Y         S1      
327GND              PEX1  -AC6 M      A01X+062087Y+117244X0180Y         S1      
327GND              PEX1  -AB1        A01X+060216Y+117618X0180Y         S1      
327GND              PEX1  -AY10       A01X+063583Y+110886X0180Y         S1      
327GND              PEX1  -BA9 M      A01X+063209Y+110512X0180Y         S1      
327GND              PEX1  -AY9        A01X+063209Y+110886X0180Y         S1      
327GND              PEX1  -BD8 M      A01X+062835Y+109390X0180Y         S1      
327GND              PEX1  -BE8 M      A01X+062835Y+109016X0180Y         S1      
327GND              PEX1  -BF7 M      A01X+062461Y+108642X0180Y         S1      
327GND              PEX1  -BA15       A01X+065453Y+110512X0180Y         S1      
327GND              PEX1  -AU17M      A01X+066201Y+112008X0180Y         S1      
327GND              PEX1  -AU18M      A01X+066575Y+112008X0180Y         S1      
327GND              PEX1  -AR19M      A01X+066949Y+112756X0180Y         S1      
327GND              PEX1  -AT19M      A01X+066949Y+112382X0180Y         S1      
327GND              PEX1  -AR17M      A01X+066201Y+112756X0180Y         S1      
327GND              PEX1  -AT17M      A01X+066201Y+112382X0180Y         S1      
327GND              PEX1  -AR18M      A01X+066575Y+112756X0180Y         S1      
327GND              PEX1  -AT18M      A01X+066575Y+112382X0180Y         S1      
327GND              PEX1  -BA23       A01X+068445Y+110512X0180Y         S1      
327GND              PEX1  -BA21       A01X+067697Y+110512X0180Y         S1      
327GND              PEX1  -AR21M      A01X+067697Y+112756X0180Y         S1      
327GND              PEX1  -AR23M      A01X+068445Y+112756X0180Y         S1      
327GND              PEX1  -AR20M      A01X+067323Y+112756X0180Y         S1      
327GND              PEX1  -AR22M      A01X+068071Y+112756X0180Y         S1      
327GND              PEX1  -AT20M      A01X+067323Y+112382X0180Y         S1      
327GND              PEX1  -AT21M      A01X+067697Y+112382X0180Y         S1      
327GND              PEX1  -AU21M      A01X+067697Y+112008X0180Y         S1      
327GND              PEX1  -AV20M      A01X+067323Y+111634X0180Y         S1      
327GND              PEX1  -AU20M      A01X+067323Y+112008X0180Y         S1      
327GND              PEX1  -AU23M      A01X+068445Y+112008X0180Y         S1      
327GND              PEX1  -AT22M      A01X+068071Y+112382X0180Y         S1      
327GND              PEX1  -AT23M      A01X+068445Y+112382X0180Y         S1      
327GND              PEX1  -AY23       A01X+068445Y+110886X0180Y         S1      
327GND              PEX1  -AR24       A01X+068819Y+112756X0180Y         S1      
327GND              PEX1  -AR27M      A01X+069941Y+112756X0180Y         S1      
327GND              PEX1  -AR25       A01X+069193Y+112756X0180Y         S1      
327GND              PEX1  -AR26M      A01X+069567Y+112756X0180Y         S1      
327GND              PEX1  -AV24M      A01X+068819Y+111634X0180Y         S1      
327GND              PEX1  -AU24M      A01X+068819Y+112008X0180Y         S1      
327GND              PEX1  -AT24M      A01X+068819Y+112382X0180Y         S1      
327GND              PEX1  -AU25       A01X+069193Y+112008X0180Y         S1      
327GND              PEX1  -AT25M      A01X+069193Y+112382X0180Y         S1      
327GND              PEX1  -AT26M      A01X+069567Y+112382X0180Y         S1      
327GND              PEX1  -AU27M      A01X+069941Y+112008X0180Y         S1      
327GND              PEX1  -AT27M      A01X+069941Y+112382X0180Y         S1      
327GND              PEX1  -AY26       A01X+069567Y+110886X0180Y         S1      
327GND              PEX1  -BA27       A01X+069941Y+110512X0180Y         S1      
327GND              PEX1  -AY27       A01X+069941Y+110886X0180Y         S1      
327GND              PEX1  -BA25       A01X+069193Y+110512X0180Y         S1      
327GND              PEX1  -AY24       A01X+068819Y+110886X0180Y         S1      
327GND              PEX1  -AY25       A01X+069193Y+110886X0180Y         S1      
327GND              PEX1  -AJ25       A01X+069193Y+115000X0180Y         S1      
327GND              PEX1  -AU29M      A01X+070689Y+112008X0180Y         S1      
327GND              PEX1  -AU28M      A01X+070315Y+112008X0180Y         S1      
327GND              PEX1  -AT28M      A01X+070315Y+112382X0180Y         S1      
327GND              PEX1  -AY32       A01X+071811Y+110886X0180Y         S1      
327GND              PEX1  -AU32M      A01X+071811Y+112008X0180Y         S1      
327GND              PEX1  -AT31M      A01X+071437Y+112382X0180Y         S1      
327GND              PEX1  -AT30M      A01X+071063Y+112382X0180Y         S1      
327GND              PEX1  -AL30M      A01X+071063Y+114252X0180Y         S1      
327GND              PEX1  -AJ28M      A01X+070315Y+115000X0180Y         S1      
327GND              PEX1  -AJ30M      A01X+071063Y+115000X0180Y         S1      
327GND              PEX1  -AL32M      A01X+071811Y+114252X0180Y         S1      
327GND              PEX1  -AJ32M      A01X+071811Y+115000X0180Y         S1      
327GND              PEX1  -AR30M      A01X+071063Y+112756X0180Y         S1      
327GND              PEX1  -AR31M      A01X+071437Y+112756X0180Y         S1      
327GND              PEX1  -AT32M      A01X+071811Y+112382X0180Y         S1      
327GND              PEX1  -AR32M      A01X+071811Y+112756X0180Y         S1      
327GND              PEX1  -AL33M      A01X+072185Y+114252X0180Y         S1      
327GND              PEX1  -AL34M      A01X+072559Y+114252X0180Y         S1      
327GND              PEX1  -AK34M      A01X+072559Y+114626X0180Y         S1      
327GND              PEX1  -AH34M      A01X+072559Y+115374X0180Y         S1      
327GND              PEX1  -AG34       A01X+072559Y+115748X0180Y         S1      
327GND              PEX1  -AH35M      A01X+072933Y+115374X0180Y         S1      
327GND              PEX1  -AL36M      A01X+073307Y+114252X0180Y         S1      
327GND              PEX1  -AH36M      A01X+073307Y+115374X0180Y         S1      
327GND              PEX1  -AP34       A01X+072559Y+113130X0180Y         S1      
327GND              PEX1  -AR35       A01X+072933Y+112756X0180Y         S1      
327GND              PEX1  -AR33M      A01X+072185Y+112756X0180Y         S1      
327GND              PEX1  -AR34M      A01X+072559Y+112756X0180Y         S1      
327GND              PEX1  -AM36M      A01X+073307Y+113878X0180Y         S1      
327GND              PEX1  -AT35M      A01X+072933Y+112382X0180Y         S1      
327GND              PEX1  -AU35M      A01X+072933Y+112008X0180Y         S1      
327GND              PEX1  -AU34M      A01X+072559Y+112008X0180Y         S1      
327GND              PEX1  -AT33M      A01X+072185Y+112382X0180Y         S1      
327GND              PEX1  -AU33M      A01X+072185Y+112008X0180Y         S1      
327GND              PEX1  -AT34M      A01X+072559Y+112382X0180Y         S1      
327GND              PEX1  -AY34       A01X+072559Y+110886X0180Y         S1      
327GND              PEX1  -AY35       A01X+072933Y+110886X0180Y         S1      
327GND              PEX1  -AY36       A01X+073307Y+110886X0180Y         S1      
327GND              PEX1  -AU36M      A01X+073307Y+112008X0180Y         S1      
327GND              PEX1  -BA39       A01X+074429Y+110512X0180Y         S1      
327GND              PEX1  -AH40M      A01X+074803Y+115374X0180Y         S1      
327GND              PEX1  -AL40M      A01X+074803Y+114252X0180Y         S1      
327GND              PEX1  -AK40M      A01X+074803Y+114626X0180Y         S1      
327GND              PEX1  -AJ40M      A01X+074803Y+115000X0180Y         S1      
327GND              PEX1  -AH39M      A01X+074429Y+115374X0180Y         S1      
327GND              PEX1  -AM40       A01X+074803Y+113878X0180Y         S1      
327GND              PEX1  -AR40       A01X+074803Y+112756X0180Y         S1      
327GND              PEX1  -AY37       A01X+073681Y+110886X0180Y         S1      
327GND              PEX1  -AY38       A01X+074055Y+110886X0180Y         S1      
327GND              PEX1  -AY40       A01X+074803Y+110886X0180Y         S1      
327GND              PEX1  -AT40       A01X+074803Y+112382X0180Y         S1      
327GND              PEX1  -AU40       A01X+074803Y+112008X0180Y         S1      
327GND              PEX1  -AW40       A01X+074803Y+111260X0180Y         S1      
327GND              PEX1  -AF39       A01X+074429Y+116122X0180Y         S1      
327GND              PEX1  -AG40M      A01X+074803Y+115748X0180Y         S1      
327GND              PEX1  -AG39M      A01X+074429Y+115748X0180Y         S1      
327GND              PEX1  -AF40M      A01X+074803Y+116122X0180Y         S1      
327GND              PEX1  -AK43M      A01X+075925Y+114626X0180Y         S1      
327GND              PEX1  -AJ41M      A01X+075177Y+115000X0180Y         S1      
327GND              PEX1  -AG41M      A01X+075177Y+115748X0180Y         S1      
327GND              PEX1  -AF43       A01X+075925Y+116122X0180Y         S1      
327GND              PEX1  -AG42M      A01X+075551Y+115748X0180Y         S1      
327GND              PEX1  -AH43M      A01X+075925Y+115374X0180Y         S1      
327GND              PEX1  -AJ42M      A01X+075551Y+115000X0180Y         S1      
327GND              PEX1  -AL45M      A01X+076673Y+114252X0180Y         S1      
327GND              PEX1  -AH45M      A01X+076673Y+115374X0180Y         S1      
327GND              PEX1  -AH44M      A01X+076299Y+115374X0180Y         S1      
327GND              PEX1  -AM43M      A01X+075925Y+113878X0180Y         S1      
327GND              PEX1  -AM44M      A01X+076299Y+113878X0180Y         S1      
327GND              PEX1  -AM45       A01X+076673Y+113878X0180Y         S1      
327GND              PEX1  -AF45       A01X+076673Y+116122X0180Y         S1      
327GND              PEX1  -AG45M      A01X+076673Y+115748X0180Y         S1      
327GND              PEX1  -AL49M      A01X+078169Y+114252X0180Y         S1      
327GND              PEX1  -AM47       A01X+077421Y+113878X0180Y         S1      
327GND              PEX1  -AL48M      A01X+077795Y+114252X0180Y         S1      
327GND              PEX1  -AK47M      A01X+077421Y+114626X0180Y         S1      
327GND              PEX1  -AK46M      A01X+077047Y+114626X0180Y         S1      
327GND              PEX1  -AJ48M      A01X+077795Y+115000X0180Y         S1      
327GND              PEX1  -AJ49M      A01X+078169Y+115000X0180Y         S1      
327GND              PEX1  -AH47M      A01X+077421Y+115374X0180Y         S1      
327GND              PEX1  -AG48M      A01X+077795Y+115748X0180Y         S1      
327GND              PEX1  -AF47M      A01X+077421Y+116122X0180Y         S1      
327GND              PEX1  -AF46M      A01X+077047Y+116122X0180Y         S1      
327GND              PEX1  -AG49M      A01X+078169Y+115748X0180Y         S1      
327GND              PEX1  -AH46M      A01X+077047Y+115374X0180Y         S1      
327GND              PEX1  -AK45M      A01X+076673Y+114626X0180Y         S1      
327GND              PEX1  -AK44M      A01X+076299Y+114626X0180Y         S1      
327GND              PEX1  -AJ45M      A01X+076673Y+115000X0180Y         S1      
327GND              PEX1  -AL42M      A01X+075551Y+114252X0180Y         S1      
327GND              PEX1  -AL41M      A01X+075177Y+114252X0180Y         S1      
327GND              PEX1  -AY39       A01X+074429Y+110886X0180Y         S1      
327GND              PEX1  -AV40       A01X+074803Y+111634X0180Y         S1      
327GND              PEX1  -AN40       A01X+074803Y+113504X0180Y         S1      
327GND              PEX1  -AP40       A01X+074803Y+113130X0180Y         S1      
327GND              PEX1  -AK37M      A01X+073681Y+114626X0180Y         S1      
327GND              PEX1  -AH38M      A01X+074055Y+115374X0180Y         S1      
327GND              PEX1  -AH37       A01X+073681Y+115374X0180Y         S1      
327GND              PEX1  -AJ37M      A01X+073681Y+115000X0180Y         S1      
327GND              PEX1  -AN37M      A01X+073681Y+113504X0180Y         S1      
327GND              PEX1  -AL37M      A01X+073681Y+114252X0180Y         S1      
327GND              PEX1  -AM37M      A01X+073681Y+113878X0180Y         S1      
327GND              PEX1  -AR37M      A01X+073681Y+112756X0180Y         S1      
327GND              PEX1  -AU37M      A01X+073681Y+112008X0180Y         S1      
327GND              PEX1  -AT37M      A01X+073681Y+112382X0180Y         S1      
327GND              PEX1  -AP37M      A01X+073681Y+113130X0180Y         S1      
327GND              PEX1  -BA37       A01X+073681Y+110512X0180Y         S1      
327GND              PEX1  -AY33       A01X+072185Y+110886X0180Y         S1      
327GND              PEX1  -AJ36M      A01X+073307Y+115000X0180Y         S1      
327GND              PEX1  -AJ35M      A01X+072933Y+115000X0180Y         S1      
327GND              PEX1  -AK36M      A01X+073307Y+114626X0180Y         S1      
327GND              PEX1  -AG35M      A01X+072933Y+115748X0180Y         S1      
327GND              PEX1  -AF35       A01X+072933Y+116122X0180Y         S1      
327GND              PEX1  -AJ34M      A01X+072559Y+115000X0180Y         S1      
327GND              PEX1  -AJ33M      A01X+072185Y+115000X0180Y         S1      
327GND              PEX1  -BA33       A01X+072185Y+110512X0180Y         S1      
327GND              PEX1  -BA35       A01X+072933Y+110512X0180Y         S1      
327GND              PEX1  -AR29M      A01X+070689Y+112756X0180Y         S1      
327GND              PEX1  -AR28M      A01X+070315Y+112756X0180Y         S1      
327GND              PEX1  -AJ31M      A01X+071437Y+115000X0180Y         S1      
327GND              PEX1  -AJ29M      A01X+070689Y+115000X0180Y         S1      
327GND              PEX1  -AL31M      A01X+071437Y+114252X0180Y         S1      
327GND              PEX1  -AL29M      A01X+070689Y+114252X0180Y         S1      
327GND              PEX1  -AL28M      A01X+070315Y+114252X0180Y         S1      
327GND              PEX1  -BA31       A01X+071437Y+110512X0180Y         S1      
327GND              PEX1  -AY31       A01X+071437Y+110886X0180Y         S1      
327GND              PEX1  -AY30       A01X+071063Y+110886X0180Y         S1      
327GND              PEX1  -AY29       A01X+070689Y+110886X0180Y         S1      
327GND              PEX1  -AY28       A01X+070315Y+110886X0180Y         S1      
327GND              PEX1  -BA29       A01X+070689Y+110512X0180Y         S1      
327GND              PEX1  -AU31M      A01X+071437Y+112008X0180Y         S1      
327GND              PEX1  -AU30M      A01X+071063Y+112008X0180Y         S1      
327GND              PEX1  -AT29M      A01X+070689Y+112382X0180Y         S1      
327GND              PEX1  -AJ27M      A01X+069941Y+115000X0180Y         S1      
327GND              PEX1  -AJ26M      A01X+069567Y+115000X0180Y         S1      
327GND              PEX1  -AL27M      A01X+069941Y+114252X0180Y         S1      
327GND              PEX1  -AL25       A01X+069193Y+114252X0180Y         S1      
327GND              PEX1  -AL26M      A01X+069567Y+114252X0180Y         S1      
327GND              PEX1  -AU26M      A01X+069567Y+112008X0180Y         S1      
327GND              PEX1  -AW24       A01X+068819Y+111260X0180Y         S1      
327GND              PEX1  -AU22M      A01X+068071Y+112008X0180Y         S1      
327GND              PEX1  -AW20       A01X+067323Y+111260X0180Y         S1      
327GND              PEX1  -AY20       A01X+067323Y+110886X0180Y         S1      
327GND              PEX1  -AY21       A01X+067697Y+110886X0180Y         S1      
327GND              PEX1  -AY22       A01X+068071Y+110886X0180Y         S1      
327GND              PEX1  -AY19       A01X+066949Y+110886X0180Y         S1      
327GND              PEX1  -AY16       A01X+065827Y+110886X0180Y         S1      
327GND              PEX1  -AY18       A01X+066575Y+110886X0180Y         S1      
327GND              PEX1  -AY17       A01X+066201Y+110886X0180Y         S1      
327GND              PEX1  -AY15       A01X+065453Y+110886X0180Y         S1      
327GND              PEX1  -BA17       A01X+066201Y+110512X0180Y         S1      
327GND              PEX1  -BA19       A01X+066949Y+110512X0180Y         S1      
327GND              PEX1  -AU19M      A01X+066949Y+112008X0180Y         S1      
327GND              PEX1  -AY14       A01X+065079Y+110886X0180Y         S1      
327GND              PEX1  -BA11       A01X+063957Y+110512X0180Y         S1      
327GND              PEX1  -BA13       A01X+064705Y+110512X0180Y         S1      
327GND              PEX1  -AY13       A01X+064705Y+110886X0180Y         S1      
327GND              PEX1  -AY12       A01X+064331Y+110886X0180Y         S1      
327GND              PEX1  -AY11       A01X+063957Y+110886X0180Y         S1      
327GND              PEX1  -AW11       A01X+063957Y+111260X0180Y         S1      
327GND              PEX1  -BC8 M      A01X+062835Y+109764X0180Y         S1      
327GND              PEX1  -AW10       A01X+063583Y+111260X0180Y         S1      
327GND              PEX1  -BJ8 M      A01X+062835Y+107520X0180Y         S1      
327GND              PEX1  -BH8 M      A01X+062835Y+107894X0180Y         S1      
327GND              R1311 -2          A18X+074853Y+118711X0198Y0197R270 S2      
327GND              PEX1  -N26 M      A01X+069567Y+120984X0180Y         S1      
327GND              PEX1  -N25        A01X+069193Y+120984X0180Y         S1      
327GND              PEX1  -P25 M      A01X+069193Y+120610X0180Y         S1      
327GND              PEX1  -P26 M      A01X+069567Y+120610X0180Y         S1      
327GND              PEX1  -R26 M      A01X+069567Y+120236X0180Y         S1      
327GND              PEX1  -R25        A01X+069193Y+120236X0180Y         S1      
327GND              PEX1  -R27 M      A01X+069941Y+120236X0180Y         S1      
327GND              PEX1  -P27 M      A01X+069941Y+120610X0180Y         S1      
327GND              PEX1  -W27 M      A01X+069941Y+118740X0180Y         S1      
327GND              PEX1  -R29 M      A01X+070689Y+120236X0180Y         S1      
327GND              PEX1  -R28 M      A01X+070315Y+120236X0180Y         S1      
327GND              PEX1  -W30 M      A01X+071063Y+118740X0180Y         S1      
327GND              PEX1  -W32 M      A01X+071811Y+118740X0180Y         S1      
327GND              PEX1  -P28 M      A01X+070315Y+120610X0180Y         S1      
327GND              PEX1  -N28 M      A01X+070315Y+120984X0180Y         S1      
327GND              PEX1  -N29 M      A01X+070689Y+120984X0180Y         S1      
327GND              PEX1  -P29 M      A01X+070689Y+120610X0180Y         S1      
327GND              PEX1  -N30 M      A01X+071063Y+120984X0180Y         S1      
327GND              PEX1  -R32 M      A01X+071811Y+120236X0180Y         S1      
327GND              PEX1  -N37        A01X+073681Y+120984X0180Y         S1      
327GND              PEX1  -P37        A01X+073681Y+120610X0180Y         S1      
327GND              PEX1  -R37        A01X+073681Y+120236X0180Y         S1      
327GND              PEX1  -N36 M      A01X+073307Y+120984X0180Y         S1      
327GND              PEX1  -N33 M      A01X+072185Y+120984X0180Y         S1      
327GND              PEX1  -N34 M      A01X+072559Y+120984X0180Y         S1      
327GND              PEX1  -V34 M      A01X+072559Y+119114X0180Y         S1      
327GND              PEX1  -U35 M      A01X+072933Y+119488X0180Y         S1      
327GND              PEX1  -P35 M      A01X+072933Y+120610X0180Y         S1      
327GND              PEX1  -P33 M      A01X+072185Y+120610X0180Y         S1      
327GND              PEX1  -P34 M      A01X+072559Y+120610X0180Y         S1      
327GND              PEX1  -R33 M      A01X+072185Y+120236X0180Y         S1      
327GND              PEX1  -R34 M      A01X+072559Y+120236X0180Y         S1      
327GND              PEX1  -U34 M      A01X+072559Y+119488X0180Y         S1      
327GND              PEX1  -T34 M      A01X+072559Y+119862X0180Y         S1      
327GND              PEX1  -U33 M      A01X+072185Y+119488X0180Y         S1      
327GND              PEX1  -R35 M      A01X+072933Y+120236X0180Y         S1      
327GND              PEX1  -N35 M      A01X+072933Y+120984X0180Y         S1      
327GND              PEX1  -W33 M      A01X+072185Y+118740X0180Y         S1      
327GND              PEX1  -W34 M      A01X+072559Y+118740X0180Y         S1      
327GND              PEX1  -P32 M      A01X+071811Y+120610X0180Y         S1      
327GND              PEX1  -R30 M      A01X+071063Y+120236X0180Y         S1      
327GND              PEX1  -P31 M      A01X+071437Y+120610X0180Y         S1      
327GND              PEX1  -R31        A01X+071437Y+120236X0180Y         S1      
327GND              PEX1  -N32 M      A01X+071811Y+120984X0180Y         S1      
327GND              PEX1  -N31 M      A01X+071437Y+120984X0180Y         S1      
327GND              PEX1  -P30 M      A01X+071063Y+120610X0180Y         S1      
327GND              PEX1  -W31 M      A01X+071437Y+118740X0180Y         S1      
327GND              PEX1  -W29 M      A01X+070689Y+118740X0180Y         S1      
327GND              PEX1  -W28 M      A01X+070315Y+118740X0180Y         S1      
327GND              PEX1  -U30 M      A01X+071063Y+119488X0180Y         S1      
327GND              PEX1  -U32 M      A01X+071811Y+119488X0180Y         S1      
327GND              PEX1  -U31 M      A01X+071437Y+119488X0180Y         S1      
327GND              PEX1  -U29 M      A01X+070689Y+119488X0180Y         S1      
327GND              PEX1  -U28 M      A01X+070315Y+119488X0180Y         S1      
327GND              PEX1  -U25        A01X+069193Y+119488X0180Y         S1      
327GND              PEX1  -U26 M      A01X+069567Y+119488X0180Y         S1      
327GND              PEX1  -U27 M      A01X+069941Y+119488X0180Y         S1      
327GND              PEX1  -N27 M      A01X+069941Y+120984X0180Y         S1      
327GND              PEX1  -W26 M      A01X+069567Y+118740X0180Y         S1      
327GND              PEX1  -W25        A01X+069193Y+118740X0180Y         S1      
327GND              PEX1  -W14 M      A01X+065079Y+118740X0180Y         S1      
327GND              PEX1  -V15 M      A01X+065453Y+119114X0180Y         S1      
327GND              PEX1  -W18 M      A01X+066575Y+118740X0180Y         S1      
327GND              PEX1  -W17 M      A01X+066201Y+118740X0180Y         S1      
327GND              PEX1  -W16 M      A01X+065827Y+118740X0180Y         S1      
327GND              PEX1  -W15 M      A01X+065453Y+118740X0180Y         S1      
327GND              PEX1  -W22 M      A01X+068071Y+118740X0180Y         S1      
327GND              PEX1  -W21 M      A01X+067697Y+118740X0180Y         S1      
327GND              PEX1  -W20 M      A01X+067323Y+118740X0180Y         S1      
327GND              PEX1  -W24        A01X+068819Y+118740X0180Y         S1      
327GND              PEX1  -W23 M      A01X+068445Y+118740X0180Y         S1      
327GND              PEX1  -W19 M      A01X+066949Y+118740X0180Y         S1      
327GND              PEX1  -U19 M      A01X+066949Y+119488X0180Y         S1      
327GND              PEX1  -U21 M      A01X+067697Y+119488X0180Y         S1      
327GND              PEX1  -U22 M      A01X+068071Y+119488X0180Y         S1      
327GND              PEX1  -U23 M      A01X+068445Y+119488X0180Y         S1      
327GND              PEX1  -U24        A01X+068819Y+119488X0180Y         S1      
327GND              PEX1  -U20 M      A01X+067323Y+119488X0180Y         S1      
327GND              PEX1  -U15 M      A01X+065453Y+119488X0180Y         S1      
327GND              PEX1  -U18 M      A01X+066575Y+119488X0180Y         S1      
327GND              PEX1  -U17 M      A01X+066201Y+119488X0180Y         S1      
327GND              PEX1  -U16 M      A01X+065827Y+119488X0180Y         S1      
327GND              PEX1  -T15 M      A01X+065453Y+119862X0180Y         S1      
327GND              PEX1  -AA18M      A01X+066575Y+117992X0180Y         S1      
327GND              PEX1  -AA17M      A01X+066201Y+117992X0180Y         S1      
327GND              PEX1  -AA16M      A01X+065827Y+117992X0180Y         S1      
327GND              PEX1  -Y15 M      A01X+065453Y+118366X0180Y         S1      
327GND              PEX1  -AA23M      A01X+068445Y+117992X0180Y         S1      
327GND              PEX1  -AA24       A01X+068819Y+117992X0180Y         S1      
327GND              PEX1  -AA22M      A01X+068071Y+117992X0180Y         S1      
327GND              PEX1  -AA21M      A01X+067697Y+117992X0180Y         S1      
327GND              PEX1  -AA20M      A01X+067323Y+117992X0180Y         S1      
327GND              PEX1  -AA19M      A01X+066949Y+117992X0180Y         S1      
327GND              PEX1  -AC24       A01X+068819Y+117244X0180Y         S1      
327GND              PEX1  -AG24       A01X+068819Y+115748X0180Y         S1      
327GND              PEX1  -AL13       A01X+064705Y+114252X0180Y         S1      
327GND              PEX1  -AL12       A01X+064331Y+114252X0180Y         S1      
327GND              PEX1  -AL11       A01X+063957Y+114252X0180Y         S1      
327GND              PEX1  -AL10       A01X+063583Y+114252X0180Y         S1      
327GND              PEX1  -AL9        A01X+063209Y+114252X0180Y         S1      
327GND              PEX1  -AL8        A01X+062835Y+114252X0180Y         S1      
327GND              PEX1  -AL7        A01X+062461Y+114252X0180Y         S1      
327GND              PEX1  -AL5        A01X+061713Y+114252X0180Y         S1      
327GND              PEX1  -AL4        A01X+061339Y+114252X0180Y         S1      
327GND              PEX1  -AL3        A01X+060965Y+114252X0180Y         S1      
327GND              PEX1  -AL6        A01X+062087Y+114252X0180Y         S1      
327GND              PEX1  -BD6        A01X+062087Y+109390X0180Y         S1      
327GND              PEX1  -BD4        A01X+061339Y+109390X0180Y         S1      
327GND              R1299 -1          A01X+060492Y+099511X0198Y0197R270 S1      
327GND              PEX1  -BD1        A01X+060216Y+109390X0180Y         S1      
327GND              PEX1  -BD2        A01X+060590Y+109390X0180Y         S1      
327GND              PEX1  -AL1        A01X+060216Y+114252X0180Y         S1      
327GND              PEX1  -AL2        A01X+060590Y+114252X0180Y         S1      
327GND              R1286 -1          A01X+058892Y+099511X0198Y0197R270 S1      
327GND              C3246 -2   M      A01X+056009Y+103509X0120Y0150R090 S1      
327GND              R3469 -2          A18X+051690Y+089750X0198Y0197R180 S2      
327GND              C3635 -2   M      A01X+043480Y+155016X0198Y0197     S1      
327GND              PC283 -2          A01X+042001Y+083480X0198Y0197     S1      
327GND              PEX0  -Y1         A01X+014508Y+118366X0180Y         S1      
327GND              PEX0  -W1         A01X+014508Y+118740X0180Y         S1      
327GND              PEX0  -Y2         A01X+014882Y+118366X0180Y         S1      
327GND              PEX0  -W2         A01X+014882Y+118740X0180Y         S1      
327GND              PEX0  -D2         A01X+014882Y+124350X0180Y         S1      
327GND              PEX0  -B2         A01X+014882Y+125098X0180Y         S1      
327GND              PEX0  -F1         A01X+014508Y+123602X0180Y         S1      
327GND              PEX0  -J2         A01X+014882Y+122480X0180Y         S1      
327GND              PEX0  -G2         A01X+014882Y+123228X0180Y         S1      
327GND              PEX0  -L1         A01X+014508Y+121732X0180Y         S1      
327GND              PEX0  -N2         A01X+014882Y+120984X0180Y         S1      
327GND              PEX0  -L2         A01X+014882Y+121732X0180Y         S1      
327GND              PEX0  -R1         A01X+014508Y+120236X0180Y         S1      
327GND              PEX0  -U1         A01X+014508Y+119488X0180Y         S1      
327GND              PEX0  -R2         A01X+014882Y+120236X0180Y         S1      
327GND              PEX0  -U2         A01X+014882Y+119488X0180Y         S1      
327GND              PEX0  -P4         A01X+015630Y+120610X0180Y         S1      
327GND              PEX0  -T4         A01X+015630Y+119862X0180Y         S1      
327GND              PEX0  -T5         A01X+016004Y+119862X0180Y         S1      
327GND              PEX0  -V3         A01X+015256Y+119114X0180Y         S1      
327GND              PEX0  -V6         A01X+016378Y+119114X0180Y         S1      
327GND              PEX0  -AB6 M      A01X+016378Y+117618X0180Y         S1      
327GND              PEX0  -AC5 M      A01X+016004Y+117244X0180Y         S1      
327GND              PEX0  -AC6 M      A01X+016378Y+117244X0180Y         S1      
327GND              PEX0  -W5         A01X+016004Y+118740X0180Y         S1      
327GND              PEX0  -Y3         A01X+015256Y+118366X0180Y         S1      
327GND              PEX0  -Y4         A01X+015630Y+118366X0180Y         S1      
327GND              PEX0  -Y5  M      A01X+016004Y+118366X0180Y         S1      
327GND              PEX0  -V5         A01X+016004Y+119114X0180Y         S1      
327GND              PEX0  -V4         A01X+015630Y+119114X0180Y         S1      
327GND              PEX0  -Y6  M      A01X+016378Y+118366X0180Y         S1      
327GND              PEX0  -AA6 M      A01X+016378Y+117992X0180Y         S1      
327GND              PEX0  -G4         A01X+015630Y+123228X0180Y         S1      
327GND              PEX0  -H5         A01X+016004Y+122854X0180Y         S1      
327GND              PEX0  -F4         A01X+015630Y+123602X0180Y         S1      
327GND              PEX0  -J7         A01X+016752Y+122480X0180Y         S1      
327GND              PEX0  -J3         A01X+015256Y+122480X0180Y         S1      
327GND              PEX0  -J5         A01X+016004Y+122480X0180Y         S1      
327GND              PEX0  -P6         A01X+016378Y+120610X0180Y         S1      
327GND              PEX0  -R5         A01X+016004Y+120236X0180Y         S1      
327GND              PEX0  -P5         A01X+016004Y+120610X0180Y         S1      
327GND              PEX0  -A6         A01X+016378Y+125472X0180Y         S1      
327GND              PEX0  -B6         A01X+016378Y+125098X0180Y         S1      
327GND              PEX0  -B4         A01X+015630Y+125098X0180Y         S1      
327GND              PEX0  -A4         A01X+015630Y+125472X0180Y         S1      
327GND              PEX0  -C5         A01X+016004Y+124724X0180Y         S1      
327GND              PEX0  -C3         A01X+015256Y+124724X0180Y         S1      
327GND              PEX0  -E5         A01X+016004Y+123976X0180Y         S1      
327GND              PEX0  -D5         A01X+016004Y+124350X0180Y         S1      
327GND              PEX0  -E6         A01X+016378Y+123976X0180Y         S1      
327GND              PEX0  -AE9        A01X+017500Y+116496X0180Y         S1      
327GND              PEX0  -R9         A01X+017500Y+120236X0180Y         S1      
327GND              PEX0  -U9         A01X+017500Y+119488X0180Y         S1      
327GND              PEX0  -R10        A01X+017874Y+120236X0180Y         S1      
327GND              PEX0  -AE11M      A01X+018248Y+116496X0180Y         S1      
327GND              PEX0  -AD10M      A01X+017874Y+116870X0180Y         S1      
327GND              PEX0  -AD11M      A01X+018248Y+116870X0180Y         S1      
327GND              PEX0  -AD13M      A01X+018996Y+116870X0180Y         S1      
327GND              PEX0  -AC11M      A01X+018248Y+117244X0180Y         S1      
327GND              PEX0  -AC12       A01X+018622Y+117244X0180Y         S1      
327GND              PEX0  -AB11M      A01X+018248Y+117618X0180Y         S1      
327GND              PEX0  -AE14       A01X+019370Y+116496X0180Y         S1      
327GND              PEX0  -V7         A01X+016752Y+119114X0180Y         S1      
327GND              PEX0  -V10        A01X+017874Y+119114X0180Y         S1      
327GND              PEX0  -Y10        A01X+017874Y+118366X0180Y         S1      
327GND              PEX0  -W10 M      A01X+017874Y+118740X0180Y         S1      
327GND              PEX0  -Y7  M      A01X+016752Y+118366X0180Y         S1      
327GND              PEX0  -AA7        A01X+016752Y+117992X0180Y         S1      
327GND              PEX0  -AA8 M      A01X+017126Y+117992X0180Y         S1      
327GND              PEX0  -AB9 M      A01X+017500Y+117618X0180Y         S1      
327GND              PEX0  -AA9 M      A01X+017500Y+117992X0180Y         S1      
327GND              PEX0  -W8  M      A01X+017126Y+118740X0180Y         S1      
327GND              PEX0  -Y8  M      A01X+017126Y+118366X0180Y         S1      
327GND              PEX0  -W9  M      A01X+017500Y+118740X0180Y         S1      
327GND              PEX0  -Y9  M      A01X+017500Y+118366X0180Y         S1      
327GND              PEX0  -AD15M      A01X+019744Y+116870X0180Y         S1      
327GND              PEX0  -AB13M      A01X+018996Y+117618X0180Y         S1      
327GND              PEX0  -AA12       A01X+018622Y+117992X0180Y         S1      
327GND              PEX0  -AA11M      A01X+018248Y+117992X0180Y         S1      
327GND              PEX0  -Y11        A01X+018248Y+118366X0180Y         S1      
327GND              PEX0  -AC14M      A01X+019370Y+117244X0180Y         S1      
327GND              PEX0  -AE16       A01X+020118Y+116496X0180Y         S1      
327GND              PEX0  -N8         A01X+017126Y+120984X0180Y         S1      
327GND              PEX0  -P7         A01X+016752Y+120610X0180Y         S1      
327GND              PEX0  -K10        A01X+017874Y+122106X0180Y         S1      
327GND              PEX0  -M10        A01X+017874Y+121358X0180Y         S1      
327GND              PEX0  -A8         A01X+017126Y+125472X0180Y         S1      
327GND              PEX0  -A10        A01X+017874Y+125472X0180Y         S1      
327GND              PEX0  -B10        A01X+017874Y+125098X0180Y         S1      
327GND              PEX0  -C11        A01X+018248Y+124724X0180Y         S1      
327GND              PEX0  -D7         A01X+016752Y+124350X0180Y         S1      
327GND              PEX0  -D9         A01X+017500Y+124350X0180Y         S1      
327GND              PEX0  -F8         A01X+017126Y+123602X0180Y         S1      
327GND              PEX0  -E8         A01X+017126Y+123976X0180Y         S1      
327GND              PEX0  -E7         A01X+016752Y+123976X0180Y         S1      
327GND              PEX0  -H7         A01X+016752Y+122854X0180Y         S1      
327GND              PEX0  -G10        A01X+017874Y+123228X0180Y         S1      
327GND              PEX0  -H9         A01X+017500Y+122854X0180Y         S1      
327GND              PEX0  -E10        A01X+017874Y+123976X0180Y         S1      
327GND              PEX0  -E9         A01X+017500Y+123976X0180Y         S1      
327GND              PEX0  -F10        A01X+017874Y+123602X0180Y         S1      
327GND              PEX0  -G8         A01X+017126Y+123228X0180Y         S1      
327GND              PEX0  -J9         A01X+017500Y+122480X0180Y         S1      
327GND              PEX0  -J11        A01X+018248Y+122480X0180Y         S1      
327GND              PEX0  -F12        A01X+018622Y+123602X0180Y         S1      
327GND              PEX0  -J15        A01X+019744Y+122480X0180Y         S1      
327GND              PEX0  -H15        A01X+019744Y+122854X0180Y         S1      
327GND              PEX0  -H11        A01X+018248Y+122854X0180Y         S1      
327GND              PEX0  -G14        A01X+019370Y+123228X0180Y         S1      
327GND              PEX0  -F14        A01X+019370Y+123602X0180Y         S1      
327GND              PEX0  -J13        A01X+018996Y+122480X0180Y         S1      
327GND              PEX0  -K14        A01X+019370Y+122106X0180Y         S1      
327GND              PEX0  -K13        A01X+018996Y+122106X0180Y         S1      
327GND              PEX0  -L14        A01X+019370Y+121732X0180Y         S1      
327GND              PEX0  -D11        A01X+018248Y+124350X0180Y         S1      
327GND              PEX0  -E11        A01X+018248Y+123976X0180Y         S1      
327GND              PEX0  -E12        A01X+018622Y+123976X0180Y         S1      
327GND              PEX0  -D13        A01X+018996Y+124350X0180Y         S1      
327GND              PEX0  -E13        A01X+018996Y+123976X0180Y         S1      
327GND              PEX0  -B18        A01X+020866Y+125098X0180Y         S1      
327GND              PEX0  -A18        A01X+020866Y+125472X0180Y         S1      
327GND              PEX0  -C19        A01X+021240Y+124724X0180Y         S1      
327GND              PEX0  -C17        A01X+020492Y+124724X0180Y         S1      
327GND              PEX0  -E19        A01X+021240Y+123976X0180Y         S1      
327GND              PEX0  -D19        A01X+021240Y+124350X0180Y         S1      
327GND              PEX0  -D17        A01X+020492Y+124350X0180Y         S1      
327GND              PEX0  -J17        A01X+020492Y+122480X0180Y         S1      
327GND              PEX0  -G16        A01X+020118Y+123228X0180Y         S1      
327GND              PEX0  -F20        A01X+021614Y+123602X0180Y         S1      
327GND              PEX0  -J19        A01X+021240Y+122480X0180Y         S1      
327GND              PEX0  -H23        A01X+022736Y+122854X0180Y         S1      
327GND              PEX0  -G20        A01X+021614Y+123228X0180Y         S1      
327GND              PEX0  -J23        A01X+022736Y+122480X0180Y         S1      
327GND              PEX0  -H21        A01X+021988Y+122854X0180Y         S1      
327GND              PEX0  -J21        A01X+021988Y+122480X0180Y         S1      
327GND              PEX0  -G22        A01X+022362Y+123228X0180Y         S1      
327GND              PEX0  -F22        A01X+022362Y+123602X0180Y         S1      
327GND              PEX0  -A24        A01X+023110Y+125472X0180Y         S1      
327GND              PEX0  -C23        A01X+022736Y+124724X0180Y         S1      
327GND              PEX0  -B22        A01X+022362Y+125098X0180Y         S1      
327GND              PEX0  -E23        A01X+022736Y+123976X0180Y         S1      
327GND              PEX0  -D23        A01X+022736Y+124350X0180Y         S1      
327GND              PEX0  -E22        A01X+022362Y+123976X0180Y         S1      
327GND              PEX0  -D21        A01X+021988Y+124350X0180Y         S1      
327GND              PEX0  -E20        A01X+021614Y+123976X0180Y         S1      
327GND              PEX0  -E21        A01X+021988Y+123976X0180Y         S1      
327GND              PEX0  -K26        A01X+023858Y+122106X0180Y         S1      
327GND              PEX0  -K27        A01X+024232Y+122106X0180Y         S1      
327GND              PEX0  -K28        A01X+024606Y+122106X0180Y         S1      
327GND              PEX0  -C27        A01X+024232Y+124724X0180Y         S1      
327GND              PEX0  -E25        A01X+023484Y+123976X0180Y         S1      
327GND              PEX0  -F24        A01X+023110Y+123602X0180Y         S1      
327GND              PEX0  -D25        A01X+023484Y+124350X0180Y         S1      
327GND              PEX0  -E24        A01X+023110Y+123976X0180Y         S1      
327GND              PEX0  -E28        A01X+024606Y+123976X0180Y         S1      
327GND              PEX0  -D27        A01X+024232Y+124350X0180Y         S1      
327GND              PEX0  -G26        A01X+023858Y+123228X0180Y         S1      
327GND              PEX0  -H27        A01X+024232Y+122854X0180Y         S1      
327GND              PEX0  -G24        A01X+023110Y+123228X0180Y         S1      
327GND              PEX0  -H25        A01X+023484Y+122854X0180Y         S1      
327GND              PEX0  -J25        A01X+023484Y+122480X0180Y         S1      
327GND              PEX0  -E27        A01X+024232Y+123976X0180Y         S1      
327GND              PEX0  -F26        A01X+023858Y+123602X0180Y         S1      
327GND              PEX0  -E26        A01X+023858Y+123976X0180Y         S1      
327GND              PEX0  -J29        A01X+024980Y+122480X0180Y         S1      
327GND              PEX0  -H29        A01X+024980Y+122854X0180Y         S1      
327GND              PEX0  -G30        A01X+025354Y+123228X0180Y         S1      
327GND              PEX0  -F30        A01X+025354Y+123602X0180Y         S1      
327GND              PEX0  -J31        A01X+025728Y+122480X0180Y         S1      
327GND              PEX0  -F32        A01X+026102Y+123602X0180Y         S1      
327GND              PEX0  -G32        A01X+026102Y+123228X0180Y         S1      
327GND              PEX0  -C31        A01X+025728Y+124724X0180Y         S1      
327GND              PEX0  -C29        A01X+024980Y+124724X0180Y         S1      
327GND              PEX0  -B30        A01X+025354Y+125098X0180Y         S1      
327GND              PEX0  -A30        A01X+025354Y+125472X0180Y         S1      
327GND              PEX0  -H33        A01X+026476Y+122854X0180Y         S1      
327GND              PEX0  -G34        A01X+026850Y+123228X0180Y         S1      
327GND              PEX0  -G36        A01X+027598Y+123228X0180Y         S1      
327GND              PEX0  -J35        A01X+027224Y+122480X0180Y         S1      
327GND              PEX0  -F36        A01X+027598Y+123602X0180Y         S1      
327GND              PEX0  -J33        A01X+026476Y+122480X0180Y         S1      
327GND              PEX0  -F34        A01X+026850Y+123602X0180Y         S1      
327GND              PEX0  -K33        A01X+026476Y+122106X0180Y         S1      
327GND              PEX0  -C33        A01X+026476Y+124724X0180Y         S1      
327GND              PEX0  -B36        A01X+027598Y+125098X0180Y         S1      
327GND              PEX0  -AE40M      A01X+029094Y+116496X0180Y         S1      
327GND              PEX0  -AE39       A01X+028720Y+116496X0180Y         S1      
327GND              PEX0  -AD39M      A01X+028720Y+116870X0180Y         S1      
327GND              PEX0  -AC41M      A01X+029468Y+117244X0180Y         S1      
327GND              PEX0  -AE41M      A01X+029468Y+116496X0180Y         S1      
327GND              PEX0  -AC40M      A01X+029094Y+117244X0180Y         S1      
327GND              PEX0  -AC39M      A01X+028720Y+117244X0180Y         S1      
327GND              PEX0  -R40        A01X+029094Y+120236X0180Y         S1      
327GND              PEX0  -T40        A01X+029094Y+119862X0180Y         S1      
327GND              PEX0  -U41        A01X+029468Y+119488X0180Y         S1      
327GND              PEX0  -R41        A01X+029468Y+120236X0180Y         S1      
327GND              PEX0  -Y40 M      A01X+029094Y+118366X0180Y         S1      
327GND              PEX0  -W40 M      A01X+029094Y+118740X0180Y         S1      
327GND              PEX0  -V40        A01X+029094Y+119114X0180Y         S1      
327GND              PEX0  -W41 M      A01X+029468Y+118740X0180Y         S1      
327GND              PEX0  -AA41M      A01X+029468Y+117992X0180Y         S1      
327GND              PEX0  -H39        A01X+028720Y+122854X0180Y         S1      
327GND              PEX0  -G40        A01X+029094Y+123228X0180Y         S1      
327GND              PEX0  -H37        A01X+027972Y+122854X0180Y         S1      
327GND              PEX0  -J39        A01X+028720Y+122480X0180Y         S1      
327GND              PEX0  -F40        A01X+029094Y+123602X0180Y         S1      
327GND              PEX0  -H41        A01X+029468Y+122854X0180Y         S1      
327GND              PEX0  -F38        A01X+028346Y+123602X0180Y         S1      
327GND              PEX0  -P40        A01X+029094Y+120610X0180Y         S1      
327GND              PEX0  -L40        A01X+029094Y+121732X0180Y         S1      
327GND              PEX0  -L41        A01X+029468Y+121732X0180Y         S1      
327GND              PEX0  -K41        A01X+029468Y+122106X0180Y         S1      
327GND              PEX0  -N41        A01X+029468Y+120984X0180Y         S1      
327GND              PEX0  -B38        A01X+028346Y+125098X0180Y         S1      
327GND              PEX0  -A38        A01X+028346Y+125472X0180Y         S1      
327GND              PEX0  -E41        A01X+029468Y+123976X0180Y         S1      
327GND              PEX0  -D41        A01X+029468Y+124350X0180Y         S1      
327GND              PEX0  -V45 M      A01X+030964Y+119114X0180Y         S1      
327GND              PEX0  -U45 M      A01X+030964Y+119488X0180Y         S1      
327GND              PEX0  -V44 M      A01X+030590Y+119114X0180Y         S1      
327GND              PEX0  -T44        A01X+030590Y+119862X0180Y         S1      
327GND              PEX0  -U42        A01X+029842Y+119488X0180Y         S1      
327GND              PEX0  -T43        A01X+030216Y+119862X0180Y         S1      
327GND              PEX0  -V43 M      A01X+030216Y+119114X0180Y         S1      
327GND              PEX0  -AA42M      A01X+029842Y+117992X0180Y         S1      
327GND              PEX0  -W42 M      A01X+029842Y+118740X0180Y         S1      
327GND              PEX0  -Y43 M      A01X+030216Y+118366X0180Y         S1      
327GND              PEX0  -AA45M      A01X+030964Y+117992X0180Y         S1      
327GND              PEX0  -AB44M      A01X+030590Y+117618X0180Y         S1      
327GND              PEX0  -AB43M      A01X+030216Y+117618X0180Y         S1      
327GND              PEX0  -AE42M      A01X+029842Y+116496X0180Y         S1      
327GND              PEX0  -AE45       A01X+030964Y+116496X0180Y         S1      
327GND              PEX0  -T47        A01X+031712Y+119862X0180Y         S1      
327GND              PEX0  -T46        A01X+031338Y+119862X0180Y         S1      
327GND              PEX0  -V47 M      A01X+031712Y+119114X0180Y         S1      
327GND              PEX0  -U49 M      A01X+032461Y+119488X0180Y         S1      
327GND              PEX0  -U48 M      A01X+032087Y+119488X0180Y         S1      
327GND              PEX0  -V46 M      A01X+031338Y+119114X0180Y         S1      
327GND              PEX0  -Y46 M      A01X+031338Y+118366X0180Y         S1      
327GND              PEX0  -W49 M      A01X+032461Y+118740X0180Y         S1      
327GND              PEX0  -W48 M      A01X+032087Y+118740X0180Y         S1      
327GND              PEX0  -Y47 M      A01X+031712Y+118366X0180Y         S1      
327GND              PEX0  -AA49M      A01X+032461Y+117992X0180Y         S1      
327GND              PEX0  -AE48M      A01X+032087Y+116496X0180Y         S1      
327GND              PEX0  -AE49M      A01X+032461Y+116496X0180Y         S1      
327GND              PEX0  -AC48M      A01X+032087Y+117244X0180Y         S1      
327GND              PEX0  -AC49M      A01X+032461Y+117244X0180Y         S1      
327GND              PEX0  -AD46M      A01X+031338Y+116870X0180Y         S1      
327GND              PEX0  -AD47M      A01X+031712Y+116870X0180Y         S1      
327GND              PEX0  -AB46M      A01X+031338Y+117618X0180Y         S1      
327GND              PEX0  -AB47M      A01X+031712Y+117618X0180Y         S1      
327GND              PEX0  -AA48M      A01X+032087Y+117992X0180Y         S1      
327GND              PEX0  -AD45M      A01X+030964Y+116870X0180Y         S1      
327GND              PEX0  -AD44M      A01X+030590Y+116870X0180Y         S1      
327GND              PEX0  -AC45M      A01X+030964Y+117244X0180Y         S1      
327GND              PEX0  -AD43M      A01X+030216Y+116870X0180Y         S1      
327GND              PEX0  -AC42M      A01X+029842Y+117244X0180Y         S1      
327GND              PEX0  -AB45M      A01X+030964Y+117618X0180Y         S1      
327GND              PEX0  -W45 M      A01X+030964Y+118740X0180Y         S1      
327GND              PEX0  -Y45 M      A01X+030964Y+118366X0180Y         S1      
327GND              PEX0  -Y44 M      A01X+030590Y+118366X0180Y         S1      
327GND              PEX0  -J45        A01X+030964Y+122480X0180Y         S1      
327GND              PEX0  -H45        A01X+030964Y+122854X0180Y         S1      
327GND              PEX0  -J43        A01X+030216Y+122480X0180Y         S1      
327GND              PEX0  -H43        A01X+030216Y+122854X0180Y         S1      
327GND              PEX0  -F42        A01X+029842Y+123602X0180Y         S1      
327GND              PEX0  -G42        A01X+029842Y+123228X0180Y         S1      
327GND              PEX0  -N42        A01X+029842Y+120984X0180Y         S1      
327GND              PEX0  -R48        A01X+032087Y+120236X0180Y         S1      
327GND              PEX0  -R49        A01X+032461Y+120236X0180Y         S1      
327GND              PEX0  -P47        A01X+031712Y+120610X0180Y         S1      
327GND              PEX0  -P46        A01X+031338Y+120610X0180Y         S1      
327GND              PEX0  -P44        A01X+030590Y+120610X0180Y         S1      
327GND              PEX0  -M44        A01X+030590Y+121358X0180Y         S1      
327GND              PEX0  -K43        A01X+030216Y+122106X0180Y         S1      
327GND              PEX0  -L42        A01X+029842Y+121732X0180Y         S1      
327GND              PEX0  -K42        A01X+029842Y+122106X0180Y         S1      
327GND              PEX0  -K44        A01X+030590Y+122106X0180Y         S1      
327GND              PEX0  -K45        A01X+030964Y+122106X0180Y         S1      
327GND              PEX0  -L45        A01X+030964Y+121732X0180Y         S1      
327GND              PEX0  -B44        A01X+030590Y+125098X0180Y         S1      
327GND              PEX0  -C43        A01X+030216Y+124724X0180Y         S1      
327GND              PEX0  -E42        A01X+029842Y+123976X0180Y         S1      
327GND              PEX0  -D43        A01X+030216Y+124350X0180Y         S1      
327GND              PEX0  -E44        A01X+030590Y+123976X0180Y         S1      
327GND              PEX0  -E45        A01X+030964Y+123976X0180Y         S1      
327GND              PEX0  -J48        A01X+032087Y+122480X0180Y         S1      
327GND              PEX0  -J47        A01X+031712Y+122480X0180Y         S1      
327GND              PEX0  -L49        A01X+032461Y+121732X0180Y         S1      
327GND              PEX0  -L48        A01X+032087Y+121732X0180Y         S1      
327GND              PEX0  -K47        A01X+031712Y+122106X0180Y         S1      
327GND              PEX0  -K46        A01X+031338Y+122106X0180Y         S1      
327GND              PEX0  -H47        A01X+031712Y+122854X0180Y         S1      
327GND              PEX0  -J49        A01X+032461Y+122480X0180Y         S1      
327GND              PEX0  -G46        A01X+031338Y+123228X0180Y         S1      
327GND              PEX0  -G48        A01X+032087Y+123228X0180Y         S1      
327GND              PEX0  -F46        A01X+031338Y+123602X0180Y         S1      
327GND              PEX0  -C47        A01X+031712Y+124724X0180Y         S1      
327GND              PEX0  -E47        A01X+031712Y+123976X0180Y         S1      
327GND              PEX0  -D48        A01X+032087Y+124350X0180Y         S1      
327GND              PEX0  -D47        A01X+031712Y+124350X0180Y         S1      
327GND              PEX0  -E46        A01X+031338Y+123976X0180Y         S1      
327GND              PEX0  -D49        A01X+032461Y+124350X0180Y         S1      
327GND              PEX0  -B48        A01X+032087Y+125098X0180Y         S1      
327GND              PEX0  -A48        A01X+032087Y+125472X0180Y         S1      
327GND              PEX0  -B49        A01X+032461Y+125098X0180Y         S1      
327GND              PEX0  -D45        A01X+030964Y+124350X0180Y         S1      
327GND              PEX0  -E43        A01X+030216Y+123976X0180Y         S1      
327GND              PEX0  -B46        A01X+031338Y+125098X0180Y         S1      
327GND              PEX0  -A46        A01X+031338Y+125472X0180Y         S1      
327GND              PEX0  -C45        A01X+030964Y+124724X0180Y         S1      
327GND              PEX0  -A44        A01X+030590Y+125472X0180Y         S1      
327GND              PEX0  -M45        A01X+030964Y+121358X0180Y         S1      
327GND              PEX0  -N49        A01X+032461Y+120984X0180Y         S1      
327GND              PEX0  -N48        A01X+032087Y+120984X0180Y         S1      
327GND              PEX0  -M46        A01X+031338Y+121358X0180Y         S1      
327GND              PEX0  -M47        A01X+031712Y+121358X0180Y         S1      
327GND              PEX0  -N45        A01X+030964Y+120984X0180Y         S1      
327GND              PEX0  -P45        A01X+030964Y+120610X0180Y         S1      
327GND              PEX0  -P43        A01X+030216Y+120610X0180Y         S1      
327GND              PEX0  -M43        A01X+030216Y+121358X0180Y         S1      
327GND              PEX0  -F44        A01X+030590Y+123602X0180Y         S1      
327GND              PEX0  -G44        A01X+030590Y+123228X0180Y         S1      
327GND              PEX0  -R42        A01X+029842Y+120236X0180Y         S1      
327GND              PEX0  -T45        A01X+030964Y+119862X0180Y         S1      
327GND              PEX0  -R45        A01X+030964Y+120236X0180Y         S1      
327GND              PEX0  -D37        A01X+027972Y+124350X0180Y         S1      
327GND              PEX0  -E38        A01X+028346Y+123976X0180Y         S1      
327GND              PEX0  -E37        A01X+027972Y+123976X0180Y         S1      
327GND              PEX0  -D39        A01X+028720Y+124350X0180Y         S1      
327GND              PEX0  -E40        A01X+029094Y+123976X0180Y         S1      
327GND              PEX0  -E39        A01X+028720Y+123976X0180Y         S1      
327GND              PEX0  -B42        A01X+029842Y+125098X0180Y         S1      
327GND              PEX0  -A42        A01X+029842Y+125472X0180Y         S1      
327GND              PEX0  -C41        A01X+029468Y+124724X0180Y         S1      
327GND              PEX0  -C37        A01X+027972Y+124724X0180Y         S1      
327GND              PEX0  -B40        A01X+029094Y+125098X0180Y         S1      
327GND              PEX0  -C39        A01X+028720Y+124724X0180Y         S1      
327GND              PEX0  -A40        A01X+029094Y+125472X0180Y         S1      
327GND              PEX0  -M40        A01X+029094Y+121358X0180Y         S1      
327GND              PEX0  -N40        A01X+029094Y+120984X0180Y         S1      
327GND              PEX0  -J41        A01X+029468Y+122480X0180Y         S1      
327GND              PEX0  -J37        A01X+027972Y+122480X0180Y         S1      
327GND              PEX0  -G38        A01X+028346Y+123228X0180Y         S1      
327GND              PEX0  -AA40M      A01X+029094Y+117992X0180Y         S1      
327GND              PEX0  -AB39M      A01X+028720Y+117618X0180Y         S1      
327GND              PEX0  -AB40M      A01X+029094Y+117618X0180Y         S1      
327GND              PEX0  -U40        A01X+029094Y+119488X0180Y         S1      
327GND              PEX0  -AD40M      A01X+029094Y+116870X0180Y         S1      
327GND              PEX0  -E36        A01X+027598Y+123976X0180Y         S1      
327GND              PEX0  -E35        A01X+027224Y+123976X0180Y         S1      
327GND              PEX0  -D35        A01X+027224Y+124350X0180Y         S1      
327GND              PEX0  -E33        A01X+026476Y+123976X0180Y         S1      
327GND              PEX0  -D33        A01X+026476Y+124350X0180Y         S1      
327GND              PEX0  -E34        A01X+026850Y+123976X0180Y         S1      
327GND              PEX0  -C35        A01X+027224Y+124724X0180Y         S1      
327GND              PEX0  -A36        A01X+027598Y+125472X0180Y         S1      
327GND              PEX0  -H35        A01X+027224Y+122854X0180Y         S1      
327GND              PEX0  -B34        A01X+026850Y+125098X0180Y         S1      
327GND              PEX0  -A34        A01X+026850Y+125472X0180Y         S1      
327GND              PEX0  -E32        A01X+026102Y+123976X0180Y         S1      
327GND              PEX0  -E29        A01X+024980Y+123976X0180Y         S1      
327GND              PEX0  -E30        A01X+025354Y+123976X0180Y         S1      
327GND              PEX0  -D29        A01X+024980Y+124350X0180Y         S1      
327GND              PEX0  -E31        A01X+025728Y+123976X0180Y         S1      
327GND              PEX0  -D31        A01X+025728Y+124350X0180Y         S1      
327GND              PEX0  -B32        A01X+026102Y+125098X0180Y         S1      
327GND              PEX0  -A32        A01X+026102Y+125472X0180Y         S1      
327GND              PEX0  -K30        A01X+025354Y+122106X0180Y         S1      
327GND              PEX0  -K29        A01X+024980Y+122106X0180Y         S1      
327GND              PEX0  -K32        A01X+026102Y+122106X0180Y         S1      
327GND              PEX0  -K31        A01X+025728Y+122106X0180Y         S1      
327GND              PEX0  -H31        A01X+025728Y+122854X0180Y         S1      
327GND              PEX0  -G28        A01X+024606Y+123228X0180Y         S1      
327GND              PEX0  -F28        A01X+024606Y+123602X0180Y         S1      
327GND              PEX0  -J27        A01X+024232Y+122480X0180Y         S1      
327GND              PEX0  -B24        A01X+023110Y+125098X0180Y         S1      
327GND              PEX0  -C25        A01X+023484Y+124724X0180Y         S1      
327GND              PEX0  -A26        A01X+023858Y+125472X0180Y         S1      
327GND              PEX0  -B26        A01X+023858Y+125098X0180Y         S1      
327GND              PEX0  -B28        A01X+024606Y+125098X0180Y         S1      
327GND              PEX0  -A28        A01X+024606Y+125472X0180Y         S1      
327GND              PEX0  -A22        A01X+022362Y+125472X0180Y         S1      
327GND              PEX0  -B20        A01X+021614Y+125098X0180Y         S1      
327GND              PEX0  -C21        A01X+021988Y+124724X0180Y         S1      
327GND              PEX0  -H19        A01X+021240Y+122854X0180Y         S1      
327GND              PEX0  -G18        A01X+020866Y+123228X0180Y         S1      
327GND              PEX0  -H17        A01X+020492Y+122854X0180Y         S1      
327GND              PEX0  -F16        A01X+020118Y+123602X0180Y         S1      
327GND              PEX0  -E16        A01X+020118Y+123976X0180Y         S1      
327GND              PEX0  -E18        A01X+020866Y+123976X0180Y         S1      
327GND              PEX0  -F18        A01X+020866Y+123602X0180Y         S1      
327GND              PEX0  -E17        A01X+020492Y+123976X0180Y         S1      
327GND              PEX0  -B16        A01X+020118Y+125098X0180Y         S1      
327GND              PEX0  -A16        A01X+020118Y+125472X0180Y         S1      
327GND              PEX0  -A20        A01X+021614Y+125472X0180Y         S1      
327GND              PEX0  -E15        A01X+019744Y+123976X0180Y         S1      
327GND              PEX0  -D15        A01X+019744Y+124350X0180Y         S1      
327GND              PEX0  -E14        A01X+019370Y+123976X0180Y         S1      
327GND              PEX0  -C13        A01X+018996Y+124724X0180Y         S1      
327GND              PEX0  -A12        A01X+018622Y+125472X0180Y         S1      
327GND              PEX0  -B12        A01X+018622Y+125098X0180Y         S1      
327GND              PEX0  -C15        A01X+019744Y+124724X0180Y         S1      
327GND              PEX0  -A14        A01X+019370Y+125472X0180Y         S1      
327GND              PEX0  -B14        A01X+019370Y+125098X0180Y         S1      
327GND              PEX0  -K11        A01X+018248Y+122106X0180Y         S1      
327GND              PEX0  -L11        A01X+018248Y+121732X0180Y         S1      
327GND              PEX0  -K12        A01X+018622Y+122106X0180Y         S1      
327GND              PEX0  -H13        A01X+018996Y+122854X0180Y         S1      
327GND              PEX0  -G12        A01X+018622Y+123228X0180Y         S1      
327GND              PEX0  -C9         A01X+017500Y+124724X0180Y         S1      
327GND              PEX0  -B8         A01X+017126Y+125098X0180Y         S1      
327GND              PEX0  -K7         A01X+016752Y+122106X0180Y         S1      
327GND              PEX0  -K8         A01X+017126Y+122106X0180Y         S1      
327GND              PEX0  -K9         A01X+017500Y+122106X0180Y         S1      
327GND              PEX0  -L9         A01X+017500Y+121732X0180Y         S1      
327GND              PEX0  -L8         A01X+017126Y+121732X0180Y         S1      
327GND              PEX0  -L10        A01X+017874Y+121732X0180Y         S1      
327GND              PEX0  -P10        A01X+017874Y+120610X0180Y         S1      
327GND              PEX0  -N9         A01X+017500Y+120984X0180Y         S1      
327GND              PEX0  -N10        A01X+017874Y+120984X0180Y         S1      
327GND              PEX0  -R14 M      A01X+019370Y+120236X0180Y         S1      
327GND              PEX0  -R15 M      A01X+019744Y+120236X0180Y         S1      
327GND              PEX0  -M14        A01X+019370Y+121358X0180Y         S1      
327GND              PEX0  -N14        A01X+019370Y+120984X0180Y         S1      
327GND              PEX0  -N15 M      A01X+019744Y+120984X0180Y         S1      
327GND              PEX0  -P15 M      A01X+019744Y+120610X0180Y         S1      
327GND              PEX0  -R18 M      A01X+020866Y+120236X0180Y         S1      
327GND              PEX0  -N18 M      A01X+020866Y+120984X0180Y         S1      
327GND              PEX0  -P19 M      A01X+021240Y+120610X0180Y         S1      
327GND              PEX0  -R22 M      A01X+022362Y+120236X0180Y         S1      
327GND              PEX0  -P24 M      A01X+023110Y+120610X0180Y         S1      
327GND              PEX0  -P20 M      A01X+021614Y+120610X0180Y         S1      
327GND              PEX0  -N21 M      A01X+021988Y+120984X0180Y         S1      
327GND              PEX0  -N22 M      A01X+022362Y+120984X0180Y         S1      
327GND              PEX0  -P21 M      A01X+021988Y+120610X0180Y         S1      
327GND              PEX0  -P22 M      A01X+022362Y+120610X0180Y         S1      
327GND              PEX0  -P23 M      A01X+022736Y+120610X0180Y         S1      
327GND              PEX0  -N23 M      A01X+022736Y+120984X0180Y         S1      
327GND              PEX0  -N20 M      A01X+021614Y+120984X0180Y         S1      
327GND              PEX0  -N24        A01X+023110Y+120984X0180Y         S1      
327GND              PEX0  -R23 M      A01X+022736Y+120236X0180Y         S1      
327GND              PEX0  -R21 M      A01X+021988Y+120236X0180Y         S1      
327GND              PEX0  -R20 M      A01X+021614Y+120236X0180Y         S1      
327GND              PEX0  -R24        A01X+023110Y+120236X0180Y         S1      
327GND              PEX0  -R19 M      A01X+021240Y+120236X0180Y         S1      
327GND              PEX0  -N19 M      A01X+021240Y+120984X0180Y         S1      
327GND              PEX0  -N17 M      A01X+020492Y+120984X0180Y         S1      
327GND              PEX0  -P16 M      A01X+020118Y+120610X0180Y         S1      
327GND              PEX0  -R16 M      A01X+020118Y+120236X0180Y         S1      
327GND              PEX0  -R17 M      A01X+020492Y+120236X0180Y         S1      
327GND              PEX0  -P17 M      A01X+020492Y+120610X0180Y         S1      
327GND              PEX0  -P18 M      A01X+020866Y+120610X0180Y         S1      
327GND              PEX0  -N16 M      A01X+020118Y+120984X0180Y         S1      
327GND              PEX0  -P14 M      A01X+019370Y+120610X0180Y         S1      
327GND              PEX0  -P11        A01X+018248Y+120610X0180Y         S1      
327GND              PEX0  -P12        A01X+018622Y+120610X0180Y         S1      
327GND              PEX0  -P13 M      A01X+018996Y+120610X0180Y         S1      
327GND              PEX0  -N11        A01X+018248Y+120984X0180Y         S1      
327GND              PEX0  -N12        A01X+018622Y+120984X0180Y         S1      
327GND              PEX0  -N13        A01X+018996Y+120984X0180Y         S1      
327GND              PEX0  -M12        A01X+018622Y+121358X0180Y         S1      
327GND              PEX0  -M11        A01X+018248Y+121358X0180Y         S1      
327GND              PEX0  -R11        A01X+018248Y+120236X0180Y         S1      
327GND              PEX0  -R13 M      A01X+018996Y+120236X0180Y         S1      
327GND              PEX0  -T11        A01X+018248Y+119862X0180Y         S1      
327GND              PEX0  -T12 M      A01X+018622Y+119862X0180Y         S1      
327GND              PEX0  -T13 M      A01X+018996Y+119862X0180Y         S1      
327GND              PEX0  -U13 M      A01X+018996Y+119488X0180Y         S1      
327GND              PEX0  -U11 M      A01X+018248Y+119488X0180Y         S1      
327GND              PEX0  -U12 M      A01X+018622Y+119488X0180Y         S1      
327GND              PEX0  -V13        A01X+018996Y+119114X0180Y         S1      
327GND              PEX0  -V12 M      A01X+018622Y+119114X0180Y         S1      
327GND              PEX0  -V11 M      A01X+018248Y+119114X0180Y         S1      
327GND              PEX0  -Y13 M      A01X+018996Y+118366X0180Y         S1      
327GND              PEX0  -W12 M      A01X+018622Y+118740X0180Y         S1      
327GND              PEX0  -W13        A01X+018996Y+118740X0180Y         S1      
327GND              PEX0  -W11 M      A01X+018248Y+118740X0180Y         S1      
327GND              PEX0  -AA14M      A01X+019370Y+117992X0180Y         S1      
327GND              PEX0  -AB15M      A01X+019744Y+117618X0180Y         S1      
327GND              PEX0  -AE18       A01X+020866Y+116496X0180Y         S1      
327GND              PEX0  -AD17M      A01X+020492Y+116870X0180Y         S1      
327GND              PEX0  -AC16M      A01X+020118Y+117244X0180Y         S1      
327GND              PEX0  -M7         A01X+016752Y+121358X0180Y         S1      
327GND              PEX0  -U10        A01X+017874Y+119488X0180Y         S1      
327GND              PEX0  -T10        A01X+017874Y+119862X0180Y         S1      
327GND              PEX0  -R8         A01X+017126Y+120236X0180Y         S1      
327GND              PEX0  -T7         A01X+016752Y+119862X0180Y         S1      
327GND              PEX0  -U8         A01X+017126Y+119488X0180Y         S1      
327GND              PEX0  -AC9 M      A01X+017500Y+117244X0180Y         S1      
327GND              PEX0  -AD9 M      A01X+017500Y+116870X0180Y         S1      
327GND              PEX0  -D3         A01X+015256Y+124350X0180Y         S1      
327GND              PEX0  -E3         A01X+015256Y+123976X0180Y         S1      
327GND              PEX0  -E4         A01X+015630Y+123976X0180Y         S1      
327GND              PEX0  -C7         A01X+016752Y+124724X0180Y         S1      
327GND              PEX0  -T6         A01X+016378Y+119862X0180Y         S1      
327GND              PEX0  -K4         A01X+015630Y+122106X0180Y         S1      
327GND              PEX0  -K5         A01X+016004Y+122106X0180Y         S1      
327GND              PEX0  -K6         A01X+016378Y+122106X0180Y         S1      
327GND              PEX0  -L5         A01X+016004Y+121732X0180Y         S1      
327GND              PEX0  -M4         A01X+015630Y+121358X0180Y         S1      
327GND              PEX0  -M5         A01X+016004Y+121358X0180Y         S1      
327GND              PEX0  -M6         A01X+016378Y+121358X0180Y         S1      
327GND              PEX0  -N5         A01X+016004Y+120984X0180Y         S1      
327GND              PEX0  -M3         A01X+015256Y+121358X0180Y         S1      
327GND              PEX0  -K3         A01X+015256Y+122106X0180Y         S1      
327GND              PEX0  -F6         A01X+016378Y+123602X0180Y         S1      
327GND              PEX0  -H3         A01X+015256Y+122854X0180Y         S1      
327GND              PEX0  -G6         A01X+016378Y+123228X0180Y         S1      
327GND              PEX0  -U5         A01X+016004Y+119488X0180Y         S1      
327GND              PEX0  -T3         A01X+015256Y+119862X0180Y         S1      
327GND              PEX0  -P3         A01X+015256Y+120610X0180Y         S1      
327GND              PEX0  -N1         A01X+014508Y+120984X0180Y         S1      
327GND              PEX0  -F2         A01X+014882Y+123602X0180Y         S1      
327GND              PEX0  -G1         A01X+014508Y+123228X0180Y         S1      
327GND              PEX0  -J1         A01X+014508Y+122480X0180Y         S1      
327GND              PEX0  -D1         A01X+014508Y+124350X0180Y         S1      
327GND              PEX0  -BD10       A01X+017874Y+109390X0180Y         S1      
327GND              PEX0  -BH10       A01X+017874Y+107894X0180Y         S1      
327GND              PEX0  -BJ10       A01X+017874Y+107520X0180Y         S1      
327GND              PEX0  -BH8        A01X+017126Y+107894X0180Y         S1      
327GND              PEX0  -BJ8        A01X+017126Y+107520X0180Y         S1      
327GND              PEX0  -BE10       A01X+017874Y+109016X0180Y         S1      
327GND              PEX0  -BE8        A01X+017126Y+109016X0180Y         S1      
327GND              PEX0  -BF9        A01X+017500Y+108642X0180Y         S1      
327GND              PEX0  -BE9        A01X+017500Y+109016X0180Y         S1      
327GND              PEX0  -BA11       A01X+018248Y+110512X0180Y         S1      
327GND              PEX0  -AY10       A01X+017874Y+110886X0180Y         S1      
327GND              PEX0  -AW11       A01X+018248Y+111260X0180Y         S1      
327GND              PEX0  -BC14       A01X+019370Y+109764X0180Y         S1      
327GND              PEX0  -BB13       A01X+018996Y+110138X0180Y         S1      
327GND              PEX0  -BC12       A01X+018622Y+109764X0180Y         S1      
327GND              PEX0  -BB11       A01X+018248Y+110138X0180Y         S1      
327GND              PEX0  -BA15       A01X+019744Y+110512X0180Y         S1      
327GND              PEX0  -BB15       A01X+019744Y+110138X0180Y         S1      
327GND              PEX0  -BA13       A01X+018996Y+110512X0180Y         S1      
327GND              PEX0  -BD12       A01X+018622Y+109390X0180Y         S1      
327GND              PEX0  -BD14       A01X+019370Y+109390X0180Y         S1      
327GND              PEX0  -BH12       A01X+018622Y+107894X0180Y         S1      
327GND              PEX0  -BJ12       A01X+018622Y+107520X0180Y         S1      
327GND              PEX0  -BE15       A01X+019744Y+109016X0180Y         S1      
327GND              PEX0  -BF15       A01X+019744Y+108642X0180Y         S1      
327GND              PEX0  -AY15       A01X+019744Y+110886X0180Y         S1      
327GND              PEX0  -BJ20       A01X+021614Y+107520X0180Y         S1      
327GND              PEX0  -BF19       A01X+021240Y+108642X0180Y         S1      
327GND              PEX0  -BE19       A01X+021240Y+109016X0180Y         S1      
327GND              PEX0  -AR17M      A01X+020492Y+112756X0180Y         S1      
327GND              PEX0  -AR18M      A01X+020866Y+112756X0180Y         S1      
327GND              PEX0  -AR19M      A01X+021240Y+112756X0180Y         S1      
327GND              PEX0  -AT17M      A01X+020492Y+112382X0180Y         S1      
327GND              PEX0  -AT18M      A01X+020866Y+112382X0180Y         S1      
327GND              PEX0  -AU17M      A01X+020492Y+112008X0180Y         S1      
327GND              PEX0  -AU18M      A01X+020866Y+112008X0180Y         S1      
327GND              PEX0  -AU19M      A01X+021240Y+112008X0180Y         S1      
327GND              PEX0  -AT19M      A01X+021240Y+112382X0180Y         S1      
327GND              PEX0  -AY19       A01X+021240Y+110886X0180Y         S1      
327GND              PEX0  -AY18       A01X+020866Y+110886X0180Y         S1      
327GND              PEX0  -BA19       A01X+021240Y+110512X0180Y         S1      
327GND              PEX0  -BD20       A01X+021614Y+109390X0180Y         S1      
327GND              PEX0  -BH22       A01X+022362Y+107894X0180Y         S1      
327GND              PEX0  -BJ22       A01X+022362Y+107520X0180Y         S1      
327GND              PEX0  -BE22       A01X+022362Y+109016X0180Y         S1      
327GND              PEX0  -AR24       A01X+023110Y+112756X0180Y         S1      
327GND              PEX0  -AR22M      A01X+022362Y+112756X0180Y         S1      
327GND              PEX0  -AR20M      A01X+021614Y+112756X0180Y         S1      
327GND              PEX0  -AR21M      A01X+021988Y+112756X0180Y         S1      
327GND              PEX0  -AR23M      A01X+022736Y+112756X0180Y         S1      
327GND              PEX0  -AV24M      A01X+023110Y+111634X0180Y         S1      
327GND              PEX0  -AT22M      A01X+022362Y+112382X0180Y         S1      
327GND              PEX0  -AT20M      A01X+021614Y+112382X0180Y         S1      
327GND              PEX0  -AT21M      A01X+021988Y+112382X0180Y         S1      
327GND              PEX0  -AU21M      A01X+021988Y+112008X0180Y         S1      
327GND              PEX0  -AV20M      A01X+021614Y+111634X0180Y         S1      
327GND              PEX0  -AU20M      A01X+021614Y+112008X0180Y         S1      
327GND              PEX0  -AT23M      A01X+022736Y+112382X0180Y         S1      
327GND              PEX0  -AT24M      A01X+023110Y+112382X0180Y         S1      
327GND              PEX0  -AU24M      A01X+023110Y+112008X0180Y         S1      
327GND              PEX0  -AU23M      A01X+022736Y+112008X0180Y         S1      
327GND              PEX0  -AU22M      A01X+022362Y+112008X0180Y         S1      
327GND              PEX0  -AW20       A01X+021614Y+111260X0180Y         S1      
327GND              PEX0  -BC20       A01X+021614Y+109764X0180Y         S1      
327GND              PEX0  -BB21       A01X+021988Y+110138X0180Y         S1      
327GND              PEX0  -BA21       A01X+021988Y+110512X0180Y         S1      
327GND              PEX0  -AY21       A01X+021988Y+110886X0180Y         S1      
327GND              PEX0  -AY20       A01X+021614Y+110886X0180Y         S1      
327GND              PEX0  -AW24       A01X+023110Y+111260X0180Y         S1      
327GND              PEX0  -BD22       A01X+022362Y+109390X0180Y         S1      
327GND              PEX0  -BA23       A01X+022736Y+110512X0180Y         S1      
327GND              PEX0  -AY23       A01X+022736Y+110886X0180Y         S1      
327GND              PEX0  -AY22       A01X+022362Y+110886X0180Y         S1      
327GND              PEX0  -BB23       A01X+022736Y+110138X0180Y         S1      
327GND              PEX0  -BJ28       A01X+024606Y+107520X0180Y         S1      
327GND              PEX0  -BH28       A01X+024606Y+107894X0180Y         S1      
327GND              PEX0  -BD24       A01X+023110Y+109390X0180Y         S1      
327GND              PEX0  -AU28M      A01X+024606Y+112008X0180Y         S1      
327GND              PEX0  -AY28       A01X+024606Y+110886X0180Y         S1      
327GND              PEX0  -AU27M      A01X+024232Y+112008X0180Y         S1      
327GND              PEX0  -AT28M      A01X+024606Y+112382X0180Y         S1      
327GND              PEX0  -BA27       A01X+024232Y+110512X0180Y         S1      
327GND              PEX0  -AY26       A01X+023858Y+110886X0180Y         S1      
327GND              PEX0  -AY27       A01X+024232Y+110886X0180Y         S1      
327GND              PEX0  -BB27       A01X+024232Y+110138X0180Y         S1      
327GND              PEX0  -BC26       A01X+023858Y+109764X0180Y         S1      
327GND              PEX0  -BC24       A01X+023110Y+109764X0180Y         S1      
327GND              PEX0  -BB25       A01X+023484Y+110138X0180Y         S1      
327GND              PEX0  -BD26       A01X+023858Y+109390X0180Y         S1      
327GND              PEX0  -BG27       A01X+024232Y+108268X0180Y         S1      
327GND              PEX0  -BF25       A01X+023484Y+108642X0180Y         S1      
327GND              PEX0  -BE26       A01X+023858Y+109016X0180Y         S1      
327GND              PEX0  -BE25       A01X+023484Y+109016X0180Y         S1      
327GND              PEX0  -BE27       A01X+024232Y+109016X0180Y         S1      
327GND              PEX0  -BE28       A01X+024606Y+109016X0180Y         S1      
327GND              PEX0  -AJ27M      A01X+024232Y+115000X0180Y         S1      
327GND              PEX0  -AJ25       A01X+023484Y+115000X0180Y         S1      
327GND              PEX0  -AJ26M      A01X+023858Y+115000X0180Y         S1      
327GND              PEX0  -AL27M      A01X+024232Y+114252X0180Y         S1      
327GND              PEX0  -AL25       A01X+023484Y+114252X0180Y         S1      
327GND              PEX0  -AL26M      A01X+023858Y+114252X0180Y         S1      
327GND              PEX0  -AJ28M      A01X+024606Y+115000X0180Y         S1      
327GND              PEX0  -BC30       A01X+025354Y+109764X0180Y         S1      
327GND              PEX0  -BA29       A01X+024980Y+110512X0180Y         S1      
327GND              PEX0  -BA33       A01X+026476Y+110512X0180Y         S1      
327GND              PEX0  -BA31       A01X+025728Y+110512X0180Y         S1      
327GND              PEX0  -BD32       A01X+026102Y+109390X0180Y         S1      
327GND              PEX0  -BD30       A01X+025354Y+109390X0180Y         S1      
327GND              PEX0  -BH32       A01X+026102Y+107894X0180Y         S1      
327GND              PEX0  -BJ32       A01X+026102Y+107520X0180Y         S1      
327GND              PEX0  -BG31       A01X+025728Y+108268X0180Y         S1      
327GND              PEX0  -BE29       A01X+024980Y+109016X0180Y         S1      
327GND              PEX0  -BF31       A01X+025728Y+108642X0180Y         S1      
327GND              PEX0  -AL29M      A01X+024980Y+114252X0180Y         S1      
327GND              PEX0  -AL30M      A01X+025354Y+114252X0180Y         S1      
327GND              PEX0  -AL31M      A01X+025728Y+114252X0180Y         S1      
327GND              PEX0  -AL32M      A01X+026102Y+114252X0180Y         S1      
327GND              PEX0  -AR29M      A01X+024980Y+112756X0180Y         S1      
327GND              PEX0  -AR30M      A01X+025354Y+112756X0180Y         S1      
327GND              PEX0  -AR31M      A01X+025728Y+112756X0180Y         S1      
327GND              PEX0  -AR32M      A01X+026102Y+112756X0180Y         S1      
327GND              PEX0  -AT32M      A01X+026102Y+112382X0180Y         S1      
327GND              PEX0  -BB33       A01X+026476Y+110138X0180Y         S1      
327GND              PEX0  -BG33       A01X+026476Y+108268X0180Y         S1      
327GND              PEX0  -BJ34       A01X+026850Y+107520X0180Y         S1      
327GND              PEX0  -BH34       A01X+026850Y+107894X0180Y         S1      
327GND              PEX0  -BH36       A01X+027598Y+107894X0180Y         S1      
327GND              PEX0  -BJ36       A01X+027598Y+107520X0180Y         S1      
327GND              PEX0  -BG35       A01X+027224Y+108268X0180Y         S1      
327GND              PEX0  -AP37M      A01X+027972Y+113130X0180Y         S1      
327GND              PEX0  -AR37M      A01X+027972Y+112756X0180Y         S1      
327GND              PEX0  -AM36M      A01X+027598Y+113878X0180Y         S1      
327GND              PEX0  -AY33       A01X+026476Y+110886X0180Y         S1      
327GND              PEX0  -BA37       A01X+027972Y+110512X0180Y         S1      
327GND              PEX0  -AL33M      A01X+026476Y+114252X0180Y         S1      
327GND              PEX0  -AL34M      A01X+026850Y+114252X0180Y         S1      
327GND              PEX0  -AJ33M      A01X+026476Y+115000X0180Y         S1      
327GND              PEX0  -AH36M      A01X+027598Y+115374X0180Y         S1      
327GND              PEX0  -AJ36M      A01X+027598Y+115000X0180Y         S1      
327GND              PEX0  -AK34M      A01X+026850Y+114626X0180Y         S1      
327GND              PEX0  -AJ35M      A01X+027224Y+115000X0180Y         S1      
327GND              PEX0  -AH34M      A01X+026850Y+115374X0180Y         S1      
327GND              PEX0  -AG34       A01X+026850Y+115748X0180Y         S1      
327GND              PEX0  -AH35M      A01X+027224Y+115374X0180Y         S1      
327GND              PEX0  -AG35M      A01X+027224Y+115748X0180Y         S1      
327GND              PEX0  -AF35       A01X+027224Y+116122X0180Y         S1      
327GND              PEX0  -AJ34M      A01X+026850Y+115000X0180Y         S1      
327GND              PEX0  -AK36M      A01X+027598Y+114626X0180Y         S1      
327GND              PEX0  -AL36M      A01X+027598Y+114252X0180Y         S1      
327GND              PEX0  -AL37M      A01X+027972Y+114252X0180Y         S1      
327GND              PEX0  -AM37M      A01X+027972Y+113878X0180Y         S1      
327GND              PEX0  -AN37M      A01X+027972Y+113504X0180Y         S1      
327GND              PEX0  -BC38       A01X+028346Y+109764X0180Y         S1      
327GND              PEX0  -BA39       A01X+028720Y+110512X0180Y         S1      
327GND              PEX0  -BD40       A01X+029094Y+109390X0180Y         S1      
327GND              PEX0  -BD38       A01X+028346Y+109390X0180Y         S1      
327GND              PEX0  -BG41       A01X+029468Y+108268X0180Y         S1      
327GND              PEX0  -BJ42       A01X+029842Y+107520X0180Y         S1      
327GND              PEX0  -BH42       A01X+029842Y+107894X0180Y         S1      
327GND              PEX0  -AH37       A01X+027972Y+115374X0180Y         S1      
327GND              PEX0  -AH38M      A01X+028346Y+115374X0180Y         S1      
327GND              PEX0  -AJ37M      A01X+027972Y+115000X0180Y         S1      
327GND              PEX0  -AK37M      A01X+027972Y+114626X0180Y         S1      
327GND              PEX0  -AJ40M      A01X+029094Y+115000X0180Y         S1      
327GND              PEX0  -AH39M      A01X+028720Y+115374X0180Y         S1      
327GND              PEX0  -AL41M      A01X+029468Y+114252X0180Y         S1      
327GND              PEX0  -AJ41M      A01X+029468Y+115000X0180Y         S1      
327GND              PEX0  -AN40       A01X+029094Y+113504X0180Y         S1      
327GND              PEX0  -AM40       A01X+029094Y+113878X0180Y         S1      
327GND              PEX0  -AP40       A01X+029094Y+113130X0180Y         S1      
327GND              PEX0  -AR41       A01X+029468Y+112756X0180Y         S1      
327GND              PEX0  -AN41       A01X+029468Y+113504X0180Y         S1      
327GND              PEX0  -AV40       A01X+029094Y+111634X0180Y         S1      
327GND              PEX0  -AY39       A01X+028720Y+110886X0180Y         S1      
327GND              PEX0  -AY40       A01X+029094Y+110886X0180Y         S1      
327GND              PEX0  -AW40       A01X+029094Y+111260X0180Y         S1      
327GND              PEX0  -AY41       A01X+029468Y+110886X0180Y         S1      
327GND              PEX0  -AW41       A01X+029468Y+111260X0180Y         S1      
327GND              PEX0  -AU41M      A01X+029468Y+112008X0180Y         S1      
327GND              PEX0  -AG39M      A01X+028720Y+115748X0180Y         S1      
327GND              PEX0  -AF40M      A01X+029094Y+116122X0180Y         S1      
327GND              PEX0  -AF39       A01X+028720Y+116122X0180Y         S1      
327GND              PEX0  -AG40M      A01X+029094Y+115748X0180Y         S1      
327GND              PEX0  -AG41M      A01X+029468Y+115748X0180Y         S1      
327GND              PEX0  -BJ44       A01X+030590Y+107520X0180Y         S1      
327GND              PEX0  -AT47       A01X+031712Y+112382X0180Y         S1      
327GND              PEX0  -AT46       A01X+031338Y+112382X0180Y         S1      
327GND              PEX0  -AU49       A01X+032461Y+112008X0180Y         S1      
327GND              PEX0  -AU48       A01X+032087Y+112008X0180Y         S1      
327GND              PEX0  -AW49       A01X+032461Y+111260X0180Y         S1      
327GND              PEX0  -AV47       A01X+031712Y+111634X0180Y         S1      
327GND              PEX0  -AV46       A01X+031338Y+111634X0180Y         S1      
327GND              PEX0  -AW48       A01X+032087Y+111260X0180Y         S1      
327GND              PEX0  -BB45       A01X+030964Y+110138X0180Y         S1      
327GND              PEX0  -BC44       A01X+030590Y+109764X0180Y         S1      
327GND              PEX0  -BA43       A01X+030216Y+110512X0180Y         S1      
327GND              PEX0  -BD44       A01X+030590Y+109390X0180Y         S1      
327GND              PEX0  -BD42       A01X+029842Y+109390X0180Y         S1      
327GND              PEX0  -BG45       A01X+030964Y+108268X0180Y         S1      
327GND              PEX0  -BH46       A01X+031338Y+107894X0180Y         S1      
327GND              PEX0  -BJ46       A01X+031338Y+107520X0180Y         S1      
327GND              PEX0  -BE43       A01X+030216Y+109016X0180Y         S1      
327GND              PEX0  -BE44       A01X+030590Y+109016X0180Y         S1      
327GND              PEX0  -BF43       A01X+030216Y+108642X0180Y         S1      
327GND              PEX0  -BE42       A01X+029842Y+109016X0180Y         S1      
327GND              PEX0  -BC46       A01X+031338Y+109764X0180Y         S1      
327GND              PEX0  -BA49       A01X+032461Y+110512X0180Y         S1      
327GND              PEX0  -BB47       A01X+031712Y+110138X0180Y         S1      
327GND              PEX0  -BA47       A01X+031712Y+110512X0180Y         S1      
327GND              PEX0  -AY46       A01X+031338Y+110886X0180Y         S1      
327GND              PEX0  -AY47       A01X+031712Y+110886X0180Y         S1      
327GND              PEX0  -BA48       A01X+032087Y+110512X0180Y         S1      
327GND              PEX0  -BD46       A01X+031338Y+109390X0180Y         S1      
327GND              PEX0  -BF49       A01X+032461Y+108642X0180Y         S1      
327GND              PEX0  -BF47       A01X+031712Y+108642X0180Y         S1      
327GND              PEX0  -BE46       A01X+031338Y+109016X0180Y         S1      
327GND              PEX0  -BE47       A01X+031712Y+109016X0180Y         S1      
327GND              PEX0  -BG47       A01X+031712Y+108268X0180Y         S1      
327GND              PEX0  -BF48       A01X+032087Y+108642X0180Y         S1      
327GND              PEX0  -BH48       A01X+032087Y+107894X0180Y         S1      
327GND              PEX0  -BC48       A01X+032087Y+109764X0180Y         S1      
327GND              PEX0  -BD49       A01X+032461Y+109390X0180Y         S1      
327GND              PEX0  -BC49       A01X+032461Y+109764X0180Y         S1      
327GND              PEX0  -BD48       A01X+032087Y+109390X0180Y         S1      
327GND              PEX0  -BJ48       A01X+032087Y+107520X0180Y         S1      
327GND              PEX0  -BF45       A01X+030964Y+108642X0180Y         S1      
327GND              PEX0  -BE45       A01X+030964Y+109016X0180Y         S1      
327GND              PEX0  -BH44       A01X+030590Y+107894X0180Y         S1      
327GND              PEX0  -BG43       A01X+030216Y+108268X0180Y         S1      
327GND              PEX0  -AH45M      A01X+030964Y+115374X0180Y         S1      
327GND              PEX0  -AK44M      A01X+030590Y+114626X0180Y         S1      
327GND              PEX0  -AK45M      A01X+030964Y+114626X0180Y         S1      
327GND              PEX0  -AJ45M      A01X+030964Y+115000X0180Y         S1      
327GND              PEX0  -AP47       A01X+031712Y+113130X0180Y         S1      
327GND              PEX0  -AP46       A01X+031338Y+113130X0180Y         S1      
327GND              PEX0  -AR48       A01X+032087Y+112756X0180Y         S1      
327GND              PEX0  -AR49       A01X+032461Y+112756X0180Y         S1      
327GND              PEX0  -AP45       A01X+030964Y+113130X0180Y         S1      
327GND              PEX0  -AP44       A01X+030590Y+113130X0180Y         S1      
327GND              PEX0  -AN45       A01X+030964Y+113504X0180Y         S1      
327GND              PEX0  -AR42       A01X+029842Y+112756X0180Y         S1      
327GND              PEX0  -AV45       A01X+030964Y+111634X0180Y         S1      
327GND              PEX0  -AV44       A01X+030590Y+111634X0180Y         S1      
327GND              PEX0  -AU45       A01X+030964Y+112008X0180Y         S1      
327GND              PEX0  -AY42       A01X+029842Y+110886X0180Y         S1      
327GND              PEX0  -AW42       A01X+029842Y+111260X0180Y         S1      
327GND              PEX0  -AY43       A01X+030216Y+110886X0180Y         S1      
327GND              PEX0  -AV43       A01X+030216Y+111634X0180Y         S1      
327GND              PEX0  -AU42       A01X+029842Y+112008X0180Y         S1      
327GND              PEX0  -AY44       A01X+030590Y+110886X0180Y         S1      
327GND              PEX0  -AY45       A01X+030964Y+110886X0180Y         S1      
327GND              PEX0  -AW45       A01X+030964Y+111260X0180Y         S1      
327GND              PEX0  -AT44       A01X+030590Y+112382X0180Y         S1      
327GND              PEX0  -AT45       A01X+030964Y+112382X0180Y         S1      
327GND              PEX0  -AT43       A01X+030216Y+112382X0180Y         S1      
327GND              PEX0  -AR45       A01X+030964Y+112756X0180Y         S1      
327GND              PEX0  -AM44M      A01X+030590Y+113878X0180Y         S1      
327GND              PEX0  -AM45M      A01X+030964Y+113878X0180Y         S1      
327GND              PEX0  -AL45M      A01X+030964Y+114252X0180Y         S1      
327GND              PEX0  -AF45       A01X+030964Y+116122X0180Y         S1      
327GND              PEX0  -AG45M      A01X+030964Y+115748X0180Y         S1      
327GND              PEX0  -AF47M      A01X+031712Y+116122X0180Y         S1      
327GND              PEX0  -AF46M      A01X+031338Y+116122X0180Y         S1      
327GND              PEX0  -AH46M      A01X+031338Y+115374X0180Y         S1      
327GND              PEX0  -AG49M      A01X+032461Y+115748X0180Y         S1      
327GND              PEX0  -AG48M      A01X+032087Y+115748X0180Y         S1      
327GND              PEX0  -AH47M      A01X+031712Y+115374X0180Y         S1      
327GND              PEX0  -AJ49M      A01X+032461Y+115000X0180Y         S1      
327GND              PEX0  -AJ48M      A01X+032087Y+115000X0180Y         S1      
327GND              PEX0  -AK47M      A01X+031712Y+114626X0180Y         S1      
327GND              PEX0  -AL49M      A01X+032461Y+114252X0180Y         S1      
327GND              PEX0  -AL48M      A01X+032087Y+114252X0180Y         S1      
327GND              PEX0  -AN48       A01X+032087Y+113504X0180Y         S1      
327GND              PEX0  -AN49       A01X+032461Y+113504X0180Y         S1      
327GND              PEX0  -AM47M      A01X+031712Y+113878X0180Y         S1      
327GND              PEX0  -AM46M      A01X+031338Y+113878X0180Y         S1      
327GND              PEX0  -AK46M      A01X+031338Y+114626X0180Y         S1      
327GND              PEX0  -AM43M      A01X+030216Y+113878X0180Y         S1      
327GND              PEX0  -AL42M      A01X+029842Y+114252X0180Y         S1      
327GND              PEX0  -AP43       A01X+030216Y+113130X0180Y         S1      
327GND              PEX0  -AN42       A01X+029842Y+113504X0180Y         S1      
327GND              PEX0  -AK43M      A01X+030216Y+114626X0180Y         S1      
327GND              PEX0  -AJ42M      A01X+029842Y+115000X0180Y         S1      
327GND              PEX0  -AH44M      A01X+030590Y+115374X0180Y         S1      
327GND              PEX0  -AH43M      A01X+030216Y+115374X0180Y         S1      
327GND              PEX0  -AG42M      A01X+029842Y+115748X0180Y         S1      
327GND              PEX0  -AF43       A01X+030216Y+116122X0180Y         S1      
327GND              PEX0  -BA45       A01X+030964Y+110512X0180Y         S1      
327GND              PEX0  -BC42       A01X+029842Y+109764X0180Y         S1      
327GND              PEX0  -BB43       A01X+030216Y+110138X0180Y         S1      
327GND              PEX0  -AU40       A01X+029094Y+112008X0180Y         S1      
327GND              PEX0  -AT40       A01X+029094Y+112382X0180Y         S1      
327GND              PEX0  -AY38       A01X+028346Y+110886X0180Y         S1      
327GND              PEX0  -AY37       A01X+027972Y+110886X0180Y         S1      
327GND              PEX0  -AR40       A01X+029094Y+112756X0180Y         S1      
327GND              PEX0  -AH40M      A01X+029094Y+115374X0180Y         S1      
327GND              PEX0  -AL40M      A01X+029094Y+114252X0180Y         S1      
327GND              PEX0  -AK40M      A01X+029094Y+114626X0180Y         S1      
327GND              PEX0  -BE41       A01X+029468Y+109016X0180Y         S1      
327GND              PEX0  -BF41       A01X+029468Y+108642X0180Y         S1      
327GND              PEX0  -BF37       A01X+027972Y+108642X0180Y         S1      
327GND              PEX0  -BE40       A01X+029094Y+109016X0180Y         S1      
327GND              PEX0  -BF39       A01X+028720Y+108642X0180Y         S1      
327GND              PEX0  -BE38       A01X+028346Y+109016X0180Y         S1      
327GND              PEX0  -BE39       A01X+028720Y+109016X0180Y         S1      
327GND              PEX0  -BE37       A01X+027972Y+109016X0180Y         S1      
327GND              PEX0  -BH40       A01X+029094Y+107894X0180Y         S1      
327GND              PEX0  -BJ40       A01X+029094Y+107520X0180Y         S1      
327GND              PEX0  -BG39       A01X+028720Y+108268X0180Y         S1      
327GND              PEX0  -BH38       A01X+028346Y+107894X0180Y         S1      
327GND              PEX0  -BJ38       A01X+028346Y+107520X0180Y         S1      
327GND              PEX0  -BG37       A01X+027972Y+108268X0180Y         S1      
327GND              PEX0  -BA41       A01X+029468Y+110512X0180Y         S1      
327GND              PEX0  -BB41       A01X+029468Y+110138X0180Y         S1      
327GND              PEX0  -BB37       A01X+027972Y+110138X0180Y         S1      
327GND              PEX0  -BB39       A01X+028720Y+110138X0180Y         S1      
327GND              PEX0  -BC40       A01X+029094Y+109764X0180Y         S1      
327GND              PEX0  -AY36       A01X+027598Y+110886X0180Y         S1      
327GND              PEX0  -BC36       A01X+027598Y+109764X0180Y         S1      
327GND              PEX0  -BD36       A01X+027598Y+109390X0180Y         S1      
327GND              PEX0  -AY34       A01X+026850Y+110886X0180Y         S1      
327GND              PEX0  -BA35       A01X+027224Y+110512X0180Y         S1      
327GND              PEX0  -AY35       A01X+027224Y+110886X0180Y         S1      
327GND              PEX0  -BB35       A01X+027224Y+110138X0180Y         S1      
327GND              PEX0  -AR35       A01X+027224Y+112756X0180Y         S1      
327GND              PEX0  -AR33M      A01X+026476Y+112756X0180Y         S1      
327GND              PEX0  -AR34M      A01X+026850Y+112756X0180Y         S1      
327GND              PEX0  -AT37M      A01X+027972Y+112382X0180Y         S1      
327GND              PEX0  -AU36M      A01X+027598Y+112008X0180Y         S1      
327GND              PEX0  -AT35M      A01X+027224Y+112382X0180Y         S1      
327GND              PEX0  -AT33M      A01X+026476Y+112382X0180Y         S1      
327GND              PEX0  -AU35M      A01X+027224Y+112008X0180Y         S1      
327GND              PEX0  -AT34M      A01X+026850Y+112382X0180Y         S1      
327GND              PEX0  -AU34M      A01X+026850Y+112008X0180Y         S1      
327GND              PEX0  -AU33M      A01X+026476Y+112008X0180Y         S1      
327GND              PEX0  -AU37M      A01X+027972Y+112008X0180Y         S1      
327GND              PEX0  -AP34       A01X+026850Y+113130X0180Y         S1      
327GND              PEX0  -BE36       A01X+027598Y+109016X0180Y         S1      
327GND              PEX0  -BE33       A01X+026476Y+109016X0180Y         S1      
327GND              PEX0  -BE34       A01X+026850Y+109016X0180Y         S1      
327GND              PEX0  -BF33       A01X+026476Y+108642X0180Y         S1      
327GND              PEX0  -BE35       A01X+027224Y+109016X0180Y         S1      
327GND              PEX0  -BF35       A01X+027224Y+108642X0180Y         S1      
327GND              PEX0  -BC34       A01X+026850Y+109764X0180Y         S1      
327GND              PEX0  -BD34       A01X+026850Y+109390X0180Y         S1      
327GND              PEX0  -AU32M      A01X+026102Y+112008X0180Y         S1      
327GND              PEX0  -AU29M      A01X+024980Y+112008X0180Y         S1      
327GND              PEX0  -AT31M      A01X+025728Y+112382X0180Y         S1      
327GND              PEX0  -AU30M      A01X+025354Y+112008X0180Y         S1      
327GND              PEX0  -AU31M      A01X+025728Y+112008X0180Y         S1      
327GND              PEX0  -AT29M      A01X+024980Y+112382X0180Y         S1      
327GND              PEX0  -AT30M      A01X+025354Y+112382X0180Y         S1      
327GND              PEX0  -AY32       A01X+026102Y+110886X0180Y         S1      
327GND              PEX0  -AY30       A01X+025354Y+110886X0180Y         S1      
327GND              PEX0  -AY31       A01X+025728Y+110886X0180Y         S1      
327GND              PEX0  -AY29       A01X+024980Y+110886X0180Y         S1      
327GND              PEX0  -AJ32M      A01X+026102Y+115000X0180Y         S1      
327GND              PEX0  -AJ29M      A01X+024980Y+115000X0180Y         S1      
327GND              PEX0  -AJ30M      A01X+025354Y+115000X0180Y         S1      
327GND              PEX0  -AJ31M      A01X+025728Y+115000X0180Y         S1      
327GND              PEX0  -BE32       A01X+026102Y+109016X0180Y         S1      
327GND              PEX0  -BE30       A01X+025354Y+109016X0180Y         S1      
327GND              PEX0  -BE31       A01X+025728Y+109016X0180Y         S1      
327GND              PEX0  -BF29       A01X+024980Y+108642X0180Y         S1      
327GND              PEX0  -BH30       A01X+025354Y+107894X0180Y         S1      
327GND              PEX0  -BJ30       A01X+025354Y+107520X0180Y         S1      
327GND              PEX0  -BG29       A01X+024980Y+108268X0180Y         S1      
327GND              PEX0  -BB31       A01X+025728Y+110138X0180Y         S1      
327GND              PEX0  -BC32       A01X+026102Y+109764X0180Y         S1      
327GND              PEX0  -BB29       A01X+024980Y+110138X0180Y         S1      
327GND              PEX0  -AR28M      A01X+024606Y+112756X0180Y         S1      
327GND              PEX0  -AR25       A01X+023484Y+112756X0180Y         S1      
327GND              PEX0  -AR26M      A01X+023858Y+112756X0180Y         S1      
327GND              PEX0  -AR27M      A01X+024232Y+112756X0180Y         S1      
327GND              PEX0  -AL28M      A01X+024606Y+114252X0180Y         S1      
327GND              PEX0  -BF27       A01X+024232Y+108642X0180Y         S1      
327GND              PEX0  -BC28       A01X+024606Y+109764X0180Y         S1      
327GND              PEX0  -BD28       A01X+024606Y+109390X0180Y         S1      
327GND              PEX0  -BA25       A01X+023484Y+110512X0180Y         S1      
327GND              PEX0  -AY25       A01X+023484Y+110886X0180Y         S1      
327GND              PEX0  -AY24       A01X+023110Y+110886X0180Y         S1      
327GND              PEX0  -AU25       A01X+023484Y+112008X0180Y         S1      
327GND              PEX0  -AT25M      A01X+023484Y+112382X0180Y         S1      
327GND              PEX0  -AT26M      A01X+023858Y+112382X0180Y         S1      
327GND              PEX0  -AU26M      A01X+023858Y+112008X0180Y         S1      
327GND              PEX0  -AT27M      A01X+024232Y+112382X0180Y         S1      
327GND              PEX0  -BC22       A01X+022362Y+109764X0180Y         S1      
327GND              PEX0  -BE23       A01X+022736Y+109016X0180Y         S1      
327GND              PEX0  -BE24       A01X+023110Y+109016X0180Y         S1      
327GND              PEX0  -BF23       A01X+022736Y+108642X0180Y         S1      
327GND              PEX0  -BE20       A01X+021614Y+109016X0180Y         S1      
327GND              PEX0  -BF21       A01X+021988Y+108642X0180Y         S1      
327GND              PEX0  -BE21       A01X+021988Y+109016X0180Y         S1      
327GND              PEX0  -BG23       A01X+022736Y+108268X0180Y         S1      
327GND              PEX0  -BG21       A01X+021988Y+108268X0180Y         S1      
327GND              PEX0  -BH20       A01X+021614Y+107894X0180Y         S1      
327GND              PEX0  -BB19       A01X+021240Y+110138X0180Y         S1      
327GND              PEX0  -BD18       A01X+020866Y+109390X0180Y         S1      
327GND              PEX0  -BC18       A01X+020866Y+109764X0180Y         S1      
327GND              PEX0  -BB17       A01X+020492Y+110138X0180Y         S1      
327GND              PEX0  -BC16       A01X+020118Y+109764X0180Y         S1      
327GND              PEX0  -BD16       A01X+020118Y+109390X0180Y         S1      
327GND              PEX0  -BA17       A01X+020492Y+110512X0180Y         S1      
327GND              PEX0  -AY16       A01X+020118Y+110886X0180Y         S1      
327GND              PEX0  -AY17       A01X+020492Y+110886X0180Y         S1      
327GND              PEX0  -BE18       A01X+020866Y+109016X0180Y         S1      
327GND              PEX0  -BE17       A01X+020492Y+109016X0180Y         S1      
327GND              PEX0  -BF17       A01X+020492Y+108642X0180Y         S1      
327GND              PEX0  -BE16       A01X+020118Y+109016X0180Y         S1      
327GND              PEX0  -BG19       A01X+021240Y+108268X0180Y         S1      
327GND              PEX0  -BH18       A01X+020866Y+107894X0180Y         S1      
327GND              PEX0  -BJ18       A01X+020866Y+107520X0180Y         S1      
327GND              PEX0  -BG17       A01X+020492Y+108268X0180Y         S1      
327GND              PEX0  -BH16       A01X+020118Y+107894X0180Y         S1      
327GND              PEX0  -BJ16       A01X+020118Y+107520X0180Y         S1      
327GND              PEX0  -AY14       A01X+019370Y+110886X0180Y         S1      
327GND              PEX0  -AY13       A01X+018996Y+110886X0180Y         S1      
327GND              PEX0  -AY12       A01X+018622Y+110886X0180Y         S1      
327GND              PEX0  -AY11       A01X+018248Y+110886X0180Y         S1      
327GND              PEX0  -BF11       A01X+018248Y+108642X0180Y         S1      
327GND              PEX0  -BE11       A01X+018248Y+109016X0180Y         S1      
327GND              PEX0  -BE12       A01X+018622Y+109016X0180Y         S1      
327GND              PEX0  -BE14       A01X+019370Y+109016X0180Y         S1      
327GND              PEX0  -BE13       A01X+018996Y+109016X0180Y         S1      
327GND              PEX0  -BF13       A01X+018996Y+108642X0180Y         S1      
327GND              PEX0  -BG13       A01X+018996Y+108268X0180Y         S1      
327GND              PEX0  -BG15       A01X+019744Y+108268X0180Y         S1      
327GND              PEX0  -BJ14       A01X+019370Y+107520X0180Y         S1      
327GND              PEX0  -BH14       A01X+019370Y+107894X0180Y         S1      
327GND              PEX0  -BC10       A01X+017874Y+109764X0180Y         S1      
327GND              PEX0  -BB9        A01X+017500Y+110138X0180Y         S1      
327GND              PEX0  -BA9        A01X+017500Y+110512X0180Y         S1      
327GND              PEX0  -AY9        A01X+017500Y+110886X0180Y         S1      
327GND              PEX0  -AW10       A01X+017874Y+111260X0180Y         S1      
327GND              PEX0  -BG9        A01X+017500Y+108268X0180Y         S1      
327GND              PEX0  -BC8        A01X+017126Y+109764X0180Y         S1      
327GND              PEX0  -BD8        A01X+017126Y+109390X0180Y         S1      
327GND              PEX0  -BG11       A01X+018248Y+108268X0180Y         S1      
327GND              PEX0  -N26 M      A01X+023858Y+120984X0180Y         S1      
327GND              PEX0  -N27 M      A01X+024232Y+120984X0180Y         S1      
327GND              PEX0  -N28 M      A01X+024606Y+120984X0180Y         S1      
327GND              PEX0  -N25        A01X+023484Y+120984X0180Y         S1      
327GND              PEX0  -P25 M      A01X+023484Y+120610X0180Y         S1      
327GND              PEX0  -P26 M      A01X+023858Y+120610X0180Y         S1      
327GND              PEX0  -R26 M      A01X+023858Y+120236X0180Y         S1      
327GND              PEX0  -R25        A01X+023484Y+120236X0180Y         S1      
327GND              PEX0  -P27 M      A01X+024232Y+120610X0180Y         S1      
327GND              PEX0  -R27 M      A01X+024232Y+120236X0180Y         S1      
327GND              PEX0  -P28 M      A01X+024606Y+120610X0180Y         S1      
327GND              PEX0  -U28 M      A01X+024606Y+119488X0180Y         S1      
327GND              PEX0  -W27 M      A01X+024232Y+118740X0180Y         S1      
327GND              PEX0  -W25        A01X+023484Y+118740X0180Y         S1      
327GND              PEX0  -W26 M      A01X+023858Y+118740X0180Y         S1      
327GND              PEX0  -W28 M      A01X+024606Y+118740X0180Y         S1      
327GND              PEX0  -U31 M      A01X+025728Y+119488X0180Y         S1      
327GND              PEX0  -U29 M      A01X+024980Y+119488X0180Y         S1      
327GND              PEX0  -U30 M      A01X+025354Y+119488X0180Y         S1      
327GND              PEX0  -U32 M      A01X+026102Y+119488X0180Y         S1      
327GND              PEX0  -R32 M      A01X+026102Y+120236X0180Y         S1      
327GND              PEX0  -R31        A01X+025728Y+120236X0180Y         S1      
327GND              PEX0  -R30 M      A01X+025354Y+120236X0180Y         S1      
327GND              PEX0  -P29 M      A01X+024980Y+120610X0180Y         S1      
327GND              PEX0  -P30 M      A01X+025354Y+120610X0180Y         S1      
327GND              PEX0  -P31 M      A01X+025728Y+120610X0180Y         S1      
327GND              PEX0  -N30 M      A01X+025354Y+120984X0180Y         S1      
327GND              PEX0  -N31 M      A01X+025728Y+120984X0180Y         S1      
327GND              PEX0  -N32 M      A01X+026102Y+120984X0180Y         S1      
327GND              PEX0  -P32 M      A01X+026102Y+120610X0180Y         S1      
327GND              PEX0  -V34 M      A01X+026850Y+119114X0180Y         S1      
327GND              PEX0  -W33 M      A01X+026476Y+118740X0180Y         S1      
327GND              PEX0  -W34 M      A01X+026850Y+118740X0180Y         S1      
327GND              PEX0  -U35 M      A01X+027224Y+119488X0180Y         S1      
327GND              PEX0  -U34 M      A01X+026850Y+119488X0180Y         S1      
327GND              PEX0  -T34 M      A01X+026850Y+119862X0180Y         S1      
327GND              PEX0  -R33 M      A01X+026476Y+120236X0180Y         S1      
327GND              PEX0  -R34 M      A01X+026850Y+120236X0180Y         S1      
327GND              PEX0  -R37        A01X+027972Y+120236X0180Y         S1      
327GND              PEX0  -P37        A01X+027972Y+120610X0180Y         S1      
327GND              PEX0  -N37        A01X+027972Y+120984X0180Y         S1      
327GND              PEX0  -N33 M      A01X+026476Y+120984X0180Y         S1      
327GND              PEX0  -P33 M      A01X+026476Y+120610X0180Y         S1      
327GND              PEX0  -N36 M      A01X+027598Y+120984X0180Y         S1      
327GND              PEX0  -N34 M      A01X+026850Y+120984X0180Y         S1      
327GND              PEX0  -N35 M      A01X+027224Y+120984X0180Y         S1      
327GND              PEX0  -P34 M      A01X+026850Y+120610X0180Y         S1      
327GND              PEX0  -P35 M      A01X+027224Y+120610X0180Y         S1      
327GND              PEX0  -R35 M      A01X+027224Y+120236X0180Y         S1      
327GND              PEX0  -U33 M      A01X+026476Y+119488X0180Y         S1      
327GND              PEX0  -N29 M      A01X+024980Y+120984X0180Y         S1      
327GND              PEX0  -R29 M      A01X+024980Y+120236X0180Y         S1      
327GND              PEX0  -W31 M      A01X+025728Y+118740X0180Y         S1      
327GND              PEX0  -W29 M      A01X+024980Y+118740X0180Y         S1      
327GND              PEX0  -W30 M      A01X+025354Y+118740X0180Y         S1      
327GND              PEX0  -W32 M      A01X+026102Y+118740X0180Y         S1      
327GND              PEX0  -R28 M      A01X+024606Y+120236X0180Y         S1      
327GND              PEX0  -U25        A01X+023484Y+119488X0180Y         S1      
327GND              PEX0  -U26 M      A01X+023858Y+119488X0180Y         S1      
327GND              PEX0  -U27 M      A01X+024232Y+119488X0180Y         S1      
327GND              PEX0  -AD35M      A01X+027224Y+116870X0180Y         S1      
327GND              PEX0  -AE35       A01X+027224Y+116496X0180Y         S1      
327GND              PEX0  -AB36M      A01X+027598Y+117618X0180Y         S1      
327GND              PEX0  -V36 M      A01X+027598Y+119114X0180Y         S1      
327GND              PEX0  -W36 M      A01X+027598Y+118740X0180Y         S1      
327GND              PEX0  -AA36M      A01X+027598Y+117992X0180Y         S1      
327GND              PEX0  -AC37M      A01X+027972Y+117244X0180Y         S1      
327GND              PEX0  -V38 M      A01X+028346Y+119114X0180Y         S1      
327GND              PEX0  -Y37 M      A01X+027972Y+118366X0180Y         S1      
327GND              PEX0  -Y38 M      A01X+028346Y+118366X0180Y         S1      
327GND              PEX0  -W37 M      A01X+027972Y+118740X0180Y         S1      
327GND              PEX0  -V37 M      A01X+027972Y+119114X0180Y         S1      
327GND              PEX0  -AB38M      A01X+028346Y+117618X0180Y         S1      
327GND              PEX0  -AB37M      A01X+027972Y+117618X0180Y         S1      
327GND              PEX0  -AA38M      A01X+028346Y+117992X0180Y         S1      
327GND              PEX0  -U37 M      A01X+027972Y+119488X0180Y         S1      
327GND              PEX0  -T37        A01X+027972Y+119862X0180Y         S1      
327GND              PEX0  -AD37M      A01X+027972Y+116870X0180Y         S1      
327GND              PEX0  -AE37       A01X+027972Y+116496X0180Y         S1      
327GND              PEX0  -Y36 M      A01X+027598Y+118366X0180Y         S1      
327GND              PEX0  -AC34       A01X+026850Y+117244X0180Y         S1      
327GND              PEX0  -AC35M      A01X+027224Y+117244X0180Y         S1      
327GND              PEX0  -AB34M      A01X+026850Y+117618X0180Y         S1      
327GND              R1244 -2          A18X+029144Y+118711X0198Y0197R270 S2      
327GND              C1101 -2          A18X+022320Y+116229X0280Y0320R090 S2      
327GND              PEX0  -V15 M      A01X+019744Y+119114X0180Y         S1      
327GND              PEX0  -W14 M      A01X+019370Y+118740X0180Y         S1      
327GND              PEX0  -W15 M      A01X+019744Y+118740X0180Y         S1      
327GND              PEX0  -W18 M      A01X+020866Y+118740X0180Y         S1      
327GND              PEX0  -W17 M      A01X+020492Y+118740X0180Y         S1      
327GND              PEX0  -W16 M      A01X+020118Y+118740X0180Y         S1      
327GND              PEX0  -W22 M      A01X+022362Y+118740X0180Y         S1      
327GND              PEX0  -W23 M      A01X+022736Y+118740X0180Y         S1      
327GND              PEX0  -W21 M      A01X+021988Y+118740X0180Y         S1      
327GND              PEX0  -W20 M      A01X+021614Y+118740X0180Y         S1      
327GND              PEX0  -W24        A01X+023110Y+118740X0180Y         S1      
327GND              PEX0  -W19 M      A01X+021240Y+118740X0180Y         S1      
327GND              PEX0  -Y15 M      A01X+019744Y+118366X0180Y         S1      
327GND              PEX0  -AA18M      A01X+020866Y+117992X0180Y         S1      
327GND              PEX0  -AA17M      A01X+020492Y+117992X0180Y         S1      
327GND              PEX0  -AA16M      A01X+020118Y+117992X0180Y         S1      
327GND              PEX0  -AA23M      A01X+022736Y+117992X0180Y         S1      
327GND              PEX0  -AA22M      A01X+022362Y+117992X0180Y         S1      
327GND              PEX0  -AA21M      A01X+021988Y+117992X0180Y         S1      
327GND              PEX0  -AA20M      A01X+021614Y+117992X0180Y         S1      
327GND              PEX0  -AA24       A01X+023110Y+117992X0180Y         S1      
327GND              PEX0  -AA19M      A01X+021240Y+117992X0180Y         S1      
327GND              PEX0  -T15 M      A01X+019744Y+119862X0180Y         S1      
327GND              PEX0  -U18 M      A01X+020866Y+119488X0180Y         S1      
327GND              PEX0  -U17 M      A01X+020492Y+119488X0180Y         S1      
327GND              PEX0  -U16 M      A01X+020118Y+119488X0180Y         S1      
327GND              PEX0  -U19 M      A01X+021240Y+119488X0180Y         S1      
327GND              PEX0  -U21 M      A01X+021988Y+119488X0180Y         S1      
327GND              PEX0  -U23 M      A01X+022736Y+119488X0180Y         S1      
327GND              PEX0  -U24        A01X+023110Y+119488X0180Y         S1      
327GND              PEX0  -U22 M      A01X+022362Y+119488X0180Y         S1      
327GND              PEX0  -U20 M      A01X+021614Y+119488X0180Y         S1      
327GND              PEX0  -U15 M      A01X+019744Y+119488X0180Y         S1      
327GND              PEX0  -AL13       A01X+018996Y+114252X0180Y         S1      
327GND              PEX0  -AL12       A01X+018622Y+114252X0180Y         S1      
327GND              PEX0  -AL10       A01X+017874Y+114252X0180Y         S1      
327GND              PEX0  -AL9        A01X+017500Y+114252X0180Y         S1      
327GND              PEX0  -AL8        A01X+017126Y+114252X0180Y         S1      
327GND              PEX0  -AL11       A01X+018248Y+114252X0180Y         S1      
327GND              PEX0  -BD4        A01X+015630Y+109390X0180Y         S1      
327GND              PEX0  -BD6        A01X+016378Y+109390X0180Y         S1      
327GND              PEX0  -AL6        A01X+016378Y+114252X0180Y         S1      
327GND              PEX0  -AL4        A01X+015630Y+114252X0180Y         S1      
327GND              PEX0  -AL3        A01X+015256Y+114252X0180Y         S1      
327GND              PEX0  -AL7        A01X+016752Y+114252X0180Y         S1      
327GND              PEX0  -AL5        A01X+016004Y+114252X0180Y         S1      
327GND              PEX0  -AL2        A01X+014882Y+114252X0180Y         S1      
327GND              PEX0  -AL1        A01X+014508Y+114252X0180Y         S1      
327GND              PEX0  -BD1        A01X+014508Y+109390X0180Y         S1      
327GND              PEX0  -BD2        A01X+014882Y+109390X0180Y         S1      
327GND              R3441 -2          A18X+005996Y+089750X0198Y0197R180 S2      
327GND              PC210 -2          A01X+004496Y+119326X0198Y0197     S1      
327GND              C625  -2          A01X+004062Y+109376X0198Y0197R180 S1      
327GND              U317  -10  M      A01X+005850Y+090030X0320Y0750R270 S1      
327GND              JPEX0 -10         A01X+005913Y+090030X0200Y0600R090 S1      
327GND              C2081 -2          A18X+133738Y+085979X0164Y0164R090 S2      
327GND              PC264 -2          A01X+179110Y+125794X0198Y0197R180 S1      
327GND              C631  -2          A01X+179526Y+110325X0198Y0197R180 S1      
327GND              R1451 -1          A01X+172566Y+119542X0198Y0197R090 S1      
327GND              PEX3  -AB1 M      A01X+151634Y+117618X0180Y         S1      
327GND              PEX3  -AB3 M      A01X+152382Y+117618X0180Y         S1      
327GND              PEX3  -AB2 M      A01X+152008Y+117618X0180Y         S1      
327GND              PEX3  -AC3 M      A01X+152382Y+117244X0180Y         S1      
327GND              PEX3  -AC4 M      A01X+152756Y+117244X0180Y         S1      
327GND              PEX3  -AA3 M      A01X+152382Y+117992X0180Y         S1      
327GND              PEX3  -AA4 M      A01X+152756Y+117992X0180Y         S1      
327GND              PEX3  -AE9        A01X+154626Y+116496X0180Y         S1      
327GND              PEX3  -AB6 M      A01X+153504Y+117618X0180Y         S1      
327GND              PEX3  -AC5 M      A01X+153130Y+117244X0180Y         S1      
327GND              PEX3  -AC6 M      A01X+153504Y+117244X0180Y         S1      
327GND              PEX3  -AA6 M      A01X+153504Y+117992X0180Y         S1      
327GND              PEX3  -AA7 M      A01X+153878Y+117992X0180Y         S1      
327GND              PEX3  -AA9 M      A01X+154626Y+117992X0180Y         S1      
327GND              PEX3  -AA8 M      A01X+154252Y+117992X0180Y         S1      
327GND              PEX3  -AA5 M      A01X+153130Y+117992X0180Y         S1      
327GND              PEX3  -AD9 M      A01X+154626Y+116870X0180Y         S1      
327GND              PEX3  -AE16       A01X+157244Y+116496X0180Y         S1      
327GND              PEX3  -AD15M      A01X+156870Y+116870X0180Y         S1      
327GND              PEX3  -AC14M      A01X+156496Y+117244X0180Y         S1      
327GND              PEX3  -AE18       A01X+157992Y+116496X0180Y         S1      
327GND              PEX3  -AD17M      A01X+157618Y+116870X0180Y         S1      
327GND              PEX3  -AC16M      A01X+157244Y+117244X0180Y         S1      
327GND              PEX3  -AA14M      A01X+156496Y+117992X0180Y         S1      
327GND              PEX3  -AB15M      A01X+156870Y+117618X0180Y         S1      
327GND              PEX3  -AB13M      A01X+156122Y+117618X0180Y         S1      
327GND              PEX3  -AB11M      A01X+155374Y+117618X0180Y         S1      
327GND              PEX3  -AE14       A01X+156496Y+116496X0180Y         S1      
327GND              PEX3  -AE12       A01X+155748Y+116496X0180Y         S1      
327GND              PEX3  -AD13M      A01X+156122Y+116870X0180Y         S1      
327GND              PEX3  -AC12M      A01X+155748Y+117244X0180Y         S1      
327GND              PEX3  -AC11M      A01X+155374Y+117244X0180Y         S1      
327GND              PEX3  -AE11       A01X+155374Y+116496X0180Y         S1      
327GND              PEX3  -AD10M      A01X+155000Y+116870X0180Y         S1      
327GND              PEX3  -AD11M      A01X+155374Y+116870X0180Y         S1      
327GND              PEX3  -AA11M      A01X+155374Y+117992X0180Y         S1      
327GND              PEX3  -W13        A01X+156122Y+118740X0180Y         S1      
327GND              PEX3  -Y13 M      A01X+156122Y+118366X0180Y         S1      
327GND              PEX3  -W12 M      A01X+155748Y+118740X0180Y         S1      
327GND              PEX3  -W10        A01X+155000Y+118740X0180Y         S1      
327GND              PEX3  -W11 M      A01X+155374Y+118740X0180Y         S1      
327GND              PEX3  -Y11 M      A01X+155374Y+118366X0180Y         S1      
327GND              PEX3  -L14        A01X+156496Y+121732X0180Y         S1      
327GND              PEX3  -AC39M      A01X+165846Y+117244X0180Y         S1      
327GND              PEX3  -AD39M      A01X+165846Y+116870X0180Y         S1      
327GND              PEX3  -AE39       A01X+165846Y+116496X0180Y         S1      
327GND              PEX3  -AB39M      A01X+165846Y+117618X0180Y         S1      
327GND              PEX3  -AC41M      A01X+166594Y+117244X0180Y         S1      
327GND              PEX3  -V43 M      A01X+167342Y+119114X0180Y         S1      
327GND              PEX3  -AA40M      A01X+166220Y+117992X0180Y         S1      
327GND              PEX3  -AA41M      A01X+166594Y+117992X0180Y         S1      
327GND              PEX3  -Y40 M      A01X+166220Y+118366X0180Y         S1      
327GND              PEX3  -AC40M      A01X+166220Y+117244X0180Y         S1      
327GND              PEX3  -AB40M      A01X+166220Y+117618X0180Y         S1      
327GND              PEX3  -AA42M      A01X+166968Y+117992X0180Y         S1      
327GND              PEX3  -W42 M      A01X+166968Y+118740X0180Y         S1      
327GND              PEX3  -Y43 M      A01X+167342Y+118366X0180Y         S1      
327GND              PEX3  -AB43M      A01X+167342Y+117618X0180Y         S1      
327GND              PEX3  -AC42M      A01X+166968Y+117244X0180Y         S1      
327GND              PEX3  -W40 M      A01X+166220Y+118740X0180Y         S1      
327GND              PEX3  -V40 M      A01X+166220Y+119114X0180Y         S1      
327GND              PEX3  -W41 M      A01X+166594Y+118740X0180Y         S1      
327GND              PEX3  -AD47M      A01X+168838Y+116870X0180Y         S1      
327GND              PEX3  -AD44M      A01X+167716Y+116870X0180Y         S1      
327GND              PEX3  -AD45M      A01X+168090Y+116870X0180Y         S1      
327GND              PEX3  -AD46M      A01X+168464Y+116870X0180Y         S1      
327GND              PEX3  -AE45       A01X+168090Y+116496X0180Y         S1      
327GND              PEX3  -AC49M      A01X+169587Y+117244X0180Y         S1      
327GND              PEX3  -AC48M      A01X+169213Y+117244X0180Y         S1      
327GND              PEX3  -AC45M      A01X+168090Y+117244X0180Y         S1      
327GND              PEX3  -T47        A01X+168838Y+119862X0180Y         S1      
327GND              PEX3  -U48 M      A01X+169213Y+119488X0180Y         S1      
327GND              PEX3  -U49 M      A01X+169587Y+119488X0180Y         S1      
327GND              PEX3  -W49 M      A01X+169587Y+118740X0180Y         S1      
327GND              PEX3  -W48 M      A01X+169213Y+118740X0180Y         S1      
327GND              PEX3  -AB47M      A01X+168838Y+117618X0180Y         S1      
327GND              PEX3  -AA49M      A01X+169587Y+117992X0180Y         S1      
327GND              PEX3  -AA48M      A01X+169213Y+117992X0180Y         S1      
327GND              PEX3  -AB46M      A01X+168464Y+117618X0180Y         S1      
327GND              PEX3  -V45 M      A01X+168090Y+119114X0180Y         S1      
327GND              PEX3  -V46 M      A01X+168464Y+119114X0180Y         S1      
327GND              PEX3  -Y44 M      A01X+167716Y+118366X0180Y         S1      
327GND              PEX3  -W45 M      A01X+168090Y+118740X0180Y         S1      
327GND              PEX3  -Y45 M      A01X+168090Y+118366X0180Y         S1      
327GND              PEX3  -AB44M      A01X+167716Y+117618X0180Y         S1      
327GND              PEX3  -AB45M      A01X+168090Y+117618X0180Y         S1      
327GND              PEX3  -AA45M      A01X+168090Y+117992X0180Y         S1      
327GND              PEX3  -Y46 M      A01X+168464Y+118366X0180Y         S1      
327GND              PEX3  -Y47 M      A01X+168838Y+118366X0180Y         S1      
327GND              PEX3  -V47 M      A01X+168838Y+119114X0180Y         S1      
327GND              PEX3  -V44 M      A01X+167716Y+119114X0180Y         S1      
327GND              PEX3  -U45 M      A01X+168090Y+119488X0180Y         S1      
327GND              PEX3  -T46 M      A01X+168464Y+119862X0180Y         S1      
327GND              PEX3  -T45 M      A01X+168090Y+119862X0180Y         S1      
327GND              PEX3  -AE48M      A01X+169213Y+116496X0180Y         S1      
327GND              PEX3  -AE49M      A01X+169587Y+116496X0180Y         S1      
327GND              PEX3  -L40        A01X+166220Y+121732X0180Y         S1      
327GND              PEX3  -T43        A01X+167342Y+119862X0180Y         S1      
327GND              PEX3  -R40 M      A01X+166220Y+120236X0180Y         S1      
327GND              PEX3  -P40 M      A01X+166220Y+120610X0180Y         S1      
327GND              PEX3  -U42 M      A01X+166968Y+119488X0180Y         S1      
327GND              PEX3  -T40 M      A01X+166220Y+119862X0180Y         S1      
327GND              PEX3  -U41 M      A01X+166594Y+119488X0180Y         S1      
327GND              PEX3  -U40 M      A01X+166220Y+119488X0180Y         S1      
327GND              PEX3  -N40 M      A01X+166220Y+120984X0180Y         S1      
327GND              PEX3  -M40 M      A01X+166220Y+121358X0180Y         S1      
327GND              PEX3  -AE40M      A01X+166220Y+116496X0180Y         S1      
327GND              PEX3  -AD40M      A01X+166220Y+116870X0180Y         S1      
327GND              PEX3  -AE41M      A01X+166594Y+116496X0180Y         S1      
327GND              PEX3  -AD43M      A01X+167342Y+116870X0180Y         S1      
327GND              PEX3  -AE42M      A01X+166968Y+116496X0180Y         S1      
327GND              PEX3  -L21 M      A01X+159114Y+121732X0180Y         S1      
327GND              PEX3  -P10        A01X+155000Y+120610X0180Y         S1      
327GND              PEX3  -R10        A01X+155000Y+120236X0180Y         S1      
327GND              PEX3  -P11 M      A01X+155374Y+120610X0180Y         S1      
327GND              PEX3  -R11 M      A01X+155374Y+120236X0180Y         S1      
327GND              PEX3  -R12 M      A01X+155748Y+120236X0180Y         S1      
327GND              PEX3  -P12 M      A01X+155748Y+120610X0180Y         S1      
327GND              PEX3  -R13 M      A01X+156122Y+120236X0180Y         S1      
327GND              PEX3  -T10        A01X+155000Y+119862X0180Y         S1      
327GND              PEX3  -T11 M      A01X+155374Y+119862X0180Y         S1      
327GND              PEX3  -T12 M      A01X+155748Y+119862X0180Y         S1      
327GND              PEX3  -T13 M      A01X+156122Y+119862X0180Y         S1      
327GND              PEX3  -U10        A01X+155000Y+119488X0180Y         S1      
327GND              PEX3  -U11 M      A01X+155374Y+119488X0180Y         S1      
327GND              PEX3  -V11 M      A01X+155374Y+119114X0180Y         S1      
327GND              PEX3  -U12 M      A01X+155748Y+119488X0180Y         S1      
327GND              PEX3  -U13 M      A01X+156122Y+119488X0180Y         S1      
327GND              PEX3  -V12 M      A01X+155748Y+119114X0180Y         S1      
327GND              PEX3  -V13        A01X+156122Y+119114X0180Y         S1      
327GND              PEX3  -V10        A01X+155000Y+119114X0180Y         S1      
327GND              PEX3  -P13 M      A01X+156122Y+120610X0180Y         S1      
327GND              PEX3  -N16 M      A01X+157244Y+120984X0180Y         S1      
327GND              PEX3  -N17 M      A01X+157618Y+120984X0180Y         S1      
327GND              PEX3  -R14 M      A01X+156496Y+120236X0180Y         S1      
327GND              PEX3  -M14 M      A01X+156496Y+121358X0180Y         S1      
327GND              PEX3  -N15 M      A01X+156870Y+120984X0180Y         S1      
327GND              PEX3  -N14 M      A01X+156496Y+120984X0180Y         S1      
327GND              PEX3  -P15 M      A01X+156870Y+120610X0180Y         S1      
327GND              PEX3  -P14 M      A01X+156496Y+120610X0180Y         S1      
327GND              PEX3  -P16 M      A01X+157244Y+120610X0180Y         S1      
327GND              PEX3  -R15 M      A01X+156870Y+120236X0180Y         S1      
327GND              PEX3  -R16 M      A01X+157244Y+120236X0180Y         S1      
327GND              PEX3  -R17 M      A01X+157618Y+120236X0180Y         S1      
327GND              PEX3  -P17 M      A01X+157618Y+120610X0180Y         S1      
327GND              PEX3  -R18 M      A01X+157992Y+120236X0180Y         S1      
327GND              PEX3  -R19 M      A01X+158366Y+120236X0180Y         S1      
327GND              PEX3  -R20 M      A01X+158740Y+120236X0180Y         S1      
327GND              PEX3  -R21 M      A01X+159114Y+120236X0180Y         S1      
327GND              PEX3  -R22 M      A01X+159488Y+120236X0180Y         S1      
327GND              PEX3  -N18 M      A01X+157992Y+120984X0180Y         S1      
327GND              PEX3  -N19 M      A01X+158366Y+120984X0180Y         S1      
327GND              PEX3  -P19 M      A01X+158366Y+120610X0180Y         S1      
327GND              PEX3  -N20 M      A01X+158740Y+120984X0180Y         S1      
327GND              PEX3  -P20 M      A01X+158740Y+120610X0180Y         S1      
327GND              PEX3  -N21 M      A01X+159114Y+120984X0180Y         S1      
327GND              PEX3  -N22 M      A01X+159488Y+120984X0180Y         S1      
327GND              PEX3  -P21 M      A01X+159114Y+120610X0180Y         S1      
327GND              PEX3  -P22 M      A01X+159488Y+120610X0180Y         S1      
327GND              PEX3  -N23 M      A01X+159862Y+120984X0180Y         S1      
327GND              PEX3  -N24        A01X+160236Y+120984X0180Y         S1      
327GND              PEX3  -P23 M      A01X+159862Y+120610X0180Y         S1      
327GND              PEX3  -P24 M      A01X+160236Y+120610X0180Y         S1      
327GND              PEX3  -R23 M      A01X+159862Y+120236X0180Y         S1      
327GND              PEX3  -R24        A01X+160236Y+120236X0180Y         S1      
327GND              PEX3  -P18 M      A01X+157992Y+120610X0180Y         S1      
327GND              PEX3  -L10        A01X+155000Y+121732X0180Y         S1      
327GND              PEX3  -M10        A01X+155000Y+121358X0180Y         S1      
327GND              PEX3  -N10        A01X+155000Y+120984X0180Y         S1      
327GND              PEX3  -M11        A01X+155374Y+121358X0180Y         S1      
327GND              PEX3  -N11 M      A01X+155374Y+120984X0180Y         S1      
327GND              PEX3  -N13 M      A01X+156122Y+120984X0180Y         S1      
327GND              PEX3  -N12 M      A01X+155748Y+120984X0180Y         S1      
327GND              PEX3  -M12 M      A01X+155748Y+121358X0180Y         S1      
327GND              PEX3  -AA12M      A01X+155748Y+117992X0180Y         S1      
327GND              PEX3  -AC9 M      A01X+154626Y+117244X0180Y         S1      
327GND              PEX3  -AB9 M      A01X+154626Y+117618X0180Y         S1      
327GND              PEX3  -AY9 M      A01X+154626Y+110886X0180Y         S1      
327GND              PEX3  -BD8 M      A01X+154252Y+109390X0180Y         S1      
327GND              PEX3  -AY13       A01X+156122Y+110886X0180Y         S1      
327GND              PEX3  -AR17M      A01X+157618Y+112756X0180Y         S1      
327GND              PEX3  -AT17M      A01X+157618Y+112382X0180Y         S1      
327GND              PEX3  -AU17M      A01X+157618Y+112008X0180Y         S1      
327GND              PEX3  -AY14       A01X+156496Y+110886X0180Y         S1      
327GND              PEX3  -AY15       A01X+156870Y+110886X0180Y         S1      
327GND              PEX3  -AT21M      A01X+159114Y+112382X0180Y         S1      
327GND              PEX3  -AV20M      A01X+158740Y+111634X0180Y         S1      
327GND              PEX3  -AY22       A01X+159488Y+110886X0180Y         S1      
327GND              PEX3  -AR18M      A01X+157992Y+112756X0180Y         S1      
327GND              PEX3  -AR22M      A01X+159488Y+112756X0180Y         S1      
327GND              PEX3  -AT22M      A01X+159488Y+112382X0180Y         S1      
327GND              PEX3  -AL25       A01X+160610Y+114252X0180Y         S1      
327GND              PEX3  -AL26M      A01X+160984Y+114252X0180Y         S1      
327GND              PEX3  -AJ26M      A01X+160984Y+115000X0180Y         S1      
327GND              PEX3  -AR25       A01X+160610Y+112756X0180Y         S1      
327GND              PEX3  -AR26M      A01X+160984Y+112756X0180Y         S1      
327GND              PEX3  -AY25       A01X+160610Y+110886X0180Y         S1      
327GND              PEX3  -AU25       A01X+160610Y+112008X0180Y         S1      
327GND              PEX3  -AT25M      A01X+160610Y+112382X0180Y         S1      
327GND              PEX3  -AY26       A01X+160984Y+110886X0180Y         S1      
327GND              PEX3  -AT26M      A01X+160984Y+112382X0180Y         S1      
327GND              PEX3  -AJ29M      A01X+162106Y+115000X0180Y         S1      
327GND              PEX3  -AJ27M      A01X+161358Y+115000X0180Y         S1      
327GND              PEX3  -AJ28M      A01X+161732Y+115000X0180Y         S1      
327GND              PEX3  -AJ30M      A01X+162480Y+115000X0180Y         S1      
327GND              PEX3  -AR28M      A01X+161732Y+112756X0180Y         S1      
327GND              PEX3  -AR30M      A01X+162480Y+112756X0180Y         S1      
327GND              PEX3  -AR29M      A01X+162106Y+112756X0180Y         S1      
327GND              PEX3  -AR27M      A01X+161358Y+112756X0180Y         S1      
327GND              PEX3  -AT29M      A01X+162106Y+112382X0180Y         S1      
327GND              PEX3  -AU29M      A01X+162106Y+112008X0180Y         S1      
327GND              PEX3  -AT30M      A01X+162480Y+112382X0180Y         S1      
327GND              PEX3  -AU30M      A01X+162480Y+112008X0180Y         S1      
327GND              PEX3  -AY31       A01X+162854Y+110886X0180Y         S1      
327GND              PEX3  -AT31M      A01X+162854Y+112382X0180Y         S1      
327GND              PEX3  -AU31M      A01X+162854Y+112008X0180Y         S1      
327GND              PEX3  -AU32M      A01X+163228Y+112008X0180Y         S1      
327GND              PEX3  -AU33M      A01X+163602Y+112008X0180Y         S1      
327GND              PEX3  -AU34M      A01X+163976Y+112008X0180Y         S1      
327GND              PEX3  -AT34M      A01X+163976Y+112382X0180Y         S1      
327GND              PEX3  -AR31M      A01X+162854Y+112756X0180Y         S1      
327GND              PEX3  -AT32M      A01X+163228Y+112382X0180Y         S1      
327GND              PEX3  -AR35       A01X+164350Y+112756X0180Y         S1      
327GND              PEX3  -AT35M      A01X+164350Y+112382X0180Y         S1      
327GND              PEX3  -AR34M      A01X+163976Y+112756X0180Y         S1      
327GND              PEX3  -AR32M      A01X+163228Y+112756X0180Y         S1      
327GND              PEX3  -AR33M      A01X+163602Y+112756X0180Y         S1      
327GND              PEX3  -AT33M      A01X+163602Y+112382X0180Y         S1      
327GND              PEX3  -AP34       A01X+163976Y+113130X0180Y         S1      
327GND              PEX3  -AU35M      A01X+164350Y+112008X0180Y         S1      
327GND              PEX3  -AY35       A01X+164350Y+110886X0180Y         S1      
327GND              PEX3  -AY34       A01X+163976Y+110886X0180Y         S1      
327GND              PEX3  -AY33       A01X+163602Y+110886X0180Y         S1      
327GND              PEX3  -AY32       A01X+163228Y+110886X0180Y         S1      
327GND              PEX3  -AL31M      A01X+162854Y+114252X0180Y         S1      
327GND              PEX3  -AL32M      A01X+163228Y+114252X0180Y         S1      
327GND              PEX3  -AL33M      A01X+163602Y+114252X0180Y         S1      
327GND              PEX3  -AL34M      A01X+163976Y+114252X0180Y         S1      
327GND              PEX3  -AK34M      A01X+163976Y+114626X0180Y         S1      
327GND              PEX3  -AJ34M      A01X+163976Y+115000X0180Y         S1      
327GND              PEX3  -AH34M      A01X+163976Y+115374X0180Y         S1      
327GND              PEX3  -AG34       A01X+163976Y+115748X0180Y         S1      
327GND              PEX3  -AH35M      A01X+164350Y+115374X0180Y         S1      
327GND              PEX3  -AJ35M      A01X+164350Y+115000X0180Y         S1      
327GND              PEX3  -AF35       A01X+164350Y+116122X0180Y         S1      
327GND              PEX3  -AG35M      A01X+164350Y+115748X0180Y         S1      
327GND              PEX3  -AT37M      A01X+165098Y+112382X0180Y         S1      
327GND              PEX3  -AU36M      A01X+164724Y+112008X0180Y         S1      
327GND              PEX3  -AU37M      A01X+165098Y+112008X0180Y         S1      
327GND              PEX3  -AH36M      A01X+164724Y+115374X0180Y         S1      
327GND              PEX3  -AJ36M      A01X+164724Y+115000X0180Y         S1      
327GND              PEX3  -AK36M      A01X+164724Y+114626X0180Y         S1      
327GND              PEX3  -AK37M      A01X+165098Y+114626X0180Y         S1      
327GND              PEX3  -AL36M      A01X+164724Y+114252X0180Y         S1      
327GND              PEX3  -AL37M      A01X+165098Y+114252X0180Y         S1      
327GND              PEX3  -AM37M      A01X+165098Y+113878X0180Y         S1      
327GND              PEX3  -AM36M      A01X+164724Y+113878X0180Y         S1      
327GND              PEX3  -AP37M      A01X+165098Y+113130X0180Y         S1      
327GND              PEX3  -AR37M      A01X+165098Y+112756X0180Y         S1      
327GND              PEX3  -AN37M      A01X+165098Y+113504X0180Y         S1      
327GND              PEX3  -AJ37M      A01X+165098Y+115000X0180Y         S1      
327GND              PEX3  -AH37       A01X+165098Y+115374X0180Y         S1      
327GND              PEX3  -AH38M      A01X+165472Y+115374X0180Y         S1      
327GND              PEX3  -AH39M      A01X+165846Y+115374X0180Y         S1      
327GND              PEX3  -AF39       A01X+165846Y+116122X0180Y         S1      
327GND              PEX3  -AG39M      A01X+165846Y+115748X0180Y         S1      
327GND              PEX3  -AV40       A01X+166220Y+111634X0180Y         S1      
327GND              PEX3  -AT40       A01X+166220Y+112382X0180Y         S1      
327GND              PEX3  -AF40M      A01X+166220Y+116122X0180Y         S1      
327GND              PEX3  -AF43       A01X+167342Y+116122X0180Y         S1      
327GND              PEX3  -AK40M      A01X+166220Y+114626X0180Y         S1      
327GND              PEX3  -AL40M      A01X+166220Y+114252X0180Y         S1      
327GND              PEX3  -AL41M      A01X+166594Y+114252X0180Y         S1      
327GND              PEX3  -AJ40M      A01X+166220Y+115000X0180Y         S1      
327GND              PEX3  -AJ41M      A01X+166594Y+115000X0180Y         S1      
327GND              PEX3  -AH40M      A01X+166220Y+115374X0180Y         S1      
327GND              PEX3  -AG40M      A01X+166220Y+115748X0180Y         S1      
327GND              PEX3  -AJ42M      A01X+166968Y+115000X0180Y         S1      
327GND              PEX3  -AG42M      A01X+166968Y+115748X0180Y         S1      
327GND              PEX3  -AK43M      A01X+167342Y+114626X0180Y         S1      
327GND              PEX3  -AH43M      A01X+167342Y+115374X0180Y         S1      
327GND              PEX3  -AL42M      A01X+166968Y+114252X0180Y         S1      
327GND              PEX3  -AR40       A01X+166220Y+112756X0180Y         S1      
327GND              PEX3  -AP40       A01X+166220Y+113130X0180Y         S1      
327GND              PEX3  -AN40       A01X+166220Y+113504X0180Y         S1      
327GND              PEX3  -AF47M      A01X+168838Y+116122X0180Y         S1      
327GND              PEX3  -AG49M      A01X+169587Y+115748X0180Y         S1      
327GND              PEX3  -AF45       A01X+168090Y+116122X0180Y         S1      
327GND              PEX3  -AF46M      A01X+168464Y+116122X0180Y         S1      
327GND              PEX3  -AK47M      A01X+168838Y+114626X0180Y         S1      
327GND              PEX3  -AK45M      A01X+168090Y+114626X0180Y         S1      
327GND              PEX3  -AL49M      A01X+169587Y+114252X0180Y         S1      
327GND              PEX3  -AL48M      A01X+169213Y+114252X0180Y         S1      
327GND              PEX3  -AL45M      A01X+168090Y+114252X0180Y         S1      
327GND              PEX3  -AM47M      A01X+168838Y+113878X0180Y         S1      
327GND              PEX3  -AM44M      A01X+167716Y+113878X0180Y         S1      
327GND              PEX3  -AM45M      A01X+168090Y+113878X0180Y         S1      
327GND              PEX3  -AM46M      A01X+168464Y+113878X0180Y         S1      
327GND              PEX3  -AK46M      A01X+168464Y+114626X0180Y         S1      
327GND              PEX3  -AK44M      A01X+167716Y+114626X0180Y         S1      
327GND              PEX3  -AJ45M      A01X+168090Y+115000X0180Y         S1      
327GND              PEX3  -AH46M      A01X+168464Y+115374X0180Y         S1      
327GND              PEX3  -AH45M      A01X+168090Y+115374X0180Y         S1      
327GND              PEX3  -AG45M      A01X+168090Y+115748X0180Y         S1      
327GND              PEX3  -AH44M      A01X+167716Y+115374X0180Y         S1      
327GND              PEX3  -AG48M      A01X+169213Y+115748X0180Y         S1      
327GND              PEX3  -AH47M      A01X+168838Y+115374X0180Y         S1      
327GND              PEX3  -AJ49M      A01X+169587Y+115000X0180Y         S1      
327GND              PEX3  -AJ48M      A01X+169213Y+115000X0180Y         S1      
327GND              PEX3  -AM43M      A01X+167342Y+113878X0180Y         S1      
327GND              PEX3  -AG41M      A01X+166594Y+115748X0180Y         S1      
327GND              PEX3  -AY40       A01X+166220Y+110886X0180Y         S1      
327GND              PEX3  -AU40       A01X+166220Y+112008X0180Y         S1      
327GND              PEX3  -AY37       A01X+165098Y+110886X0180Y         S1      
327GND              PEX3  -AY36       A01X+164724Y+110886X0180Y         S1      
327GND              PEX3  -AY39       A01X+165846Y+110886X0180Y         S1      
327GND              PEX3  -AY38       A01X+165472Y+110886X0180Y         S1      
327GND              PEX3  -AJ33M      A01X+163602Y+115000X0180Y         S1      
327GND              PEX3  -AJ31M      A01X+162854Y+115000X0180Y         S1      
327GND              PEX3  -AJ32M      A01X+163228Y+115000X0180Y         S1      
327GND              PEX3  -AT27M      A01X+161358Y+112382X0180Y         S1      
327GND              PEX3  -AU27M      A01X+161358Y+112008X0180Y         S1      
327GND              PEX3  -AU28M      A01X+161732Y+112008X0180Y         S1      
327GND              PEX3  -AT28M      A01X+161732Y+112382X0180Y         S1      
327GND              PEX3  -AY30       A01X+162480Y+110886X0180Y         S1      
327GND              PEX3  -AY28       A01X+161732Y+110886X0180Y         S1      
327GND              PEX3  -AY29       A01X+162106Y+110886X0180Y         S1      
327GND              PEX3  -AY27       A01X+161358Y+110886X0180Y         S1      
327GND              PEX3  -AL30M      A01X+162480Y+114252X0180Y         S1      
327GND              PEX3  -AL29M      A01X+162106Y+114252X0180Y         S1      
327GND              PEX3  -AL28M      A01X+161732Y+114252X0180Y         S1      
327GND              PEX3  -AL27M      A01X+161358Y+114252X0180Y         S1      
327GND              PEX3  -AU26M      A01X+160984Y+112008X0180Y         S1      
327GND              PEX3  -AJ25       A01X+160610Y+115000X0180Y         S1      
327GND              PEX3  -AR23M      A01X+159862Y+112756X0180Y         S1      
327GND              PEX3  -AR24       A01X+160236Y+112756X0180Y         S1      
327GND              PEX3  -AV24M      A01X+160236Y+111634X0180Y         S1      
327GND              PEX3  -AT23M      A01X+159862Y+112382X0180Y         S1      
327GND              PEX3  -AT24M      A01X+160236Y+112382X0180Y         S1      
327GND              PEX3  -AU23M      A01X+159862Y+112008X0180Y         S1      
327GND              PEX3  -AU24M      A01X+160236Y+112008X0180Y         S1      
327GND              PEX3  -AY24       A01X+160236Y+110886X0180Y         S1      
327GND              PEX3  -AY23       A01X+159862Y+110886X0180Y         S1      
327GND              PEX3  -AW24       A01X+160236Y+111260X0180Y         S1      
327GND              PEX3  -AR21M      A01X+159114Y+112756X0180Y         S1      
327GND              PEX3  -AR19M      A01X+158366Y+112756X0180Y         S1      
327GND              PEX3  -AR20M      A01X+158740Y+112756X0180Y         S1      
327GND              PEX3  -AT19M      A01X+158366Y+112382X0180Y         S1      
327GND              PEX3  -AT20M      A01X+158740Y+112382X0180Y         S1      
327GND              PEX3  -AU19M      A01X+158366Y+112008X0180Y         S1      
327GND              PEX3  -AU20M      A01X+158740Y+112008X0180Y         S1      
327GND              PEX3  -AU18M      A01X+157992Y+112008X0180Y         S1      
327GND              PEX3  -AT18M      A01X+157992Y+112382X0180Y         S1      
327GND              PEX3  -AY21       A01X+159114Y+110886X0180Y         S1      
327GND              PEX3  -AY20       A01X+158740Y+110886X0180Y         S1      
327GND              PEX3  -AY19       A01X+158366Y+110886X0180Y         S1      
327GND              PEX3  -AY18       A01X+157992Y+110886X0180Y         S1      
327GND              PEX3  -AU22M      A01X+159488Y+112008X0180Y         S1      
327GND              PEX3  -AU21M      A01X+159114Y+112008X0180Y         S1      
327GND              PEX3  -AY16       A01X+157244Y+110886X0180Y         S1      
327GND              PEX3  -AY17       A01X+157618Y+110886X0180Y         S1      
327GND              PEX3  -AY12       A01X+155748Y+110886X0180Y         S1      
327GND              PEX3  -AW10       A01X+155000Y+111260X0180Y         S1      
327GND              PEX3  -AY11       A01X+155374Y+110886X0180Y         S1      
327GND              PEX3  -AY10       A01X+155000Y+110886X0180Y         S1      
327GND              PEX3  -BC8 M      A01X+154252Y+109764X0180Y         S1      
327GND              PEX3  -BE8 M      A01X+154252Y+109016X0180Y         S1      
327GND              PEX3  -BF7 M      A01X+153878Y+108642X0180Y         S1      
327GND              PEX3  -BH8        A01X+154252Y+107894X0180Y         S1      
327GND              PEX3  -BJ8 M      A01X+154252Y+107520X0180Y         S1      
327GND              PEX3  -W26 M      A01X+160984Y+118740X0180Y         S1      
327GND              PEX3  -N26 M      A01X+160984Y+120984X0180Y         S1      
327GND              PEX3  -U25        A01X+160610Y+119488X0180Y         S1      
327GND              PEX3  -R25        A01X+160610Y+120236X0180Y         S1      
327GND              PEX3  -P25 M      A01X+160610Y+120610X0180Y         S1      
327GND              PEX3  -R26 M      A01X+160984Y+120236X0180Y         S1      
327GND              PEX3  -P26 M      A01X+160984Y+120610X0180Y         S1      
327GND              PEX3  -W27 M      A01X+161358Y+118740X0180Y         S1      
327GND              PEX3  -W28 M      A01X+161732Y+118740X0180Y         S1      
327GND              PEX3  -W29 M      A01X+162106Y+118740X0180Y         S1      
327GND              PEX3  -W30 M      A01X+162480Y+118740X0180Y         S1      
327GND              PEX3  -N30 M      A01X+162480Y+120984X0180Y         S1      
327GND              PEX3  -N29 M      A01X+162106Y+120984X0180Y         S1      
327GND              PEX3  -N27 M      A01X+161358Y+120984X0180Y         S1      
327GND              PEX3  -N28 M      A01X+161732Y+120984X0180Y         S1      
327GND              PEX3  -U27 M      A01X+161358Y+119488X0180Y         S1      
327GND              PEX3  -U28 M      A01X+161732Y+119488X0180Y         S1      
327GND              PEX3  -U29 M      A01X+162106Y+119488X0180Y         S1      
327GND              PEX3  -U30 M      A01X+162480Y+119488X0180Y         S1      
327GND              PEX3  -P27 M      A01X+161358Y+120610X0180Y         S1      
327GND              PEX3  -P28 M      A01X+161732Y+120610X0180Y         S1      
327GND              PEX3  -R27 M      A01X+161358Y+120236X0180Y         S1      
327GND              PEX3  -R28 M      A01X+161732Y+120236X0180Y         S1      
327GND              PEX3  -R29 M      A01X+162106Y+120236X0180Y         S1      
327GND              PEX3  -P29 M      A01X+162106Y+120610X0180Y         S1      
327GND              PEX3  -R30 M      A01X+162480Y+120236X0180Y         S1      
327GND              PEX3  -W31 M      A01X+162854Y+118740X0180Y         S1      
327GND              PEX3  -W32 M      A01X+163228Y+118740X0180Y         S1      
327GND              PEX3  -W34 M      A01X+163976Y+118740X0180Y         S1      
327GND              PEX3  -W33 M      A01X+163602Y+118740X0180Y         S1      
327GND              PEX3  -V34 M      A01X+163976Y+119114X0180Y         S1      
327GND              PEX3  -U31 M      A01X+162854Y+119488X0180Y         S1      
327GND              PEX3  -U32 M      A01X+163228Y+119488X0180Y         S1      
327GND              PEX3  -U34 M      A01X+163976Y+119488X0180Y         S1      
327GND              PEX3  -U35 M      A01X+164350Y+119488X0180Y         S1      
327GND              PEX3  -T34 M      A01X+163976Y+119862X0180Y         S1      
327GND              PEX3  -R33 M      A01X+163602Y+120236X0180Y         S1      
327GND              PEX3  -R34 M      A01X+163976Y+120236X0180Y         S1      
327GND              PEX3  -R35 M      A01X+164350Y+120236X0180Y         S1      
327GND              PEX3  -R32 M      A01X+163228Y+120236X0180Y         S1      
327GND              PEX3  -N31 M      A01X+162854Y+120984X0180Y         S1      
327GND              PEX3  -P31 M      A01X+162854Y+120610X0180Y         S1      
327GND              PEX3  -N32 M      A01X+163228Y+120984X0180Y         S1      
327GND              PEX3  -P32 M      A01X+163228Y+120610X0180Y         S1      
327GND              PEX3  -N33 M      A01X+163602Y+120984X0180Y         S1      
327GND              PEX3  -P33 M      A01X+163602Y+120610X0180Y         S1      
327GND              PEX3  -N36 M      A01X+164724Y+120984X0180Y         S1      
327GND              PEX3  -N37        A01X+165098Y+120984X0180Y         S1      
327GND              PEX3  -P37        A01X+165098Y+120610X0180Y         S1      
327GND              PEX3  -R37        A01X+165098Y+120236X0180Y         S1      
327GND              PEX3  -N34 M      A01X+163976Y+120984X0180Y         S1      
327GND              PEX3  -N35 M      A01X+164350Y+120984X0180Y         S1      
327GND              PEX3  -P34 M      A01X+163976Y+120610X0180Y         S1      
327GND              PEX3  -P35 M      A01X+164350Y+120610X0180Y         S1      
327GND              PEX3  -R31        A01X+162854Y+120236X0180Y         S1      
327GND              PEX3  -U33 M      A01X+163602Y+119488X0180Y         S1      
327GND              PEX3  -P30 M      A01X+162480Y+120610X0180Y         S1      
327GND              PEX3  -U26 M      A01X+160984Y+119488X0180Y         S1      
327GND              PEX3  -N25        A01X+160610Y+120984X0180Y         S1      
327GND              PEX3  -W25        A01X+160610Y+118740X0180Y         S1      
327GND              PEX3  -AE35       A01X+164350Y+116496X0180Y         S1      
327GND              PEX3  -AD35M      A01X+164350Y+116870X0180Y         S1      
327GND              PEX3  -AC34       A01X+163976Y+117244X0180Y         S1      
327GND              PEX3  -AB34M      A01X+163976Y+117618X0180Y         S1      
327GND              PEX3  -AC35M      A01X+164350Y+117244X0180Y         S1      
327GND              PEX3  -AC37M      A01X+165098Y+117244X0180Y         S1      
327GND              PEX3  -Y38 M      A01X+165472Y+118366X0180Y         S1      
327GND              PEX3  -W36 M      A01X+164724Y+118740X0180Y         S1      
327GND              PEX3  -W37 M      A01X+165098Y+118740X0180Y         S1      
327GND              PEX3  -U37 M      A01X+165098Y+119488X0180Y         S1      
327GND              PEX3  -V37 M      A01X+165098Y+119114X0180Y         S1      
327GND              PEX3  -V36 M      A01X+164724Y+119114X0180Y         S1      
327GND              PEX3  -V38 M      A01X+165472Y+119114X0180Y         S1      
327GND              PEX3  -T37        A01X+165098Y+119862X0180Y         S1      
327GND              PEX3  -Y37 M      A01X+165098Y+118366X0180Y         S1      
327GND              PEX3  -AA38M      A01X+165472Y+117992X0180Y         S1      
327GND              PEX3  -AB36M      A01X+164724Y+117618X0180Y         S1      
327GND              PEX3  -AA36M      A01X+164724Y+117992X0180Y         S1      
327GND              PEX3  -AB37M      A01X+165098Y+117618X0180Y         S1      
327GND              PEX3  -AB38M      A01X+165472Y+117618X0180Y         S1      
327GND              PEX3  -Y36 M      A01X+164724Y+118366X0180Y         S1      
327GND              PEX3  -AD37M      A01X+165098Y+116870X0180Y         S1      
327GND              PEX3  -AE37       A01X+165098Y+116496X0180Y         S1      
327GND              PEX3  -W22 M      A01X+159488Y+118740X0180Y         S1      
327GND              PEX3  -W24        A01X+160236Y+118740X0180Y         S1      
327GND              PEX3  -W23 M      A01X+159862Y+118740X0180Y         S1      
327GND              PEX3  -W21 M      A01X+159114Y+118740X0180Y         S1      
327GND              PEX3  -W20 M      A01X+158740Y+118740X0180Y         S1      
327GND              PEX3  -W19 M      A01X+158366Y+118740X0180Y         S1      
327GND              PEX3  -W18 M      A01X+157992Y+118740X0180Y         S1      
327GND              PEX3  -W17 M      A01X+157618Y+118740X0180Y         S1      
327GND              PEX3  -W16 M      A01X+157244Y+118740X0180Y         S1      
327GND              PEX3  -W15 M      A01X+156870Y+118740X0180Y         S1      
327GND              PEX3  -W14 M      A01X+156496Y+118740X0180Y         S1      
327GND              PEX3  -T15 M      A01X+156870Y+119862X0180Y         S1      
327GND              PEX3  -U15 M      A01X+156870Y+119488X0180Y         S1      
327GND              PEX3  -U16 M      A01X+157244Y+119488X0180Y         S1      
327GND              PEX3  -U17 M      A01X+157618Y+119488X0180Y         S1      
327GND              PEX3  -U18 M      A01X+157992Y+119488X0180Y         S1      
327GND              PEX3  -U19 M      A01X+158366Y+119488X0180Y         S1      
327GND              PEX3  -U20 M      A01X+158740Y+119488X0180Y         S1      
327GND              PEX3  -U21 M      A01X+159114Y+119488X0180Y         S1      
327GND              PEX3  -U24        A01X+160236Y+119488X0180Y         S1      
327GND              PEX3  -U23 M      A01X+159862Y+119488X0180Y         S1      
327GND              PEX3  -U22 M      A01X+159488Y+119488X0180Y         S1      
327GND              PEX3  -V15 M      A01X+156870Y+119114X0180Y         S1      
327GND              PEX3  -AA16M      A01X+157244Y+117992X0180Y         S1      
327GND              PEX3  -AA17M      A01X+157618Y+117992X0180Y         S1      
327GND              PEX3  -AA22M      A01X+159488Y+117992X0180Y         S1      
327GND              PEX3  -AA24       A01X+160236Y+117992X0180Y         S1      
327GND              PEX3  -AA23M      A01X+159862Y+117992X0180Y         S1      
327GND              PEX3  -AA21M      A01X+159114Y+117992X0180Y         S1      
327GND              PEX3  -AA20M      A01X+158740Y+117992X0180Y         S1      
327GND              PEX3  -AA19M      A01X+158366Y+117992X0180Y         S1      
327GND              PEX3  -AA18M      A01X+157992Y+117992X0180Y         S1      
327GND              PEX3  -Y15 M      A01X+156870Y+118366X0180Y         S1      
327GND              PEX3  -AL10       A01X+155000Y+114252X0180Y         S1      
327GND              PEX3  -AR14       A01X+156496Y+112756X0180Y         S1      
327GND              PEX3  -AL13       A01X+156122Y+114252X0180Y         S1      
327GND              PEX3  -AL12       A01X+155748Y+114252X0180Y         S1      
327GND              PEX3  -AL11       A01X+155374Y+114252X0180Y         S1      
327GND              PEX3  -AU14       A01X+156496Y+112008X0180Y         S1      
327GND              PEX3  -AT14       A01X+156496Y+112382X0180Y         S1      
327GND              PEX3  -AL9        A01X+154626Y+114252X0180Y         S1      
327GND              PEX3  -AL8        A01X+154252Y+114252X0180Y         S1      
327GND              PEX3  -AL7        A01X+153878Y+114252X0180Y         S1      
327GND              PEX3  -AL6        A01X+153504Y+114252X0180Y         S1      
327GND              PEX3  -BD6        A01X+153504Y+109390X0180Y         S1      
327GND              PEX3  -AL5        A01X+153130Y+114252X0180Y         S1      
327GND              PEX3  -AL4        A01X+152756Y+114252X0180Y         S1      
327GND              PEX3  -AL3        A01X+152382Y+114252X0180Y         S1      
327GND              PEX3  -AL2        A01X+152008Y+114252X0180Y         S1      
327GND              PEX3  -BD4        A01X+152756Y+109390X0180Y         S1      
327GND              PEX3  -BD2        A01X+152008Y+109390X0180Y         S1      
327GND              PEX3  -BF1        A01X+151634Y+108642X0180Y         S1      
327GND              PEX3  -BD1        A01X+151634Y+109390X0180Y         S1      
327GND              PEX3  -BC1        A01X+151634Y+109764X0180Y         S1      
327GND              PEX3  -AW1        A01X+151634Y+111260X0180Y         S1      
327GND              PEX3  -AU1        A01X+151634Y+112008X0180Y         S1      
327GND              PEX3  -AR1        A01X+151634Y+112756X0180Y         S1      
327GND              PEX3  -AN1        A01X+151634Y+113504X0180Y         S1      
327GND              PEX3  -AL1        A01X+151634Y+114252X0180Y         S1      
327GND              PEX3  -AK1        A01X+151634Y+114626X0180Y         S1      
327GND              PEX3  -AH1        A01X+151634Y+115374X0180Y         S1      
327GND              PEX3  -AF1        A01X+151634Y+116122X0180Y         S1      
327GND              R3507 -2          A18X+143108Y+089750X0198Y0197R180 S2      
327GND              C2058 -2          A18X+130320Y+083225X0164Y0164     S2      
327GND              R1041 -1          A18X+117370Y+079434X0198Y0197R270 S2      
327GND              Q122  -1          A01X+161434Y+063379X0240Y0240     S1      
327GND              R344  -2          A01X+159828Y+055370X0198Y0197R180 S1      
327GND              J26   -B16        A01X+155253Y+054002X0140Y0480R270 S1      
327GND              U41   -3          A01X+156513Y+068201X0220Y0530R180 S1      
327GND              C620  -2          A01X+144020Y+057584X0198Y0197R180 S1      
327GND              R4806 -2          A18X+138286Y+060750X0198Y0197     S2      
327GND              R4246 -1          A01X+134237Y+076968X0198Y0197R180 S1      
327GND              R4844 -1          A01X+133258Y+059050X0198Y0197R180 S1      
327GND              Q121  -1          A01X+115725Y+063379X0240Y0240     S1      
327GND              J24   -B16        A01X+109544Y+054002X0140Y0480R270 S1      
327GND              R218  -2          A01X+106460Y+061160X0198Y0197R180 S1      
327GND              R217  -2   M      A01X+106460Y+061560X0198Y0197R180 S1      
327GND              C422  -2          A01X+098312Y+057584X0198Y0197R180 S1      
327GND              C916  -2          A01X+097858Y+057576X0198Y0197R270 S1      
327GND              C2796 -2          A18X+090087Y+055636X0198Y0197     S2      
327GND              R5965 -2          A01X+086388Y+049130X0198Y0197R180 S1      
327GND              R4207 -1          A01X+086949Y+057070X0198Y0197     S1      
327GND              R4203 -1          A01X+086949Y+058283X0198Y0197     S1      
327GND              J22   -B16        A01X+063836Y+054002X0140Y0480R270 S1      
327GND              R116  -2          A01X+060751Y+061160X0198Y0197R180 S1      
327GND              R115  -2   M      A01X+060751Y+061560X0198Y0197R180 S1      
327GND              R128  -2          A01X+060748Y+060759X0198Y0197R180 S1      
327GND              Y4    -2   M      A01X+054661Y+076078X0480Y0560R090 S1      
327GND              C416  -2          A01X+052603Y+057584X0198Y0197R180 S1      
327GND              C2661 -2          A18X+051538Y+068581X0198Y0197R090 S2      
327GND              PC303 -2          A01X+046598Y+049167X0198Y0197     S1      
327GND              PC302 -2          A01X+046598Y+050767X0198Y0197     S1      
327GND              J20   -B16        A01X+018127Y+054002X0140Y0480R270 S1      
327GND              C410  -2          A01X+006894Y+057584X0198Y0197R180 S1      
327GND              PR6877-2   M      A01X+003669Y+063939X0198Y0197R090 S1      
327GND              C2594 -2          A18X+055617Y+078784X0198Y0197R090 S2      
327GND              C2095 -1          A01X+071342Y+078345X0198Y0197R180 S1      
327GND              PU105 -7          A01X+141652Y+062482X0100Y0320R180 S1      
327GND              PU103 -7          A01X+095943Y+062482X0100Y0320R180 S1      
327GND              PU73  -7          A01X+050234Y+062482X0100Y0320R180 S1      
327GND              PU71  -7          A01X+004526Y+062482X0100Y0320R180 S1      
327GND              PR7095-2          A01X+175816Y+028806X0198Y0197R090 S1      
327GND              C980  -1          A01X+174892Y+010170X0198Y0197R270 S1      
327GND              R763  -2          A01X+172575Y+037957X0198Y0197R270 S1      
327GND              R383  -2          A18X+167812Y+039392X0198Y0197R180 S2      
327GND              R372  -2          A18X+167812Y+040992X0198Y0197R180 S2      
327GND              PC974 -2   M      A01X+169557Y+010475X0198Y0197R270 S1      
327GND              PC975 -2          A01X+169359Y+013090X0198Y0197R090 S1      
327GND              PC895 -2          A01X+166075Y+025954X0198Y0197R270 S1      
327GND              U43   -3          A18X+164094Y+045163X0240Y0240R270 S2      
327GND              C979  -1          A01X+164656Y+010170X0198Y0197R270 S1      
327GND              PC579 -2          A01X+161218Y+023613X0198Y0197R090 S1      
327GND              C3995 -1          A01X+161187Y+033625X0198Y0197R180 S1      
327GND              PC970 -2   M      A01X+159320Y+010475X0198Y0197R270 S1      
327GND              C978  -1          A01X+154420Y+010170X0198Y0197R270 S1      
327GND              PC964 -2   M      A01X+149084Y+010475X0198Y0197R270 S1      
327GND              C977  -1          A01X+144184Y+010170X0198Y0197R270 S1      
327GND              PR7123-2   M      A01X+138448Y+010475X0198Y0197R270 S1      
327GND              R1608 -2          A01X+138788Y+035687X0198Y0197R180 S1      
327GND              PC960 -2   M      A01X+138848Y+010475X0198Y0197R270 S1      
327GND              PC324 -2          A01X+130341Y+037348X0198Y0197R270 S1      
327GND              C976  -1          A01X+129184Y+010170X0198Y0197R270 S1      
327GND              R281  -2          A18X+122103Y+039392X0198Y0197R180 S2      
327GND              R270  -2          A18X+122103Y+040992X0198Y0197R180 S2      
327GND              PC956 -2   M      A01X+123848Y+010475X0198Y0197R270 S1      
327GND              Q227  -4          A01X+120890Y+014646X0240Y0240R270 S1      
327GND              U33   -3          A18X+118386Y+045163X0240Y0240R270 S2      
327GND              C975  -1          A01X+118947Y+010170X0198Y0197R270 S1      
327GND              R274  -2          A01X+114486Y+040472X0198Y0197R180 S1      
327GND              R275  -2          A01X+114486Y+041272X0198Y0197R180 S1      
327GND              PC954 -2   M      A01X+113612Y+010475X0198Y0197R270 S1      
327GND              C2773 -2   M      A01X+114374Y+010650X0198Y0197R180 S1      
327GND              R491  -2          A01X+112592Y+032900X0198Y0197R180 S1      
327GND              U413  -S          A01X+110836Y+010792X0400Y0560R180 S1      
327GND              PC862 -2          A01X+109235Y+028806X0198Y0197R090 S1      
327GND              C974  -1          A01X+108711Y+010170X0198Y0197R270 S1      
327GND              PC946 -2   M      A01X+103376Y+010475X0198Y0197R270 S1      
327GND              U373  -S          A01X+103936Y+015330X0400Y0560     S1      
327GND              C973  -1          A01X+098475Y+010170X0198Y0197R270 S1      
327GND              R434  -1          A01X+099483Y+010135X0198Y0197R270 S1      
327GND              Q204  -4          A01X+094606Y+024981X0240Y0240     S1      
327GND              PC944 -2   M      A01X+093139Y+010475X0198Y0197R270 S1      
327GND              PC857 -2          A01X+084894Y+025954X0198Y0197R270 S1      
327GND              C972  -1          A01X+083475Y+010170X0198Y0197R270 S1      
327GND              R4267 -2          A01X+081505Y+034637X0198Y0197     S1      
327GND              R183  -2          A01X+078152Y+044250X0198Y0197R180 S1      
327GND              R179  -2          A18X+076394Y+039392X0198Y0197R180 S2      
327GND              R168  -2          A18X+076394Y+040992X0198Y0197R180 S2      
327GND              U23   -3          A18X+072677Y+045163X0240Y0240R270 S2      
327GND              C971  -1          A01X+073239Y+010170X0198Y0197R270 S1      
327GND              PC934 -2   M      A01X+067903Y+010475X0198Y0197R270 S1      
327GND              C970  -1          A01X+063003Y+010170X0198Y0197R270 S1      
327GND              PC926 -2   M      A01X+057667Y+010475X0198Y0197R270 S1      
327GND              PR7109-2   M      A01X+057267Y+010475X0198Y0197R270 S1      
327GND              C969  -1          A01X+052766Y+010170X0198Y0197R270 S1      
327GND              PC924 -2   M      A01X+047431Y+010475X0198Y0197R270 S1      
327GND              R6064 -2          A01X+042892Y+015154X0198Y0197R180 S1      
327GND              C968  -1          A01X+037766Y+010170X0198Y0197R270 S1      
327GND              PC662 -2          A01X+034745Y+045833X0198Y0197R180 S1      
327GND              R77   -2          A18X+030686Y+039392X0198Y0197R180 S2      
327GND              R66   -2          A18X+030686Y+040992X0198Y0197R180 S2      
327GND              PC686 -2   M      A01X+032431Y+010475X0198Y0197R270 S1      
327GND              PC529 -2          A01X+033118Y+023612X0198Y0197R090 S1      
327GND              U13   -3          A18X+026968Y+045163X0240Y0240R270 S2      
327GND              U400  -S          A01X+029655Y+010792X0400Y0560R180 S1      
327GND              C3668 -2          A01X+028258Y+019194X0198Y0197R180 S1      
327GND              C967  -1          A01X+027530Y+010170X0198Y0197R270 S1      
327GND              PC684 -2   M      A01X+022194Y+010475X0198Y0197R270 S1      
327GND              U365  -S          A01X+022755Y+015330X0400Y0560     S1      
327GND              C966  -1          A01X+017294Y+010170X0198Y0197R270 S1      
327GND              PC676 -2   M      A01X+011958Y+010475X0198Y0197R270 S1      
327GND              PC672 -2          A01X+011761Y+013090X0198Y0197R090 S1      
327GND              C965  -1          A01X+007058Y+010170X0198Y0197R270 S1      
327GND              C2881 -2          A01X+049532Y+047898X0198Y0197R180 S1      
327GND              PR7062-2   M      A01X+181501Y+045260X0198Y0197     S1      
327GND              PR7038-2   M      A01X+135792Y+045260X0198Y0197     S1      
327GND              PU74  -7          A01X+092451Y+046038X0100Y0320R090 S1      
327GND              PR6902-2   M      A01X+093907Y+046894X0198Y0197     S1      
327GND              PR7112-2   M      A01X+067103Y+010475X0198Y0197R270 S1      
327GND              PR7111-2   M      A01X+067503Y+010475X0198Y0197R270 S1      
327GND              PR6878-2   M      A01X+044375Y+045260X0198Y0197     S1      
327GND              PJ10  -2          A01X+006853Y+120156X0180Y0200R180 S1      
317GND              VIA   -    MD0100PA00X+007095Y+120156X0200Y         S0      
327GND              PJ14  -2          A01X+097620Y+121057X0180Y0200R180 S1      
317GND              VIA   -    MD0100PA00X+097861Y+121057X0200Y         S0      
327GND              PC296 -2          A01X+039905Y+088435X0198Y0197R090 S1      
327GND              PR187 -2   M      A01X+040297Y+088445X0198Y0197R090 S1      
327GND              PC221 -2          A01X+005770Y+119567X0198Y0197R270 S1      
327GND              PR167 -2   M      A01X+005374Y+119683X0198Y0197R270 S1      
327GND              R1223 -2   M      A18X+043248Y+132237X0198Y0197R270 S2      
327GND              C2703 -2          A18X+042853Y+132068X0198Y0197R180 S2      
327GND              C4007 -2          A18X+080007Y+096145X0198Y0197R090 S2      
327GND              R6179 -2          A18X+128789Y+088565X0198Y0197     S2      
327GND              R6415 -1   M      A18X+128789Y+088180X0198Y0197R180 S2      
327GND              Q124  -S          A18X+127605Y+093514X0240Y0320R090 S2      
327GND              U423  -12         A18X+082663Y+100209X0120Y0630R180 S2      
327GND              R6399 -1   M      A01X+171826Y+114607X0198Y0197R180 S1      
327GND              U428  -4          A01X+171764Y+115324X0140Y0520     S1      
327GND              C4379 -2   M      A18X+137949Y+124411X0120Y0150     S2      
327GND              C4365 -2          A18X+137949Y+124751X0120Y0150     S2      
327GND              C1668 -2          A18X+137858Y+125840X0280Y0320R270 S2      
327GND              C4336 -2          A01X+091184Y+102810X0120Y0150R180 S1      
327GND              C4337 -2   M      A01X+091189Y+102289X0120Y0150R180 S1      
327GND              C4224 -2          A01X+006929Y+104614X0120Y0150     S1      
327GND              C4225 -2   M      A01X+006926Y+105078X0120Y0150     S1      
327GND              C4238 -2          A01X+006931Y+105565X0120Y0150     S1      
327GND              C4239 -2   M      A01X+006937Y+106081X0120Y0150     S1      
327GND              C4350 -2          A18X+091001Y+100854X0120Y0150     S2      
327GND              C4351 -2   M      A18X+090996Y+101175X0120Y0150     S2      
327GND              R476  -2          A01X+093764Y+082348X0198Y0197R270 S1      
327GND              C193  -2   M      A01X+094154Y+082348X0198Y0197R270 S1      
327GND              C196  -2   M      A01X+094894Y+083333X0198Y0197R090 S1      
327GND              R480  -2          A01X+094504Y+083333X0198Y0197R090 S1      
327GND              C4434 -2   M      A01X+095010Y+085358X0198Y0197R090 S1      
327GND              C4435 -2   M      A01X+095110Y+083852X0198Y0197R270 S1      
327GND              C3605 -2          A18X+092074Y+084687X0164Y0164R180 S2      
327GND              C2747 -2          A01X+110461Y+160675X0198Y0197R090 S1      
327GND              U320  -10  M      A01X+051544Y+090030X0320Y0750R270 S1      
327GND              JPEX1 -10         A01X+051607Y+090030X0200Y0600R090 S1      
327GND              U64   -3          A18X+115343Y+077224X0240Y0420     S2      
327GND              C4453 -2          A01X+180727Y+147081X0120Y0150R270 S1      
327GND              C4458 -2   M      A01X+097666Y+083180X0198Y0197     S1      
327GND              R6714 -2          A01X+097667Y+082791X0198Y0197     S1      
327GND              R6772 -2          A01X+143679Y+155537X0198Y0197R270 S1      
327GND              C4485 -2          A01X+102126Y+131660X0198Y0197R090 S1      
327GND              R6798 -2   M      A01X+102540Y+131658X0180Y0200R270 S1      
327GND              R1250 -1   M      A01X+035840Y+119542X0198Y0197R090 S1      
327GND              R1247 -1          A01X+035040Y+119542X0198Y0197R090 S1      
327GND              R1248 -1   M      A01X+035440Y+119542X0198Y0197R090 S1      
327GND              R6818 -1          A18X+093875Y+088514X0198Y0197R090 S2      
327GND              C4490 -2   M      A18X+093494Y+088514X0198Y0197R270 S2      
327GND              C4488 -2          A18X+081697Y+087281X0198Y0197R180 S2      
327GND              R6819 -1   M      A18X+081697Y+086908X0198Y0197     S2      
327GND              R6816 -1          A18X+094906Y+092304X0198Y0197R090 S2      
327GND              C4489 -2          A18X+095296Y+092306X0198Y0197R270 S2      
327GND              C4492 -2          A01X+101093Y+135371X0198Y0197R180 S1      
327GND              C4494 -2          A01X+051458Y+078938X0198Y0197R090 S1      
327GND              C4495 -2   M      A01X+051976Y+078930X0198Y0197R090 S1      
327GND              R6835 -2          A01X+137850Y+093740X0198Y0197R090 S1      
327GND              R6834 -2   M      A01X+138256Y+093740X0198Y0197R090 S1      
327GND              PEX0  -AJ12       A01X+018622Y+115000X0180Y         S1      
327m5588            C743  -1          A01X+153831Y+140149X0120Y0150R090 S1      
317m5588            VIA   -    MD0100PA01X+153821Y+139658X0180Y         S0      
317m5588            VIA   -    MD0080PA01X+163602Y+123602X0160Y    R270 S0      
327m5588            PEX3  -F33        A01X+163602Y+123602X0180Y         S1      
317m5589            J3    -P5   D0122PA01X+014453Y+150468X0282Y    R180 S3      
317m5589            VIA   -    MD0080PA01X+015630Y+124350X0160Y         S0      
327m5589            PEX0  -D4         A01X+015630Y+124350X0180Y         S1      
317m5590            VIA   -    MD0100PA01X+026610Y+134819X0180Y         S0      
317m5590            VIA   -    MD0080PA01X+017874Y+122480X0160Y         S0      
327m5590            PEX0  -J10        A01X+017874Y+122480X0180Y         S1      
327m5590            C133  -1          A01X+026600Y+135309X0120Y0150R090 S1      
327m5591            C756  -1          A01X+154695Y+135309X0120Y0150R090 S1      
317m5591            VIA   -    MD0100PA01X+154705Y+134819X0180Y         S0      
317m5591            VIA   -    MD0080PA01X+160984Y+122480X0160Y    R270 S0      
327m5591            PEX3  -J26        A01X+160984Y+122480X0180Y         S1      
317m5592            J3    -N6   D0122PA01X+015319Y+151413X0282Y    R180 S3      
317m5592            VIA   -    MD0080PA01X+016004Y+125472X0160Y         S0      
327m5592            PEX0  -A5         A01X+016004Y+125472X0180Y         S1      
317m5593            VIA   -    MD0100PA01X+030282Y+137238X0180Y         S0      
317m5593            VIA   -    MD0080PA01X+019744Y+123228X0160Y    R270 S0      
327m5593            PEX0  -G15        A01X+019744Y+123228X0180Y         S1      
327m5593            C143  -1          A01X+030272Y+137729X0120Y0150R090 S1      
317m5594            VIA   -    MD0080PA01X+159862Y+109764X0160Y    R270 S0      
327m5594            PEX3  -BC23       A01X+159862Y+109764X0180Y         S1      
317m5594            VIA   -    MD0100PA01X+176475Y+012174X0200Y    R090 S0      
327m5594            C726  -1          A01X+175985Y+012184X0120Y0150R180 S1      
317m5595            J3    -N8   D0122PA01X+017051Y+151413X0282Y    R180 S3      
317m5595            VIA   -    MD0080PA01X+016752Y+125472X0160Y         S0      
327m5595            PEX0  -A7         A01X+016752Y+125472X0180Y         S1      
317m5596            VIA   -    MD0100PA01X+024502Y+134819X0180Y         S0      
317m5596            VIA   -    MD0080PA01X+017126Y+122854X0160Y         S0      
327m5596            PEX0  -H8         A01X+017126Y+122854X0180Y         S1      
327m5596            C130  -1          A01X+024512Y+135309X0120Y0150R090 S1      
327m5597            C750  -1          A01X+157143Y+135309X0120Y0150R090 S1      
317m5597            VIA   -    MD0100PA01X+157153Y+134819X0180Y         S0      
317m5597            VIA   -    MD0080PA01X+162106Y+123228X0160Y    R270 S0      
327m5597            PEX3  -G29        A01X+162106Y+123228X0180Y         S1      
317m5598            J11   -X6   D0122PA01X+032642Y+146295X0282Y    R180 S3      
317m5598            VIA   -    MD0080PA01X+027972Y+125098X0160Y    R090 S0      
327m5598            PEX0  -B37        A01X+027972Y+125098X0180Y         S1      
317m5599            VIA   -    MD0080PA01X+113779Y+110138X0160Y    R270 S0      
327m5599            PEX2  -BB22       A01X+113780Y+110138X0180Y         S1      
317m5599            VIA   -    MD0100PA01X+129726Y+012540X0200Y    R090 S0      
327m5599            C514  -1          A01X+129236Y+012530X0120Y0150R180 S1      
327m5600            C730  -1          A01X+158367Y+140149X0120Y0150R090 S1      
317m5600            VIA   -    MD0100PA01X+158377Y+139658X0180Y         S0      
317m5600            VIA   -    MD0080PA01X+165846Y+123228X0160Y    R270 S0      
327m5600            PEX3  -G39        A01X+165846Y+123228X0180Y         S1      
317m5601            J11   -Y7   D0122PA01X+033508Y+145862X0282Y    R180 S3      
317m5601            VIA   -    MD0080PA01X+028346Y+124350X0160Y         S0      
327m5601            PEX0  -D38        A01X+028346Y+124350X0180Y         S1      
317m5602            VIA   -    MD0100PA01X+115263Y+138430X0180Y         S0      
317m5602            J7    -V5   D0122PA01X+116650Y+147398X0282Y    R180 S3      
327m5602            C589  -2          A01X+115253Y+137939X0120Y0150R090 S1      
327m5603            C522  -1          A01X+134399Y+140149X0120Y0150R090 S1      
317m5603            VIA   -    MD0100PA01X+134389Y+139658X0180Y         S0      
317m5603            VIA   -    MD0080PA01X+119764Y+122854X0160Y    R270 S0      
327m5603            PEX2  -H38        A01X+119764Y+122854X0180Y         S1      
317m5604            VIA   -    MD0080PA01X+158366Y+109764X0160Y    R270 S0      
327m5604            PEX3  -BC19       A01X+158366Y+109764X0180Y         S1      
317m5604            VIA   -    MD0100PA01X+166239Y+012174X0200Y    R090 S0      
327m5604            C718  -1          A01X+165748Y+012184X0120Y0150R180 S1      
317m5605            J11   -X5   D0122PA01X+031776Y+146374X0282Y    R180 S3      
317m5605            VIA   -    MD0080PA01X+027598Y+124724X0160Y         S0      
327m5605            PEX0  -C36        A01X+027598Y+124724X0180Y         S1      
317m5606            VIA   -    MD0100PA01X+116827Y+140850X0180Y         S0      
317m5606            J7    -U7   D0122PA01X+118382Y+147910X0282Y    R180 S3      
327m5606            C586  -2          A01X+116837Y+140359X0120Y0150R090 S1      
317m5607            VIA   -    MD0100PA01X+035518Y+137238X0180Y         S0      
317m5607            VIA   -    MD0080PA01X+021988Y+123602X0160Y    R270 S0      
327m5607            PEX0  -F21        A01X+021988Y+123602X0180Y         S1      
327m5607            C156  -1          A01X+035528Y+137729X0120Y0150R090 S1      
317m5608            VIA   -    MD0100PA01X+063853Y+140850X0180Y         S0      
317m5608            J5    -I2   D0122PA01X+063823Y+158067X0282Y    R180 S3      
327m5608            C400  -2          A01X+063843Y+140359X0120Y0150R090 S1      
327m5609            C544  -1          A01X+125831Y+137729X0120Y0150R090 S1      
317m5609            VIA   -    MD0100PA01X+125821Y+137238X0180Y         S0      
317m5609            VIA   -    MD0080PA01X+115650Y+123602X0160Y    R270 S0      
327m5609            PEX2  -F27        A01X+115650Y+123602X0180Y         S1      
317m5610            VIA   -    MD0080PA01X+159488Y+110138X0160Y    R270 S0      
327m5610            PEX3  -BB22       A01X+159488Y+110138X0180Y         S1      
317m5610            VIA   -    MD0100PA01X+175435Y+012540X0200Y    R090 S0      
327m5610            C725  -1          A01X+174944Y+012530X0120Y0150R180 S1      
317m5611            J11   -W8   D0122PA01X+034374Y+146807X0282Y    R180 S3      
317m5611            VIA   -    MD0080PA01X+028720Y+125472X0160Y    R090 S0      
327m5611            PEX0  -A39        A01X+028720Y+125472X0180Y         S1      
317m5612            VIA   -    MD0100PA01X+114379Y+136010X0180Y         S0      
317m5612            J7    -U3   D0122PA01X+114917Y+147910X0282Y    R180 S3      
327m5612            C593  -2          A01X+114389Y+135519X0120Y0150R090 S1      
317m5613            VIA   -    MD0100PA01X+029398Y+139658X0180Y         S0      
317m5613            VIA   -    MD0080PA01X+019370Y+122854X0160Y         S0      
327m5613            PEX0  -H14        A01X+019370Y+122854X0180Y         S1      
327m5613            C142  -1          A01X+029408Y+140149X0120Y0150R090 S1      
327m5614            C523  -1          A01X+134039Y+135309X0120Y0150R090 S1      
317m5614            VIA   -    MD0100PA01X+134049Y+134819X0180Y         S0      
317m5614            VIA   -    MD0080PA01X+119390Y+123228X0160Y    R270 S0      
327m5614            PEX2  -G37        A01X+119390Y+123228X0180Y         S1      
327m5615            C740  -1          A01X+154695Y+137729X0120Y0150R090 S1      
317m5615            VIA   -    MD0100PA01X+154705Y+137238X0180Y         S0      
317m5615            VIA   -    MD0080PA01X+163976Y+122480X0160Y    R270 S0      
327m5615            PEX3  -J34        A01X+163976Y+122480X0180Y         S1      
317m5616            J11   -Y5   D0122PA01X+031776Y+145862X0282Y    R180 S3      
317m5616            VIA   -    MD0080PA01X+027598Y+124350X0160Y         S0      
327m5616            PEX0  -D36        A01X+027598Y+124350X0180Y         S1      
317m5617            VIA   -    MD0100PA01X+033070Y+137238X0180Y         S0      
317m5617            VIA   -    MD0080PA01X+020866Y+122854X0160Y         S0      
327m5617            PEX0  -H18        A01X+020866Y+122854X0180Y         S1      
327m5617            C150  -1          A01X+033080Y+137729X0120Y0150R090 S1      
317m5618            VIA   -    MD0080PA01X+111909Y+109390X0160Y    R270 S0      
327m5618            PEX2  -BD17       A01X+111909Y+109390X0180Y         S1      
327m5618            C504  -1          A01X+120040Y+013241X0120Y0150R180 S1      
317m5618            VIA   -    MD0100PA01X+120530Y+013251X0200Y    R090 S0      
317m5619            VIA   -    MD0080PA01X+156122Y+109764X0160Y    R270 S0      
327m5619            PEX3  -BC13       A01X+156122Y+109764X0180Y         S1      
317m5619            VIA   -    MD0100PA01X+156003Y+013591X0200Y    R090 S0      
327m5619            C706  -1          A01X+155512Y+013601X0120Y0150R180 S1      
317m5620            VIA   -    MD0100PA01X+014955Y+138430X0180Y         S0      
317m5620            J3    -U2   D0122PA01X+011854Y+147831X0282Y    R180 S3      
327m5620            C174  -2          A01X+014945Y+137939X0120Y0150R090 S1      
327m5621            C525  -1          A01X+132815Y+137729X0120Y0150R090 S1      
317m5621            VIA   -    MD0100PA01X+132825Y+137238X0180Y         S0      
317m5621            VIA   -    MD0080PA01X+119016Y+122480X0160Y    R270 S0      
327m5621            PEX2  -J36        A01X+119016Y+122480X0180Y         S1      
317m5622            VIA   -    MD0080PA01X+156870Y+109764X0160Y    R270 S0      
327m5622            PEX3  -BC15       A01X+156870Y+109764X0180Y         S1      
317m5622            VIA   -    MD0100PA01X+156003Y+012174X0200Y    R090 S0      
327m5622            C710  -1          A01X+155512Y+012184X0120Y0150R180 S1      
317m5623            VIA   -    MD0100PA01X+013731Y+140850X0180Y         S0      
317m5623            J3    -V1   D0122PA01X+010988Y+147398X0282Y    R180 S3      
327m5623            C175  -2          A01X+013721Y+140359X0120Y0150R090 S1      
317m5624            VIA   -    MD0080PA01X+112283Y+110512X0160Y    R270 S0      
327m5624            C505  -1          A01X+119000Y+012890X0120Y0150R180 S1      
317m5624            VIA   -    MD0100PA01X+119490Y+012880X0200Y    R090 S0      
327m5624            PEX2  -BA18       A01X+112283Y+110512X0180Y         S1      
317m5625            VIA   -    MD0080PA01X+158366Y+109390X0160Y    R270 S0      
327m5625            PEX3  -BD19       A01X+158366Y+109390X0180Y         S1      
317m5625            VIA   -    MD0100PA01X+166239Y+011834X0200Y    R090 S0      
327m5625            C719  -1          A01X+165748Y+011824X0120Y0150R180 S1      
317m5626            VIA   -    MD0100PA01X+032730Y+136010X0180Y         S0      
317m5626            J11   -S3   D0122PA01X+030043Y+148933X0282Y    R180 S3      
327m5626            C107  -2          A01X+032720Y+135519X0120Y0150R090 S1      
317m5627            VIA   -    MD0100PA01X+117711Y+138430X0180Y         S0      
317m5627            J7    -U8   D0122PA01X+119248Y+147831X0282Y    R180 S3      
327m5627            C583  -2          A01X+117701Y+137939X0120Y0150R090 S1      
317m5628            VIA   -    MD0100PA01X+062629Y+140850X0180Y         S0      
317m5628            J5    -J1   D0122PA01X+062957Y+157634X0282Y    R180 S3      
327m5628            C402  -2          A01X+062619Y+140359X0120Y0150R090 S1      
317m5629            VIA   -    MD0080PA01X+112657Y+109764X0160Y    R270 S0      
327m5629            PEX2  -BC19       A01X+112657Y+109764X0180Y         S1      
327m5629            C507  -1          A01X+120040Y+012184X0120Y0150R180 S1      
317m5629            VIA   -    MD0100PA01X+120530Y+012174X0200Y    R090 S0      
327m5630            C737  -1          A01X+156279Y+140149X0120Y0150R090 S1      
317m5630            VIA   -    MD0100PA01X+156269Y+139658X0180Y         S0      
317m5630            VIA   -    MD0080PA01X+164724Y+122854X0160Y    R270 S0      
327m5630            PEX3  -H36        A01X+164724Y+122854X0180Y         S1      
317m5631            VIA   -    MD0100PA01X+032730Y+140850X0180Y         S0      
317m5631            J11   -R4   D0122PA01X+030909Y+149366X0282Y    R180 S3      
327m5631            C105  -2          A01X+032720Y+140359X0120Y0150R090 S1      
317m5632            VIA   -    MD0080PA01X+017500Y+123228X0160Y    R270 S0      
317m5632            VIA   -    MD0100PA01X+025386Y+137238X0180Y         S0      
327m5632            PEX0  -G9         A01X+017500Y+123228X0180Y         S1      
327m5632            C131  -1          A01X+025376Y+137729X0120Y0150R090 S1      
327m5633            C520  -1          A01X+135623Y+137729X0120Y0150R090 S1      
317m5633            VIA   -    MD0100PA01X+135613Y+137238X0180Y         S0      
317m5633            VIA   -    MD0080PA01X+120138Y+123602X0160Y    R270 S0      
327m5633            PEX2  -F39        A01X+120138Y+123602X0180Y         S1      
327m5634            C733  -1          A01X+158727Y+135309X0120Y0150R090 S1      
317m5634            VIA   -    MD0100PA01X+158717Y+134819X0180Y         S0      
317m5634            VIA   -    MD0080PA01X+165472Y+122854X0160Y    R270 S0      
327m5634            PEX3  -H38        A01X+165472Y+122854X0180Y         S1      
317m5635            VIA   -    MD0100PA01X+033070Y+140850X0180Y         S0      
317m5635            J11   -Q4   D0122PA01X+030909Y+149878X0282Y    R180 S3      
327m5635            C106  -2          A01X+033080Y+140359X0120Y0150R090 S1      
317m5636            VIA   -    MD0100PA01X+033954Y+134819X0180Y         S0      
317m5636            VIA   -    MD0080PA01X+021240Y+123228X0160Y    R270 S0      
327m5636            C151  -1          A01X+033944Y+135309X0120Y0150R090 S1      
327m5636            PEX0  -G19        A01X+021240Y+123228X0180Y         S1      
327m5637            C540  -1          A01X+127055Y+140149X0120Y0150R090 S1      
317m5637            VIA   -    MD0100PA01X+127045Y+139658X0180Y         S0      
317m5637            VIA   -    MD0080PA01X+116398Y+123602X0160Y    R270 S0      
327m5637            PEX2  -F29        A01X+116398Y+123602X0180Y         S1      
327m5638            C760  -1          A01X+152247Y+140149X0120Y0150R090 S1      
317m5638            VIA   -    MD0100PA01X+152257Y+139658X0180Y         S0      
317m5638            VIA   -    MD0080PA01X+160236Y+122480X0160Y         S0      
327m5638            PEX3  -J24        A01X+160236Y+122480X0180Y         S1      
317m5639            VIA   -    MD0100PA01X+030622Y+140850X0180Y         S0      
317m5639            J11   -R1   D0122PA01X+028311Y+149445X0282Y    R180 S3      
327m5639            C112  -2          A01X+030632Y+140359X0120Y0150R090 S1      
317m5640            VIA   -    MD0100PA01X+026610Y+139658X0180Y    R180 S0      
317m5640            VIA   -    MD0080PA01X+018248Y+123228X0160Y    R270 S0      
327m5640            PEX0  -G11        A01X+018248Y+123228X0180Y         S1      
327m5640            C135  -1          A01X+026600Y+140149X0120Y0150R090 S1      
327m5641            C543  -1          A01X+125471Y+137729X0120Y0150R090 S1      
317m5641            VIA   -    MD0100PA01X+125481Y+137238X0180Y         S0      
317m5641            VIA   -    MD0080PA01X+115650Y+123228X0160Y    R270 S0      
327m5641            PEX2  -G27        A01X+115650Y+123228X0180Y         S1      
327m5642            C758  -1          A01X+153471Y+137729X0120Y0150R090 S1      
317m5642            VIA   -    MD0100PA01X+153481Y+137238X0180Y         S0      
317m5642            VIA   -    MD0080PA01X+160610Y+123228X0160Y    R270 S0      
327m5642            PEX3  -G25        A01X+160610Y+123228X0180Y         S1      
317m5643            VIA   -    MD0100PA01X+016179Y+140850X0180Y         S0      
317m5643            J3    -U4   D0122PA01X+013587Y+147831X0282Y    R180 S3      
327m5643            C169  -2          A01X+016169Y+140359X0120Y0150R090 S1      
317m5644            VIA   -    MD0100PA01X+113155Y+138430X0180Y         S0      
317m5644            J7    -T2   D0122PA01X+114051Y+148343X0282Y    R180 S3      
327m5644            C595  -2          A01X+113165Y+137939X0120Y0150R090 S1      
317m5645            VIA   -    MD0100PA01X+031506Y+134819X0180Y         S0      
317m5645            VIA   -    MD0080PA01X+020118Y+122480X0160Y         S0      
327m5645            PEX0  -J16        A01X+020118Y+122480X0180Y         S1      
327m5645            C145  -1          A01X+031496Y+135309X0120Y0150R090 S1      
317m5646            VIA   -    MD0080PA01X+114154Y+109764X0160Y    R270 S0      
327m5646            PEX2  -BC23       A01X+114154Y+109764X0180Y         S1      
317m5646            VIA   -    MD0100PA01X+130767Y+012174X0200Y    R090 S0      
327m5646            C515  -1          A01X+130276Y+012184X0120Y0150R180 S1      
317m5647            VIA   -    MD0080PA01X+157618Y+109764X0160Y    R270 S0      
327m5647            PEX3  -BC17       A01X+157618Y+109764X0180Y         S1      
317m5647            VIA   -    MD0100PA01X+166239Y+013591X0200Y    R090 S0      
327m5647            C714  -1          A01X+165748Y+013601X0120Y0150R180 S1      
317m5648            VIA   -    MD0100PA01X+031506Y+138430X0180Y         S0      
317m5648            J11   -R2   D0122PA01X+029177Y+149366X0282Y    R180 S3      
327m5648            C109  -2          A01X+031496Y+137939X0120Y0150R090 S1      
317m5649            VIA   -    MD0100PA01X+111591Y+140850X0180Y         S0      
317m5649            J7    -V1   D0122PA01X+113185Y+147398X0282Y    R180 S3      
327m5649            C597  -2          A01X+111581Y+140359X0120Y0150R090 S1      
317m5650            VIA   -    MD0100PA01X+035178Y+137238X0180Y         S0      
317m5650            VIA   -    MD0080PA01X+021988Y+123228X0160Y    R270 S0      
327m5650            PEX0  -G21        A01X+021988Y+123228X0180Y         S1      
327m5650            C155  -1          A01X+035168Y+137729X0120Y0150R090 S1      
317m5651            VIA   -    MD0080PA01X+110787Y+110512X0160Y    R270 S0      
327m5651            C497  -1          A01X+108763Y+012890X0120Y0150R180 S1      
317m5651            VIA   -    MD0100PA01X+109254Y+012880X0200Y    R090 S0      
327m5651            PEX2  -BA14       A01X+110787Y+110512X0180Y         S1      
327m5652            C757  -1          A01X+155055Y+135309X0120Y0150R090 S1      
317m5652            VIA   -    MD0100PA01X+155045Y+134819X0180Y         S0      
317m5652            VIA   -    MD0080PA01X+160984Y+122854X0160Y    R270 S0      
327m5652            PEX3  -H26        A01X+160984Y+122854X0180Y         S1      
317m5653            VIA   -    MD0100PA01X+030282Y+140850X0180Y         S0      
317m5653            J11   -S1   D0122PA01X+028311Y+148933X0282Y    R180 S3      
327m5653            C111  -2          A01X+030272Y+140359X0120Y0150R090 S1      
317m5654            VIA   -    MD0100PA01X+027834Y+137238X0180Y         S0      
317m5654            VIA   -    MD0080PA01X+018622Y+122480X0160Y         S0      
327m5654            PEX0  -J12        A01X+018622Y+122480X0180Y         S1      
327m5654            C137  -1          A01X+027824Y+137729X0120Y0150R090 S1      
317m5655            VIA   -    MD0080PA01X+108917Y+109390X0160Y    R270 S0      
327m5655            PEX2  -BD9        A01X+108917Y+109390X0180Y         S1      
327m5655            C488  -1          A01X+099567Y+013241X0120Y0150R180 S1      
317m5655            VIA   -    MD0100PA01X+100058Y+013251X0200Y    R090 S0      
317m5656            VIA   -    MD0080PA01X+155748Y+110512X0160Y    R270 S0      
327m5656            PEX3  -BA12       A01X+155748Y+110512X0180Y         S1      
317m5656            VIA   -    MD0100PA01X+144726Y+011462X0200Y    R090 S0      
327m5656            C704  -1          A01X+144236Y+011472X0120Y0150R180 S1      
317m5657            VIA   -    MD0100PA01X+016179Y+136010X0180Y         S0      
317m5657            J3    -V3   D0122PA01X+012720Y+147398X0282Y    R180 S3      
327m5657            C172  -2          A01X+016169Y+135519X0120Y0150R090 S1      
317m5658            VIA   -    MD0100PA01X+031506Y+139658X0180Y         S0      
317m5658            VIA   -    MD0080PA01X+020492Y+123228X0160Y    R270 S0      
327m5658            C147  -1          A01X+031496Y+140149X0120Y0150R090 S1      
327m5658            PEX0  -G17        A01X+020492Y+123228X0180Y         S1      
327m5659            C533  -1          A01X+129143Y+140149X0120Y0150R090 S1      
317m5659            VIA   -    MD0100PA01X+129153Y+139658X0180Y         S0      
317m5659            VIA   -    MD0080PA01X+117520Y+122480X0160Y    R270 S0      
327m5659            PEX2  -J32        A01X+117520Y+122480X0180Y         S1      
327m5660            C755  -1          A01X+155055Y+140149X0120Y0150R090 S1      
317m5660            VIA   -    MD0100PA01X+155045Y+139658X0180Y         S0      
317m5660            VIA   -    MD0080PA01X+161358Y+123602X0160Y    R270 S0      
327m5660            PEX3  -F27        A01X+161358Y+123602X0180Y         S1      
317m5661            VIA   -    MD0100PA01X+016519Y+140850X0180Y         S0      
317m5661            J3    -T4   D0122PA01X+013587Y+148343X0282Y    R180 S3      
327m5661            C170  -2          A01X+016529Y+140359X0120Y0150R090 S1      
327m5662            C526  -1          A01X+133175Y+137729X0120Y0150R090 S1      
317m5662            VIA   -    MD0100PA01X+133165Y+137238X0180Y         S0      
317m5662            VIA   -    MD0080PA01X+119016Y+122854X0160Y    R270 S0      
327m5662            PEX2  -H36        A01X+119016Y+122854X0180Y         S1      
327m5663            C751  -1          A01X+157503Y+135309X0120Y0150R090 S1      
317m5663            VIA   -    MD0100PA01X+157493Y+134819X0180Y         S0      
317m5663            VIA   -    MD0080PA01X+162106Y+123602X0160Y    R270 S0      
327m5663            PEX3  -F29        A01X+162106Y+123602X0180Y         S1      
317m5664            VIA   -    MD0100PA01X+014071Y+140850X0180Y         S0      
317m5664            J3    -U1   D0122PA01X+010988Y+147910X0282Y    R180 S3      
327m5664            C176  -2          A01X+014081Y+140359X0120Y0150R090 S1      
317m5665            VIA   -    MD0100PA01X+116487Y+136010X0180Y         S0      
317m5665            J7    -U6   D0122PA01X+117516Y+147831X0282Y    R180 S3      
327m5665            C587  -2          A01X+116477Y+135519X0120Y0150R090 S1      
327m5666            C105  -1          A01X+032720Y+140149X0120Y0150R090 S1      
317m5666            VIA   -    MD0100PA01X+032730Y+139658X0180Y         S0      
317m5666            VIA   -    MD0080PA01X+027224Y+123228X0160Y    R270 S0      
327m5666            PEX0  -G35        A01X+027224Y+123228X0180Y         S1      
317m5667            VIA   -    MD0080PA01X+114528Y+110138X0160Y    R270 S0      
327m5667            PEX2  -BB24       A01X+114528Y+110138X0180Y         S1      
317m5667            VIA   -    MD0100PA01X+129726Y+011122X0200Y    R090 S0      
327m5667            C518  -1          A01X+129236Y+011112X0120Y0150R180 S1      
317m5668            VIA   -    MD0080PA01X+159114Y+109764X0160Y    R270 S0      
327m5668            PEX3  -BC21       A01X+159114Y+109764X0180Y         S1      
317m5668            VIA   -    MD0100PA01X+176475Y+013591X0200Y    R090 S0      
327m5668            C722  -1          A01X+175985Y+013601X0120Y0150R180 S1      
317m5669            VIA   -    MD0100PA01X+031846Y+138430X0180Y         S0      
317m5669            J11   -Q2   D0122PA01X+029177Y+149878X0282Y    R180 S3      
327m5669            C110  -2          A01X+031856Y+137939X0120Y0150R090 S1      
317m5670            VIA   -    MD0100PA01X+030622Y+137238X0180Y         S0      
317m5670            VIA   -    MD0080PA01X+019744Y+123602X0160Y    R270 S0      
327m5670            PEX0  -F15        A01X+019744Y+123602X0180Y         S1      
327m5670            C144  -1          A01X+030632Y+137729X0120Y0150R090 S1      
327m5671            C104  -1          A01X+034304Y+137729X0120Y0150R090 S1      
317m5671            VIA   -    MD0100PA01X+034294Y+137238X0180Y         S0      
317m5671            VIA   -    MD0080PA01X+027598Y+122854X0160Y    R270 S0      
327m5671            PEX0  -H36        A01X+027598Y+122854X0180Y         S1      
327m5672            C549  -1          A01X+123023Y+137729X0120Y0150R090 S1      
317m5672            VIA   -    MD0100PA01X+123033Y+137238X0180Y         S0      
317m5672            VIA   -    MD0080PA01X+114528Y+122480X0160Y         S0      
327m5672            PEX2  -J24        A01X+114528Y+122480X0180Y         S1      
317m5673            VIA   -    MD0080PA01X+156122Y+109390X0160Y         S0      
327m5673            PEX3  -BD13       A01X+156122Y+109390X0180Y         S1      
317m5673            VIA   -    MD0100PA01X+156003Y+013251X0200Y    R090 S0      
327m5673            C707  -1          A01X+155512Y+013241X0120Y0150R180 S1      
317m5674            VIA   -    MD0100PA01X+016519Y+136010X0180Y         S0      
317m5674            J3    -U3   D0122PA01X+012720Y+147910X0282Y    R180 S3      
327m5674            C171  -2          A01X+016529Y+135519X0120Y0150R090 S1      
317m5675            VIA   -    MD0100PA01X+131941Y+136010X0180Y         S0      
317m5675            J13   -R3   D0122PA01X+132240Y+149445X0282Y    R180 S3      
327m5675            C530  -2          A01X+131951Y+135519X0120Y0150R090 S1      
317m5676            VIA   -    MD0080PA01X+018248Y+109390X0160Y    R270 S0      
327m5676            PEX0  -BD11       A01X+018248Y+109390X0180Y         S1      
327m5676            C70   -1          A01X+008150Y+011824X0120Y0150R180 S1      
317m5676            VIA   -    MD0100PA01X+008641Y+011834X0200Y    R090 S0      
327m5677            C524  -1          A01X+134399Y+135309X0120Y0150R090 S1      
317m5677            VIA   -    MD0100PA01X+134389Y+134819X0180Y         S0      
317m5677            VIA   -    MD0080PA01X+119390Y+123602X0160Y    R270 S0      
327m5677            PEX2  -F37        A01X+119390Y+123602X0180Y         S1      
317m5678            VIA   -    MD0080PA01X+156496Y+110512X0160Y    R270 S0      
327m5678            PEX3  -BA14       A01X+156496Y+110512X0180Y         S1      
317m5678            VIA   -    MD0100PA01X+154963Y+012880X0200Y    R090 S0      
327m5678            C708  -1          A01X+154472Y+012890X0120Y0150R180 S1      
317m5679            VIA   -    MD0100PA01X+033070Y+136010X0180Y         S0      
317m5679            J11   -R3   D0122PA01X+030043Y+149445X0282Y    R180 S3      
327m5679            C108  -2          A01X+033080Y+135519X0120Y0150R090 S1      
317m5680            VIA   -    MD0100PA01X+134389Y+136010X0180Y         S0      
317m5680            J13   -Q6   D0122PA01X+134839Y+149878X0282Y    R180 S3      
327m5680            C524  -2          A01X+134399Y+135519X0120Y0150R090 S1      
317m5681            VIA   -    MD0100PA01X+026950Y+139658X0180Y    R180 S0      
317m5681            VIA   -    MD0080PA01X+018248Y+123602X0160Y    R270 S0      
327m5681            PEX0  -F11        A01X+018248Y+123602X0180Y         S1      
327m5681            C136  -1          A01X+026960Y+140149X0120Y0150R090 S1      
327m5682            C119  -1          A01X+027824Y+135309X0120Y0150R090 S1      
317m5682            VIA   -    MD0100PA01X+027834Y+134819X0180Y         S0      
317m5682            VIA   -    MD0080PA01X+024606Y+122480X0160Y    R270 S0      
327m5682            PEX0  -J28        A01X+024606Y+122480X0180Y         S1      
317m5683            VIA   -    MD0080PA01X+109291Y+110138X0160Y    R270 S0      
327m5683            PEX2  -BB10       A01X+109291Y+110138X0180Y         S1      
327m5683            C490  -1          A01X+098527Y+012530X0120Y0150R180 S1      
317m5683            VIA   -    MD0100PA01X+099018Y+012540X0200Y    R090 S0      
317m5684            VIA   -    MD0080PA01X+159488Y+110512X0160Y    R270 S0      
317m5684            VIA   -    MD0100PA01X+175435Y+012880X0200Y    R090 S0      
327m5684            C724  -1          A01X+174944Y+012890X0120Y0150R180 S1      
327m5684            PEX3  -BA22       A01X+159488Y+110512X0180Y         S1      
317m5685            VIA   -    MD0100PA01X+015295Y+138430X0180Y         S0      
317m5685            J3    -T2   D0122PA01X+011854Y+148343X0282Y    R180 S3      
327m5685            C173  -2          A01X+015305Y+137939X0120Y0150R090 S1      
317m5686            VIA   -    MD0080PA01X+019744Y+109764X0160Y    R270 S0      
327m5686            PEX0  -BC15       A01X+019744Y+109764X0180Y         S1      
327m5686            C77   -1          A01X+018386Y+012184X0120Y0150R180 S1      
317m5686            VIA   -    MD0100PA01X+018877Y+012174X0200Y    R090 S0      
317m5687            VIA   -    MD0080PA01X+109665Y+109390X0160Y    R270 S0      
327m5687            PEX2  -BD11       A01X+109665Y+109390X0180Y         S1      
327m5687            C492  -1          A01X+099567Y+011824X0120Y0150R180 S1      
317m5687            VIA   -    MD0100PA01X+100058Y+011834X0200Y    R090 S0      
327m5688            C759  -1          A01X+153831Y+137729X0120Y0150R090 S1      
317m5688            VIA   -    MD0100PA01X+153821Y+137238X0180Y         S0      
317m5688            VIA   -    MD0080PA01X+160610Y+123602X0160Y    R270 S0      
327m5688            PEX3  -F25        A01X+160610Y+123602X0180Y         S1      
327m5689            C825  -1          A01X+161490Y+135309X0120Y0150R090 S1      
317m5689            VIA   -    MD0100PA01X+161480Y+134819X0180Y         S0      
317m5689            VIA   -    MD0080PA01X+153504Y+118740X0160Y         S0      
327m5689            PEX3  -W6         A01X+153504Y+118740X0180Y         S1      
317m5690            VIA   -    MD0100PA01X+130377Y+138430X0180Y         S0      
317m5690            J13   -R2   D0122PA01X+131374Y+149366X0282Y    R180 S3      
327m5690            C531  -2          A01X+130367Y+137939X0120Y0150R090 S1      
317m5691            VIA   -    MD0080PA01X+018622Y+110512X0160Y    R270 S0      
327m5691            PEX0  -BA12       A01X+018622Y+110512X0180Y         S1      
327m5691            C71   -1          A01X+007110Y+011472X0120Y0150R180 S1      
317m5691            VIA   -    MD0100PA01X+007600Y+011462X0200Y    R090 S0      
327m5692            C546  -1          A01X+124607Y+140149X0120Y0150R090 S1      
317m5692            VIA   -    MD0100PA01X+124597Y+139658X0180Y         S0      
317m5692            VIA   -    MD0080PA01X+115276Y+122854X0160Y    R270 S0      
327m5692            PEX2  -H26        A01X+115276Y+122854X0180Y         S1      
327m5693            C746  -1          A01X+158367Y+137729X0120Y0150R090 S1      
317m5693            VIA   -    MD0100PA01X+158377Y+137238X0180Y         S0      
317m5693            VIA   -    MD0080PA01X+162854Y+123228X0160Y    R270 S0      
327m5693            PEX3  -G31        A01X+162854Y+123228X0180Y         S1      
327m5694            C773  -1          A01X+151383Y+135309X0120Y0150R090 S1      
317m5694            VIA   -    MD0100PA01X+151373Y+134819X0180Y         S0      
317m5694            VIA   -    MD0080PA01X+156122Y+123602X0160Y    R270 S0      
327m5694            PEX3  -F13        A01X+156122Y+123602X0180Y         S1      
317m5695            VIA   -    MD0100PA01X+114039Y+136010X0180Y         S0      
317m5695            J7    -V3   D0122PA01X+114917Y+147398X0282Y    R180 S3      
327m5695            C594  -2          A01X+114029Y+135519X0120Y0150R090 S1      
327m5696            C99   -1          A01X+035168Y+140149X0120Y0150R090 S1      
317m5696            VIA   -    MD0100PA01X+035178Y+139658X0180Y         S0      
317m5696            VIA   -    MD0080PA01X+028346Y+122480X0160Y    R270 S0      
327m5696            PEX0  -J38        A01X+028346Y+122480X0180Y         S1      
317m5697            VIA   -    MD0080PA01X+110039Y+110138X0160Y    R270 S0      
327m5697            PEX2  -BB12       A01X+110039Y+110138X0180Y         S1      
327m5697            C494  -1          A01X+098527Y+011112X0120Y0150R180 S1      
317m5697            VIA   -    MD0100PA01X+099018Y+011122X0200Y    R090 S0      
327m5698            C752  -1          A01X+155919Y+137729X0120Y0150R090 S1      
317m5698            VIA   -    MD0100PA01X+155929Y+137238X0180Y         S0      
317m5698            VIA   -    MD0080PA01X+161732Y+122480X0160Y    R270 S0      
327m5698            PEX3  -J28        A01X+161732Y+122480X0180Y         S1      
327m5699            C813  -1          A01X+166386Y+140149X0120Y0150R090 S1      
317m5699            VIA   -    MD0100PA01X+166376Y+139658X0180Y         S0      
317m5699            VIA   -    MD0080PA01X+153504Y+120984X0160Y         S0      
327m5699            PEX3  -N6         A01X+153504Y+120984X0180Y         S1      
317m5700            VIA   -    MD0100PA01X+024162Y+134819X0180Y         S0      
317m5700            VIA   -    MD0080PA01X+017126Y+122480X0160Y         S0      
327m5700            PEX0  -J8         A01X+017126Y+122480X0180Y         S1      
327m5700            C129  -1          A01X+024152Y+135309X0120Y0150R090 S1      
327m5701            U18   -4          A18X+067663Y+055780X0240Y0240R180 S2      
317m5701            VIA   -    M      A01X+068059Y+056800X0200Y         S2      
017m5701            VIA   -    M      A18X+068059Y+056800X0260Y         S2      
017m5701                  -    MD0100PA00X+068059Y+056800                       
327m5701            R137  -1   M      A01X+068726Y+055770X0198Y0197R180 S1      
327m5701            R139  -2          A01X+068726Y+054970X0198Y0197     S1      
327m5701            R140  -1   M      A01X+068726Y+055370X0198Y0197R180 S1      
327m5702            C125  -1          A01X+025376Y+135309X0120Y0150R090 S1      
317m5702            VIA   -    MD0100PA01X+025386Y+134819X0180Y         S0      
317m5702            VIA   -    MD0080PA01X+023484Y+123228X0160Y    R270 S0      
327m5702            PEX0  -G25        A01X+023484Y+123228X0180Y         S1      
317m5703            VIA   -    MD0080PA01X+113779Y+110512X0160Y    R270 S0      
317m5703            VIA   -    MD0100PA01X+129726Y+012880X0200Y    R090 S0      
327m5703            C513  -1          A01X+129236Y+012890X0120Y0150R180 S1      
327m5703            PEX2  -BA22       A01X+113780Y+110512X0180Y         S1      
317m5704            VIA   -    MD0080PA01X+160236Y+110138X0160Y    R270 S0      
327m5704            PEX3  -BB24       A01X+160236Y+110138X0180Y         S1      
317m5704            VIA   -    MD0100PA01X+175435Y+011122X0200Y    R090 S0      
327m5704            C729  -1          A01X+174944Y+011112X0120Y0150R180 S1      
327m5705            C771  -1          A01X+150159Y+137729X0120Y0150R090 S1      
317m5705            VIA   -    MD0100PA01X+150149Y+137238X0180Y         S0      
317m5705            VIA   -    MD0080PA01X+155748Y+122854X0160Y         S0      
327m5705            PEX3  -H12        A01X+155748Y+122854X0180Y         S1      
317m5706            VIA   -    MD0100PA01X+135273Y+138430X0180Y         S0      
317m5706            J13   -R8   D0122PA01X+136571Y+149366X0282Y    R180 S3      
327m5706            C519  -2          A01X+135263Y+137939X0120Y0150R090 S1      
327m5707            VIA   -    M      A18X+067259Y+054400X0260Y         S2      
327m5707            U18   -2          A18X+066955Y+055485X0160Y0240R090 S2      
327m5707            R138  -2          A18X+067759Y+053958X0198Y0197R270 S2      
317m5708            VIA   -    MD0080PA01X+022362Y+110512X0160Y    R270 S0      
327m5708            C91   -1          A01X+037818Y+012890X0120Y0150R180 S1      
317m5708            VIA   -    MD0100PA01X+038309Y+012880X0200Y    R090 S0      
327m5708            PEX0  -BA22       A01X+022362Y+110512X0180Y         S1      
317m5709            VIA   -    MD0080PA01X+113405Y+109764X0160Y    R270 S0      
327m5709            PEX2  -BC21       A01X+113405Y+109764X0180Y         S1      
317m5709            VIA   -    MD0100PA01X+130767Y+013591X0200Y    R090 S0      
327m5709            C511  -1          A01X+130276Y+013601X0120Y0150R180 S1      
327m5710            C747  -1          A01X+158727Y+137729X0120Y0150R090 S1      
317m5710            VIA   -    MD0100PA01X+158717Y+137238X0180Y         S0      
317m5710            VIA   -    MD0080PA01X+162854Y+123602X0160Y    R270 S0      
327m5710            PEX3  -F31        A01X+162854Y+123602X0180Y         S1      
327m5711            C810  -1          A01X+167250Y+137729X0120Y0150R090 S1      
317m5711            VIA   -    MD0100PA01X+167260Y+137238X0180Y         S0      
317m5711            VIA   -    MD0080PA01X+154626Y+121358X0160Y         S0      
327m5711            PEX3  -M9         A01X+154626Y+121358X0180Y         S1      
317m5712            J11   -X4   D0122PA01X+030909Y+146295X0282Y    R180 S3      
317m5712            VIA   -    MD0080PA01X+027224Y+125098X0160Y    R090 S0      
327m5712            PEX0  -B35        A01X+027224Y+125098X0180Y         S1      
317m5713            VIA   -    MD0100PA01X+115603Y+138430X0180Y         S0      
317m5713            J7    -U5   D0122PA01X+116650Y+147910X0282Y    R180 S3      
327m5713            C590  -2          A01X+115613Y+137939X0120Y0150R090 S1      
317m5714            VIA   -    MD0100PA01X+026950Y+134819X0180Y         S0      
317m5714            VIA   -    MD0080PA01X+017874Y+122854X0160Y         S0      
327m5714            PEX0  -H10        A01X+017874Y+122854X0180Y         S1      
327m5714            C134  -1          A01X+026960Y+135309X0120Y0150R090 S1      
317m5715            VIA   -    M      A01X+116687Y+044296X0200Y         S2      
017m5715            VIA   -    M      A18X+116687Y+044296X0260Y         S2      
017m5715                  -    MD0100PA00X+116687Y+044296                       
327m5715            U33   -4          A18X+118386Y+045871X0240Y0240R270 S2      
327m5715            R290  -1   M      A01X+116330Y+044587X0198Y0197     S1      
327m5715            R292  -2          A01X+116330Y+045387X0198Y0197R180 S1      
327m5715            R293  -1   M      A01X+116330Y+044987X0198Y0197     S1      
317HP_NIC3_PWRGD    VIA   -    M      A01X+077216Y+031489X0200Y         S2      
017HP_NIC3_PWRGD    VIA   -    M      A18X+077216Y+031489X0260Y         S2      
017HP_NIC3_PWRGD          -    MD0100PA00X+077216Y+031489                       
327HP_NIC3_PWRGD    U27   -1          A01X+077651Y+031285X0400Y0500     S1      
327HP_NIC3_PWRGD    R204  -2          A01X+076935Y+031874X0198Y0197R270 S1      
327HP_NIC3_PWRGD    R202  -2   M      A01X+076935Y+031489X0198Y0197R090 S1      
317m5716            VIA   -    MD0080PA01X+018996Y+109764X0160Y    R270 S0      
327m5716            PEX0  -BC13       A01X+018996Y+109764X0180Y         S1      
327m5716            C73   -1          A01X+018386Y+013601X0120Y0150R180 S1      
317m5716            VIA   -    MD0100PA01X+018877Y+013591X0200Y    R090 S0      
317m5717            VIA   -    MD0080PA01X+113031Y+110138X0160Y    R270 S0      
327m5717            PEX2  -BB20       A01X+113031Y+110138X0180Y         S1      
327m5717            C510  -1          A01X+119000Y+011112X0120Y0150R180 S1      
317m5717            VIA   -    MD0100PA01X+119490Y+011122X0200Y    R090 S0      
327m5718            C748  -1          A01X+157143Y+140149X0120Y0150R090 S1      
317m5718            VIA   -    MD0100PA01X+157153Y+139658X0180Y         S0      
317m5718            VIA   -    MD0080PA01X+162480Y+122480X0160Y    R270 S0      
327m5718            PEX3  -J30        A01X+162480Y+122480X0180Y         S1      
327m5719            C819  -1          A01X+163938Y+140149X0120Y0150R090 S1      
317m5719            VIA   -    MD0100PA01X+163928Y+139658X0180Y    R180 S0      
317m5719            VIA   -    MD0080PA01X+154252Y+119862X0160Y         S0      
327m5719            PEX3  -T8         A01X+154252Y+119862X0180Y         S1      
317m5720            J3    -N4   D0122PA01X+013587Y+151413X0282Y    R180 S3      
317m5720            VIA   -    MD0080PA01X+015256Y+125472X0160Y         S0      
327m5720            PEX0  -A3         A01X+015256Y+125472X0180Y         S1      
317m5721            VIA   -    MD0100PA01X+025386Y+140850X0180Y         S0      
317m5721            J11   -G3   D0122PA01X+030043Y+159169X0282Y    R180 S3      
327m5721            C123  -2          A01X+025376Y+140359X0120Y0150R090 S1      
327m5722            VIA   -    M      A18X+117428Y+044358X0260Y         S2      
327m5722            R291  -2          A18X+117589Y+043832X0198Y0197R180 S2      
327m5722            U33   -2          A18X+118681Y+045163X0160Y0240R180 S2      
327m5723            VIA   -    M      A01X+075193Y+031791X0300Y         S1      
327m5723            R203  -2          A01X+074718Y+031787X0198Y0197     S1      
327m5723            Q4    -2          A01X+075692Y+031929X0170Y0240R270 S1      
327m5723            Q4    -3          A01X+075692Y+031673X0170Y0240R270 S1      
327m5724            C114  -1          A01X+030632Y+135309X0120Y0150R090 S1      
317m5724            VIA   -    MD0100PA01X+030622Y+134819X0180Y         S0      
317m5724            VIA   -    MD0080PA01X+025728Y+123602X0160Y    R270 S0      
327m5724            PEX0  -F31        A01X+025728Y+123602X0180Y         S1      
327m5725            C535  -1          A01X+129143Y+135309X0120Y0150R090 S1      
317m5725            VIA   -    MD0100PA01X+129153Y+134819X0180Y         S0      
317m5725            VIA   -    MD0080PA01X+117146Y+123228X0160Y    R270 S0      
327m5725            PEX2  -G31        A01X+117146Y+123228X0180Y         S1      
327m5726            C753  -1          A01X+156279Y+137729X0120Y0150R090 S1      
317m5726            VIA   -    MD0100PA01X+156269Y+137238X0180Y         S0      
317m5726            VIA   -    MD0080PA01X+161732Y+122854X0160Y    R270 S0      
327m5726            PEX3  -H28        A01X+161732Y+122854X0180Y         S1      
327m5727            C765  -1          A01X+147711Y+137729X0120Y0150R090 S1      
317m5727            VIA   -    MD0100PA01X+147701Y+137238X0180Y         S0      
317m5727            VIA   -    MD0080PA01X+154626Y+123602X0160Y    R270 S0      
327m5727            PEX3  -F9         A01X+154626Y+123602X0180Y         S1      
317m5728            J11   -W4   D0122PA01X+030909Y+146807X0282Y    R180 S3      
317m5728            VIA   -    MD0080PA01X+027224Y+125472X0160Y    R090 S0      
327m5728            PEX0  -A35        A01X+027224Y+125472X0180Y         S1      
317m5729            VIA   -    MD0100PA01X+133165Y+138430X0180Y         S0      
317m5729            J13   -R5   D0122PA01X+133972Y+149445X0282Y    R180 S3      
327m5729            C526  -2          A01X+133175Y+137939X0120Y0150R090 S1      
317m5730            VIA   -    MD0100PA01X+025726Y+140850X0180Y         S0      
317m5730            J11   -F3   D0122PA01X+030043Y+159681X0282Y    R180 S3      
327m5730            C124  -2          A01X+025736Y+140359X0120Y0150R090 S1      
317HP_NIC0_PWRGD    VIA   -    M      A01X+025269Y+063636X0200Y         S2      
017HP_NIC0_PWRGD    VIA   -    M      A18X+025269Y+063636X0260Y         S2      
017HP_NIC0_PWRGD          -    MD0100PA00X+025269Y+063636                       
327HP_NIC0_PWRGD    R51   -2          A18X+024670Y+063626X0198Y0197R270 S2      
327HP_NIC0_PWRGD    R49   -2          A01X+025184Y+067589X0198Y0197     S1      
327HP_NIC0_PWRGD    U12   -1   M      A01X+025058Y+066991X0400Y0500R180 S1      
327PRSNT_NIC3_N     R194  -1          A01X+070621Y+046286X0198Y0197     S1      
317PRSNT_NIC3_N     VIA   -    M      A01X+070621Y+046587X0200Y         S2      
017PRSNT_NIC3_N     VIA   -    M      A18X+070621Y+046587X0260Y         S2      
017PRSNT_NIC3_N           -    MD0100PA00X+070621Y+046587                       
317PRSNT_NIC3_N     VIA   -    MD0100PA00X+070245Y+054671X0200Y    R180 S0      
327PRSNT_NIC3_N     R195  -1          A01X+077575Y+062691X0198Y0197R180 S1      
317PRSNT_NIC3_N     VIA   -    MD0100PA00X+077886Y+062691X0200Y    R180 S0      
317PRSNT_NIC3_N     VIA   -    MD0100PA00X+079600Y+055310X0200Y         S0      
327PRSNT_NIC3_N     R193  -1   M      A01X+070540Y+054671X0198Y0197     S1      
327PRSNT_NIC3_N     R192  -1   M      A01X+077575Y+054591X0198Y0197R180 S1      
327PRSNT_NIC3_N     R196  -2          A01X+079937Y+055514X0198Y0197R270 S1      
327m5731            C97   -1          A01X+036392Y+137729X0120Y0150R090 S1      
317m5731            VIA   -    MD0100PA01X+036402Y+137238X0180Y         S0      
317m5731            VIA   -    MD0080PA01X+028720Y+123228X0160Y    R270 S0      
327m5731            PEX0  -G39        A01X+028720Y+123228X0180Y         S1      
317m5732            VIA   -    MD0080PA01X+111161Y+109764X0160Y    R270 S0      
327m5732            PEX2  -BC15       A01X+111161Y+109764X0180Y         S1      
327m5732            C499  -1          A01X+109804Y+012184X0120Y0150R180 S1      
317m5732            VIA   -    MD0100PA01X+110294Y+012174X0200Y    R090 S0      
327m5733            C745  -1          A01X+153831Y+135309X0120Y0150R090 S1      
317m5733            VIA   -    MD0100PA01X+153821Y+134819X0180Y         S0      
317m5733            VIA   -    MD0080PA01X+163228Y+122854X0160Y    R270 S0      
327m5733            PEX3  -H32        A01X+163228Y+122854X0180Y         S1      
327m5734            C766  -1          A01X+148575Y+135309X0120Y0150R090 S1      
317m5734            VIA   -    MD0100PA01X+148585Y+134819X0180Y         S0      
317m5734            VIA   -    MD0080PA01X+155000Y+122480X0160Y         S0      
327m5734            PEX3  -J10        A01X+155000Y+122480X0180Y         S1      
317m5735            J3    -O4   D0122PA01X+013587Y+150902X0282Y    R180 S3      
317m5735            VIA   -    MD0080PA01X+015256Y+125098X0160Y         S0      
327m5735            PEX0  -B3         A01X+015256Y+125098X0180Y         S1      
327m5736            VIA   -    M      A18X+022582Y+063568X0260Y         S2      
327m5736            Q1    -3          A18X+023075Y+063824X0170Y0240R270 S2      
327m5736            R50   -2          A18X+022126Y+063573X0198Y0197R270 S2      
327m5736            Q1    -2          A18X+023075Y+063568X0170Y0240R270 S2      
317m5737            VIA   -    M      A01X+068706Y+037646X0200Y         S2      
017m5737            VIA   -    M      A18X+068706Y+037646X0260Y         S2      
017m5737                  -    MD0100PA00X+068706Y+037646                       
327m5737            R201  -2          A01X+068778Y+038472X0198Y0197R180 S1      
327m5737            R200  -2   M      A01X+068778Y+038072X0198Y0197R180 S1      
327m5737            R198  -2   M      A01X+077850Y+034232X0198Y0197R270 S1      
327m5737            U25   -4          A01X+076903Y+034232X0160Y0360R270 S1      
327m5737            R199  -2   M      A01X+077450Y+034232X0198Y0197R270 S1      
327m5738            C102  -1          A01X+035528Y+135309X0120Y0150R090 S1      
317m5738            VIA   -    MD0100PA01X+035518Y+134819X0180Y         S0      
317m5738            VIA   -    MD0080PA01X+027972Y+123602X0160Y    R270 S0      
327m5738            PEX0  -F37        A01X+027972Y+123602X0180Y         S1      
327m5739            C547  -1          A01X+124247Y+135309X0120Y0150R090 S1      
317m5739            VIA   -    MD0100PA01X+124257Y+134819X0180Y         S0      
317m5739            VIA   -    MD0080PA01X+114902Y+123228X0160Y    R270 S0      
327m5739            PEX2  -G25        A01X+114902Y+123228X0180Y         S1      
317m5740            VIA   -    MD0080PA01X+155748Y+110138X0160Y    R270 S0      
327m5740            PEX3  -BB12       A01X+155748Y+110138X0180Y         S1      
317m5740            VIA   -    MD0100PA01X+144726Y+011122X0200Y    R090 S0      
327m5740            C705  -1          A01X+144236Y+011112X0120Y0150R180 S1      
327m5741            C807  -1          A01X+168474Y+140149X0120Y0150R090 S1      
317m5741            VIA   -    MD0100PA01X+168484Y+139658X0180Y         S0      
317m5741            VIA   -    MD0080PA01X+151634Y+122854X0160Y    R270 S0      
327m5741            PEX3  -H1         A01X+151634Y+122854X0180Y         S1      
317m5742            VIA   -    MD0100PA01X+112815Y+138430X0180Y         S0      
317m5742            J7    -U2   D0122PA01X+114051Y+147831X0282Y    R180 S3      
327m5742            C596  -2          A01X+112805Y+137939X0120Y0150R090 S1      
327PRSNT_NIC6_N     R347  -1          A01X+159284Y+054580X0198Y0197R180 S1      
317PRSNT_NIC6_N     VIA   -    MD0100PA00X+159626Y+054050X0200Y         S0      
317PRSNT_NIC6_N     VIA   -    MD0100PA00X+159264Y+045591X0200Y         S0      
327PRSNT_NIC6_N     R349  -2          A01X+149850Y+045566X0198Y0197R090 S1      
327PRSNT_NIC6_N     R345  -1   M      A01X+152228Y+045960X0198Y0197     S1      
327PRSNT_NIC6_N     R346  -1          A01X+159264Y+045880X0198Y0197R180 S1      
317PRSNT_NIC6_N     VIA   -    MD0100PA00X+151944Y+045871X0200Y         S0      
317PRSNT_NIC6_N     VIA   -    M      A01X+151932Y+037860X0200Y         S2      
017PRSNT_NIC6_N     VIA   -    M      A18X+151932Y+037860X0260Y         S2      
017PRSNT_NIC6_N           -    MD0100PA00X+151932Y+037860                       
327PRSNT_NIC6_N     R348  -1          A01X+152228Y+037860X0198Y0197     S1      
327m5743            U10   -4          A18X+023669Y+060777X0160Y0360R270 S2      
317m5743            VIA   -    M      A01X+022033Y+061793X0200Y         S2      
017m5743            VIA   -    M      A18X+022033Y+061793X0260Y         S2      
017m5743                  -    MD0100PA00X+022033Y+061793                       
327m5743            R47   -2          A01X+022198Y+062540X0198Y0197     S1      
327m5743            R46   -2          A01X+021794Y+061504X0198Y0197R090 S1      
327m5743            R45   -2   M      A01X+022181Y+061505X0198Y0197R090 S1      
327m5743            R48   -2   M      A01X+022198Y+062140X0198Y0197     S1      
327m5744            C113  -1          A01X+030272Y+135309X0120Y0150R090 S1      
317m5744            VIA   -    MD0100PA01X+030282Y+134819X0180Y         S0      
317m5744            VIA   -    MD0080PA01X+025728Y+123228X0160Y    R270 S0      
327m5744            PEX0  -G31        A01X+025728Y+123228X0180Y         S1      
317m5745            VIA   -    MD0080PA01X+110413Y+109390X0160Y         S0      
327m5745            PEX2  -BD13       A01X+110413Y+109390X0180Y         S1      
327m5745            C496  -1          A01X+109804Y+013241X0120Y0150R180 S1      
317m5745            VIA   -    MD0100PA01X+110294Y+013251X0200Y    R090 S0      
317m5746            VIA   -    MD0080PA01X+153504Y+122854X0160Y         S0      
317m5746            VIA   -    MD0100PA01X+173720Y+134819X0180Y         S0      
327m5746            PEX3  -H6         A01X+153504Y+122854X0180Y         S1      
327m5746            C797  -1          A01X+173730Y+135309X0120Y0150R090 S1      
317m5747            VIA   -    MD0100PA01X+114379Y+140850X0180Y         S0      
317m5747            J7    -T4   D0122PA01X+115783Y+148343X0282Y    R180 S3      
327m5747            C592  -2          A01X+114389Y+140359X0120Y0150R090 S1      
327HP_NIC6_PWRGD    VIA   -    M      A01X+162111Y+068705X0300Y         S1      
317HP_NIC6_PWRGD    VIA   -    MD0100PA00X+161591Y+069224X0200Y         S0      
327HP_NIC6_PWRGD    U42   -1          A01X+162184Y+066991X0400Y0500R180 S1      
327HP_NIC6_PWRGD    R355  -2   M      A01X+162310Y+067589X0198Y0197     S1      
317HP_NIC6_PWRGD    VIA   -    MD0100PA00X+157800Y+067878X0200Y         S0      
327HP_NIC6_PWRGD    R357  -2          A01X+157931Y+068969X0198Y0197     S1      
317PRSNT_NIC0_N     VIA   -    MD0100PA00X+022138Y+045502X0200Y         S0      
327PRSNT_NIC0_N     R43   -2          A01X+012724Y+045566X0198Y0197R090 S1      
327PRSNT_NIC0_N     R39   -1   M      A01X+015102Y+045960X0198Y0197     S1      
327PRSNT_NIC0_N     R40   -1          A01X+022138Y+045880X0198Y0197R180 S1      
317PRSNT_NIC0_N     VIA   -    MD0100PA00X+014818Y+045871X0200Y         S0      
317PRSNT_NIC0_N     VIA   -    M      A01X+014806Y+037860X0200Y         S2      
017PRSNT_NIC0_N     VIA   -    M      A18X+014806Y+037860X0260Y         S2      
017PRSNT_NIC0_N           -    MD0100PA00X+014806Y+037860                       
327PRSNT_NIC0_N     R42   -1          A01X+015102Y+037860X0198Y0197     S1      
327PRSNT_NIC0_N     R41   -1          A01X+022158Y+054580X0198Y0197R180 S1      
317PRSNT_NIC0_N     VIA   -    MD0100PA00X+022500Y+054050X0200Y         S0      
327m5748            C120  -1          A01X+028184Y+135309X0120Y0150R090 S1      
317m5748            VIA   -    MD0100PA01X+028174Y+134819X0180Y         S0      
317m5748            VIA   -    MD0080PA01X+024606Y+122854X0160Y    R270 S0      
327m5748            PEX0  -H28        A01X+024606Y+122854X0180Y         S1      
327m5749            C548  -1          A01X+124607Y+135309X0120Y0150R090 S1      
317m5749            VIA   -    MD0100PA01X+124597Y+134819X0180Y         S0      
317m5749            VIA   -    MD0080PA01X+114902Y+123602X0160Y    R270 S0      
327m5749            PEX2  -F25        A01X+114902Y+123602X0180Y         S1      
317m5750            VIA   -    MD0080PA01X+154252Y+122854X0160Y         S0      
317m5750            VIA   -    MD0100PA01X+146477Y+134819X0180Y         S0      
327m5750            PEX3  -H8         A01X+154252Y+122854X0180Y         S1      
327m5750            C763  -1          A01X+146487Y+135309X0120Y0150R090 S1      
327m5751            VIA   -    M      A01X+156666Y+070731X0300Y         S1      
327m5751            Q7    -2          A01X+157338Y+070228X0170Y0240R180 S1      
327m5751            R356  -2   M      A01X+157204Y+071013X0198Y0197R180 S1      
327m5751            Q7    -3          A01X+157082Y+070228X0170Y0240R180 S1      
327m5752            C101  -1          A01X+035168Y+135309X0120Y0150R090 S1      
317m5752            VIA   -    MD0100PA01X+035178Y+134819X0180Y         S0      
317m5752            VIA   -    MD0080PA01X+027972Y+123228X0160Y    R270 S0      
327m5752            PEX0  -G37        A01X+027972Y+123228X0180Y         S1      
317m5753            VIA   -    MD0080PA01X+110039Y+110512X0160Y    R270 S0      
327m5753            PEX2  -BA12       A01X+110039Y+110512X0180Y         S1      
327m5753            C493  -1          A01X+098527Y+011472X0120Y0150R180 S1      
317m5753            VIA   -    MD0100PA01X+099018Y+011462X0200Y    R090 S0      
327m5754            C781  -1          A01X+147711Y+135309X0120Y0150R090 S1      
317m5754            VIA   -    MD0100PA01X+147701Y+134819X0180Y         S0      
317m5754            VIA   -    MD0080PA01X+157618Y+123602X0160Y    R270 S0      
327m5754            PEX3  -F17        A01X+157618Y+123602X0180Y         S1      
327m5755            VIA   -    M      A01X+158698Y+065240X0300Y         S1      
327m5755            R354  -2          A01X+159324Y+062140X0198Y0197     S1      
327m5755            R353  -2   M      A01X+159324Y+062540X0198Y0197     S1      
327m5755            U40   -4          A01X+156677Y+065316X0160Y0360R270 S1      
327m5755            R352  -2   M      A01X+157624Y+065631X0198Y0197R090 S1      
327m5755            R351  -2   M      A01X+157224Y+065631X0198Y0197R090 S1      
317m5756            VIA   -    MD0080PA01X+021240Y+109764X0160Y    R270 S0      
327m5756            PEX0  -BC19       A01X+021240Y+109764X0180Y         S1      
327m5756            C85   -1          A01X+028622Y+012184X0120Y0150R180 S1      
317m5756            VIA   -    MD0100PA01X+029113Y+012174X0200Y    R090 S0      
317m5757            VIA   -    MD0080PA01X+109665Y+109764X0160Y    R270 S0      
327m5757            PEX2  -BC11       A01X+109665Y+109764X0180Y         S1      
327m5757            C491  -1          A01X+099567Y+012184X0120Y0150R180 S1      
317m5757            VIA   -    MD0100PA01X+100058Y+012174X0200Y    R090 S0      
327m5758            C805  -1          A01X+169698Y+137729X0120Y0150R090 S1      
317m5758            VIA   -    MD0100PA01X+169708Y+137238X0180Y         S0      
317m5758            VIA   -    MD0080PA01X+151634Y+123976X0160Y         S0      
327m5758            PEX3  -E1         A01X+151634Y+123976X0180Y         S1      
317m5759            J3    -P3   D0122PA01X+012720Y+150468X0282Y    R180 S3      
317m5759            VIA   -    MD0080PA01X+014508Y+124724X0160Y         S0      
327m5759            PEX0  -C1         A01X+014508Y+124724X0180Y         S1      
327m5760            C117  -1          A01X+027824Y+140149X0120Y0150R090 S1      
317m5760            VIA   -    MD0100PA01X+027834Y+139658X0180Y         S0      
317m5760            VIA   -    MD0080PA01X+024980Y+123228X0160Y    R270 S0      
327m5760            PEX0  -G29        A01X+024980Y+123228X0180Y         S1      
327m5761            C529  -1          A01X+131591Y+135309X0120Y0150R090 S1      
317m5761            VIA   -    MD0100PA01X+131601Y+134819X0180Y         S0      
317m5761            VIA   -    MD0080PA01X+118268Y+122480X0160Y    R270 S0      
327m5761            PEX2  -J34        A01X+118268Y+122480X0180Y         S1      
327m5762            C815  -1          A01X+166386Y+135309X0120Y0150R090 S1      
317m5762            VIA   -    MD0100PA01X+166376Y+134819X0180Y         S0      
317m5762            VIA   -    MD0080PA01X+154252Y+120610X0160Y         S0      
327m5762            PEX3  -P8         A01X+154252Y+120610X0180Y         S1      
317m5763            J11   -X3   D0122PA01X+030043Y+146374X0282Y    R180 S3      
317m5763            VIA   -    MD0080PA01X+026850Y+124724X0160Y         S0      
327m5763            PEX0  -C34        A01X+026850Y+124724X0180Y         S1      
327m5764            C106  -1          A01X+033080Y+140149X0120Y0150R090 S1      
317m5764            VIA   -    MD0100PA01X+033070Y+139658X0180Y         S0      
317m5764            VIA   -    MD0080PA01X+027224Y+123602X0160Y    R270 S0      
327m5764            PEX0  -F35        A01X+027224Y+123602X0180Y         S1      
327m5765            C542  -1          A01X+127055Y+135309X0120Y0150R090 S1      
317m5765            VIA   -    MD0100PA01X+127045Y+134819X0180Y         S0      
317m5765            VIA   -    MD0080PA01X+116024Y+122854X0160Y    R270 S0      
327m5765            PEX2  -H28        A01X+116024Y+122854X0180Y         S1      
317m5766            VIA   -    MD0080PA01X+166968Y+110138X0160Y    R270 S0      
327m5766            PEX3  -BB42       A01X+166968Y+110138X0180Y         S1      
327m5766            C637  -1          A01X+168735Y+060390X0120Y0150R180 S1      
317m5766            VIA   -    MD0100PA01X+169225Y+060400X0200Y    R090 S0      
317m5767            VIA   -    MD0080PA01X+153130Y+123228X0160Y    R270 S0      
317m5767            VIA   -    MD0100PA01X+172156Y+137238X0180Y         S0      
327m5767            C798  -1          A01X+172146Y+137729X0120Y0150R090 S1      
327m5767            PEX3  -G5         A01X+153130Y+123228X0180Y         S1      
317m5768            J11   -Y3   D0122PA01X+030043Y+145862X0282Y    R180 S3      
317m5768            VIA   -    MD0080PA01X+026850Y+124350X0160Y         S0      
327m5768            PEX0  -D34        A01X+026850Y+124350X0180Y         S1      
317m5769            VIA   -    MD0100PA01X+017403Y+138430X0180Y         S0      
317m5769            J3    -V5   D0122PA01X+014453Y+147398X0282Y    R180 S3      
327m5769            C167  -2          A01X+017393Y+137939X0120Y0150R090 S1      
327m5770            C121  -1          A01X+026600Y+137729X0120Y0150R090 S1      
317m5770            VIA   -    MD0100PA01X+026610Y+137238X0180Y         S0      
317m5770            VIA   -    MD0080PA01X+024232Y+123228X0160Y    R270 S0      
327m5770            PEX0  -G27        A01X+024232Y+123228X0180Y         S1      
317m5771            VIA   -    MD0080PA01X+073681Y+123228X0160Y    R270 S0      
317m5771            VIA   -    MD0100PA01X+055056Y+137238X0180Y         S0      
327m5771            C2247 -1          A01X+055046Y+137729X0120Y0150R090 S1      
327m5771            PEX1  -G37        A01X+073681Y+123228X0180Y         S1      
317m5772            VIA   -    MD0080PA01X+113405Y+109390X0160Y    R270 S0      
327m5772            PEX2  -BD21       A01X+113405Y+109390X0180Y         S1      
317m5772            VIA   -    MD0100PA01X+130767Y+013251X0200Y    R090 S0      
327m5772            C512  -1          A01X+130276Y+013241X0120Y0150R180 S1      
317m5773            VIA   -    MD0080PA01X+167342Y+109764X0160Y    R270 S0      
317m5773            VIA   -    MD0100PA01X+170266Y+060034X0200Y    R090 S0      
327m5773            C638  -1          A01X+169775Y+060044X0120Y0150R180 S1      
327m5773            PEX3  -BC43       A01X+167342Y+109764X0180Y         S1      
327m5774            C791  -1          A01X+151383Y+137729X0120Y0150R090 S1      
317m5774            VIA   -    MD0100PA01X+151373Y+137238X0180Y         S0      
317m5774            VIA   -    MD0080PA01X+159488Y+122854X0160Y         S0      
327m5774            PEX3  -H22        A01X+159488Y+122854X0180Y         S1      
317m5775            J3    -O3   D0122PA01X+012720Y+150980X0282Y    R180 S3      
317m5775            VIA   -    MD0080PA01X+014882Y+124724X0160Y         S0      
327m5775            PEX0  -C2         A01X+014882Y+124724X0180Y         S1      
317m5776            VIA   -    MD0100PA01X+018627Y+140850X0180Y         S0      
317m5776            J3    -V7   D0122PA01X+016185Y+147398X0282Y    R180 S3      
327m5776            C163  -2          A01X+018617Y+140359X0120Y0150R090 S1      
327m5777            C103  -1          A01X+033944Y+137729X0120Y0150R090 S1      
317m5777            VIA   -    MD0100PA01X+033954Y+137238X0180Y         S0      
317m5777            VIA   -    MD0080PA01X+027598Y+122480X0160Y    R270 S0      
327m5777            PEX0  -J36        A01X+027598Y+122480X0180Y         S1      
317m5778            VIA   -    MD0080PA01X+073307Y+122854X0160Y    R270 S0      
317m5778            VIA   -    MD0100PA01X+054172Y+139658X0180Y         S0      
327m5778            C2250 -1          A01X+054182Y+140149X0120Y0150R090 S1      
327m5778            PEX1  -H36        A01X+073307Y+122854X0180Y         S1      
317m5779            VIA   -    MD0080PA01X+113031Y+110512X0160Y    R270 S0      
327m5779            PEX2  -BA20       A01X+113031Y+110512X0180Y         S1      
327m5779            C509  -1          A01X+119000Y+011472X0120Y0150R180 S1      
317m5779            VIA   -    MD0100PA01X+119490Y+011462X0200Y    R090 S0      
317m5780            VIA   -    MD0080PA01X+167716Y+110512X0160Y    R270 S0      
327m5780            C640  -1          A01X+168735Y+059332X0120Y0150R180 S1      
317m5780            VIA   -    MD0100PA01X+169225Y+059322X0200Y    R090 S0      
327m5780            PEX3  -BA44       A01X+167716Y+110512X0180Y         S1      
327m5781            C821  -1          A01X+163938Y+135309X0120Y0150R090 S1      
317m5781            VIA   -    MD0100PA01X+163928Y+134819X0180Y         S0      
317m5781            VIA   -    MD0080PA01X+153504Y+119488X0160Y         S0      
327m5781            PEX3  -U6         A01X+153504Y+119488X0180Y         S1      
317m5782            VIA   -    MD0100PA01X+020191Y+138430X0180Y         S0      
317m5782            J3    -T8   D0122PA01X+017051Y+148343X0282Y    R180 S3      
327m5782            C162  -2          A01X+020201Y+137939X0120Y0150R090 S1      
327m5783            C127  -1          A01X+024152Y+137729X0120Y0150R090 S1      
317m5783            VIA   -    MD0100PA01X+024162Y+137238X0180Y         S0      
317m5783            VIA   -    MD0080PA01X+023110Y+122480X0160Y         S0      
327m5783            PEX0  -J24        A01X+023110Y+122480X0180Y         S1      
317m5784            VIA   -    MD0080PA01X+067697Y+109390X0160Y    R270 S0      
327m5784            PEX1  -BD21       A01X+067697Y+109390X0180Y         S1      
327m5784            C301  -1          A01X+084567Y+013241X0120Y0150R180 S1      
317m5784            VIA   -    MD0100PA01X+085058Y+013251X0200Y    R090 S0      
317m5785            VIA   -    MD0080PA01X+111161Y+109390X0160Y    R270 S0      
327m5785            PEX2  -BD15       A01X+111161Y+109390X0180Y         S1      
327m5785            C500  -1          A01X+109804Y+011824X0120Y0150R180 S1      
317m5785            VIA   -    MD0100PA01X+110294Y+011834X0200Y    R090 S0      
317m5786            VIA   -    MD0080PA01X+166594Y+113130X0160Y    R270 S0      
327m5786            PEX3  -AP41       A01X+166594Y+113130X0180Y         S1      
317m5786            VIA   -    MD0100PA01X+170266Y+047782X0200Y    R090 S0      
327m5786            C662  -1          A01X+169775Y+047792X0120Y0150R180 S1      
327m5787            C769  -1          A01X+148935Y+140149X0120Y0150R090 S1      
317m5787            VIA   -    MD0100PA01X+148925Y+139658X0180Y    R180 S0      
317m5787            VIA   -    MD0080PA01X+155374Y+123602X0160Y    R270 S0      
327m5787            PEX3  -F11        A01X+155374Y+123602X0180Y         S1      
317m5788            VIA   -    MD0100PA01X+018967Y+140850X0180Y         S0      
317m5788            J3    -U7   D0122PA01X+016185Y+147910X0282Y    R180 S3      
327m5788            C164  -2          A01X+018977Y+140359X0120Y0150R090 S1      
317m5789            VIA   -    MD0080PA01X+017500Y+109390X0160Y    R270 S0      
327m5789            PEX0  -BD9        A01X+017500Y+109390X0180Y         S1      
327m5789            C66   -1          A01X+008150Y+013241X0120Y0150R180 S1      
317m5789            VIA   -    MD0100PA01X+008641Y+013251X0200Y    R090 S0      
317m5790            VIA   -    MD0080PA01X+066949Y+109390X0160Y    R270 S0      
327m5790            PEX1  -BD19       A01X+066949Y+109390X0180Y         S1      
327m5790            C297  -1          A01X+074331Y+011824X0120Y0150R180 S1      
317m5790            VIA   -    MD0100PA01X+074822Y+011834X0200Y    R090 S0      
327m5791            C521  -1          A01X+134039Y+140149X0120Y0150R090 S1      
317m5791            VIA   -    MD0100PA01X+134049Y+139658X0180Y         S0      
317m5791            VIA   -    MD0080PA01X+119764Y+122480X0160Y    R270 S0      
327m5791            PEX2  -J38        A01X+119764Y+122480X0180Y         S1      
317m5792            VIA   -    MD0080PA01X+168464Y+110138X0160Y    R270 S0      
327m5792            PEX3  -BB46       A01X+168464Y+110138X0180Y         S1      
317m5792            VIA   -    MD0100PA01X+169225Y+057565X0200Y    R090 S0      
327m5792            C645  -1          A01X+168735Y+057555X0120Y0150R180 S1      
327m5793            C816  -1          A01X+164802Y+137729X0120Y0150R090 S1      
317m5793            VIA   -    MD0100PA01X+164812Y+137238X0180Y         S0      
317m5793            VIA   -    MD0080PA01X+153878Y+120236X0160Y         S0      
327m5793            PEX3  -R7         A01X+153878Y+120236X0180Y         S1      
317m5794            VIA   -    MD0100PA01X+018627Y+136010X0180Y         S0      
317m5794            J3    -U6   D0122PA01X+015319Y+147831X0282Y    R180 S3      
327m5794            C165  -2          A01X+018617Y+135519X0120Y0150R090 S1      
317m5795            VIA   -    MD0080PA01X+022362Y+110138X0160Y    R270 S0      
327m5795            PEX0  -BB22       A01X+022362Y+110138X0180Y         S1      
327m5795            C92   -1          A01X+037818Y+012530X0120Y0150R180 S1      
317m5795            VIA   -    MD0100PA01X+038309Y+012540X0200Y    R090 S0      
317m5796            VIA   -    MD0080PA01X+068445Y+109390X0160Y    R270 S0      
327m5796            PEX1  -BD23       A01X+068445Y+109390X0180Y         S1      
327m5796            C305  -1          A01X+084567Y+011824X0120Y0150R180 S1      
317m5796            VIA   -    MD0100PA01X+085058Y+011834X0200Y    R090 S0      
317m5797            VIA   -    MD0080PA01X+110413Y+109764X0160Y    R270 S0      
327m5797            PEX2  -BC13       A01X+110413Y+109764X0180Y         S1      
327m5797            C495  -1          A01X+109804Y+013601X0120Y0150R180 S1      
317m5797            VIA   -    MD0100PA01X+110294Y+013591X0200Y    R090 S0      
317m5798            VIA   -    MD0080PA01X+163602Y+109390X0160Y    R270 S0      
317m5798            VIA   -    MD0100PA01X+150955Y+047279X0200Y    R270 S0      
327m5798            C681  -1          A01X+151446Y+047289X0120Y0150     S1      
327m5798            PEX3  -BD33       A01X+163602Y+109390X0180Y         S1      
327m5799            C767  -1          A01X+148935Y+135309X0120Y0150R090 S1      
317m5799            VIA   -    MD0100PA01X+148925Y+134819X0180Y         S0      
317m5799            VIA   -    MD0080PA01X+155000Y+122854X0160Y         S0      
327m5799            PEX3  -H10        A01X+155000Y+122854X0180Y         S1      
317m5800            VIA   -    MD0100PA01X+019851Y+138430X0180Y         S0      
317m5800            J3    -U8   D0122PA01X+017051Y+147831X0282Y    R180 S3      
327m5800            C161  -2          A01X+019841Y+137939X0120Y0150R090 S1      
317m5801            VIA   -    MD0080PA01X+021988Y+109764X0160Y    R270 S0      
327m5801            PEX0  -BC21       A01X+021988Y+109764X0180Y         S1      
327m5801            C89   -1          A01X+038859Y+013601X0120Y0150R180 S1      
317m5801            VIA   -    MD0100PA01X+039349Y+013591X0200Y    R090 S0      
317m5802            VIA   -    MD0080PA01X+065453Y+109390X0160Y    R270 S0      
327m5802            PEX1  -BD15       A01X+065453Y+109390X0180Y         S1      
327m5802            C289  -1          A01X+064095Y+011824X0120Y0150R180 S1      
317m5802            VIA   -    MD0100PA01X+064586Y+011834X0200Y    R090 S0      
317m5803            VIA   -    MD0080PA01X+114154Y+109390X0160Y    R270 S0      
327m5803            PEX2  -BD23       A01X+114154Y+109390X0180Y         S1      
317m5803            VIA   -    MD0100PA01X+130767Y+011834X0200Y    R090 S0      
327m5803            C516  -1          A01X+130276Y+011824X0120Y0150R180 S1      
317m5804            VIA   -    MD0080PA01X+166968Y+110512X0160Y    R270 S0      
327m5804            C636  -1          A01X+168735Y+060750X0120Y0150R180 S1      
317m5804            VIA   -    MD0100PA01X+169225Y+060740X0200Y    R090 S0      
327m5804            PEX3  -BA42       A01X+166968Y+110512X0180Y         S1      
327m5805            C774  -1          A01X+151023Y+140149X0120Y0150R090 S1      
317m5805            VIA   -    MD0100PA01X+151033Y+139658X0180Y         S0      
317m5805            VIA   -    MD0080PA01X+156496Y+122480X0160Y         S0      
327m5805            PEX3  -J14        A01X+156496Y+122480X0180Y         S1      
317m5806            J11   -X2   D0122PA01X+029177Y+146295X0282Y    R180 S3      
317m5806            VIA   -    MD0080PA01X+026476Y+125098X0160Y    R090 S0      
327m5806            PEX0  -B33        A01X+026476Y+125098X0180Y         S1      
317m5807            VIA   -    MD0100PA01X+017743Y+138430X0180Y         S0      
317m5807            J3    -U5   D0122PA01X+014453Y+147910X0282Y    R180 S3      
327m5807            C168  -2          A01X+017753Y+137939X0120Y0150R090 S1      
317m5808            VIA   -    MD0080PA01X+022736Y+109390X0160Y    R270 S0      
327m5808            PEX0  -BD23       A01X+022736Y+109390X0180Y         S1      
327m5808            C94   -1          A01X+038859Y+011824X0120Y0150R180 S1      
317m5808            VIA   -    MD0100PA01X+039349Y+011834X0200Y    R090 S0      
317m5809            VIA   -    MD0080PA01X+070315Y+122854X0160Y    R270 S0      
317m5809            VIA   -    MD0100PA01X+054172Y+137238X0180Y         S0      
327m5809            PEX1  -H28        A01X+070315Y+122854X0180Y         S1      
327m5809            C2266 -1          A01X+054182Y+137729X0120Y0150R090 S1      
317m5810            VIA   -    MD0080PA01X+111535Y+110138X0160Y    R270 S0      
327m5810            PEX2  -BB16       A01X+111535Y+110138X0180Y         S1      
327m5810            C502  -1          A01X+108763Y+011112X0120Y0150R180 S1      
317m5810            VIA   -    MD0100PA01X+109254Y+011122X0200Y    R090 S0      
317m5811            VIA   -    MD0080PA01X+169587Y+109016X0160Y    R270 S0      
327m5811            PEX3  -BE49       A01X+169587Y+109016X0180Y         S1      
317m5811            VIA   -    MD0100PA01X+169225Y+056148X0200Y    R090 S0      
327m5811            C649  -1          A01X+168735Y+056138X0120Y0150R180 S1      
317m5812            VIA   -    MD0080PA01X+152756Y+122854X0160Y         S0      
317m5812            VIA   -    MD0100PA01X+171272Y+139658X0180Y         S0      
327m5812            PEX3  -H4         A01X+152756Y+122854X0180Y         S1      
327m5812            C801  -1          A01X+171282Y+140149X0120Y0150R090 S1      
317m5813            VIA   -    MD0080PA01X+014882Y+122106X0160Y         S0      
317m5813            J3    -N2   D0122PA01X+011854Y+151413X0282Y    R180 S3      
327m5813            PEX0  -K2         A01X+014882Y+122106X0180Y         S1      
317m5814            VIA   -    MD0100PA01X+018967Y+136010X0180Y         S0      
317m5814            J3    -T6   D0122PA01X+015319Y+148343X0282Y    R180 S3      
327m5814            C166  -2          A01X+018977Y+135519X0120Y0150R090 S1      
327m5815            C122  -1          A01X+026960Y+137729X0120Y0150R090 S1      
317m5815            VIA   -    MD0100PA01X+026950Y+137238X0180Y         S0      
317m5815            VIA   -    MD0080PA01X+024232Y+123602X0160Y    R270 S0      
327m5815            PEX0  -F27        A01X+024232Y+123602X0180Y         S1      
317m5816            VIA   -    MD0080PA01X+074429Y+123602X0160Y    R270 S0      
317m5816            VIA   -    MD0100PA01X+056620Y+139658X0180Y         S0      
327m5816            PEX1  -F39        A01X+074429Y+123602X0180Y         S1      
327m5816            C2244 -1          A01X+056630Y+140149X0120Y0150R090 S1      
327m5817            C531  -1          A01X+130367Y+137729X0120Y0150R090 S1      
317m5817            VIA   -    MD0100PA01X+130377Y+137238X0180Y         S0      
317m5817            VIA   -    MD0080PA01X+117894Y+123228X0160Y    R270 S0      
327m5817            PEX2  -G33        A01X+117894Y+123228X0180Y         S1      
317m5818            VIA   -    MD0080PA01X+164724Y+110138X0160Y    R270 S0      
327m5818            PEX3  -BB36       A01X+164724Y+110138X0180Y         S1      
327m5818            C675  -1          A01X+152486Y+049417X0120Y0150     S1      
317m5818            VIA   -    MD0100PA01X+151995Y+049407X0200Y    R270 S0      
327m5819            C784  -1          A01X+148575Y+137729X0120Y0150R090 S1      
317m5819            VIA   -    MD0100PA01X+148585Y+137238X0180Y         S0      
317m5819            VIA   -    MD0080PA01X+158366Y+123228X0160Y    R270 S0      
327m5819            PEX3  -G19        A01X+158366Y+123228X0180Y         S1      
317m5820            J11   -W2   D0122PA01X+029177Y+146807X0282Y    R180 S3      
317m5820            VIA   -    MD0080PA01X+026476Y+125472X0160Y    R090 S0      
327m5820            PEX0  -A33        A01X+026476Y+125472X0180Y         S1      
327m5821            C116  -1          A01X+029408Y+137729X0120Y0150R090 S1      
317m5821            VIA   -    MD0100PA01X+029398Y+137238X0180Y         S0      
317m5821            VIA   -    MD0080PA01X+025354Y+122854X0160Y    R270 S0      
327m5821            PEX0  -H30        A01X+025354Y+122854X0180Y         S1      
317m5822            VIA   -    MD0080PA01X+068819Y+110512X0160Y    R270 S0      
327m5822            PEX1  -BA24       A01X+068819Y+110512X0180Y         S1      
327m5822            C306  -1          A01X+083527Y+011472X0120Y0150R180 S1      
317m5822            VIA   -    MD0100PA01X+084018Y+011462X0200Y    R090 S0      
327m5823            C534  -1          A01X+129503Y+140149X0120Y0150R090 S1      
317m5823            VIA   -    MD0100PA01X+129493Y+139658X0180Y         S0      
317m5823            VIA   -    MD0080PA01X+117520Y+122854X0160Y    R270 S0      
327m5823            PEX2  -H32        A01X+117520Y+122854X0180Y         S1      
317m5824            VIA   -    MD0080PA01X+166220Y+110512X0160Y    R270 S0      
327m5824            C666  -1          A01X+152486Y+053471X0120Y0150     S1      
317m5824            VIA   -    MD0100PA01X+151995Y+053481X0200Y    R270 S0      
327m5824            PEX3  -BA40       A01X+166220Y+110512X0180Y         S1      
327m5825            C768  -1          A01X+148575Y+140149X0120Y0150R090 S1      
317m5825            VIA   -    MD0100PA01X+148585Y+139658X0180Y    R180 S0      
317m5825            VIA   -    MD0080PA01X+155374Y+123228X0160Y    R270 S0      
327m5825            PEX3  -G11        A01X+155374Y+123228X0180Y         S1      
317m5826            VIA   -    MD0080PA01X+014508Y+122106X0160Y         S0      
317m5826            J3    -O2   D0122PA01X+011854Y+150902X0282Y    R180 S3      
327m5826            PEX0  -K1         A01X+014508Y+122106X0180Y         S1      
327m5827            C111  -1          A01X+030272Y+140149X0120Y0150R090 S1      
317m5827            VIA   -    MD0100PA01X+030282Y+139658X0180Y         S0      
317m5827            VIA   -    MD0080PA01X+026102Y+122480X0160Y    R270 S0      
327m5827            PEX0  -J32        A01X+026102Y+122480X0180Y         S1      
317m5828            VIA   -    MD0080PA01X+069941Y+123228X0160Y    R270 S0      
317m5828            VIA   -    MD0100PA01X+052608Y+139658X0180Y         S0      
327m5828            PEX1  -G27        A01X+069941Y+123228X0180Y         S1      
327m5828            C2267 -1          A01X+052598Y+140149X0120Y0150R090 S1      
327m5829            C527  -1          A01X+131591Y+140149X0120Y0150R090 S1      
317m5829            VIA   -    MD0100PA01X+131601Y+139658X0180Y         S0      
317m5829            VIA   -    MD0080PA01X+118642Y+123228X0160Y    R270 S0      
327m5829            PEX2  -G35        A01X+118642Y+123228X0180Y         S1      
317m5830            VIA   -    MD0080PA01X+167716Y+111260X0160Y    R270 S0      
327m5830            PEX3  -AW44       A01X+167716Y+111260X0180Y         S1      
317m5830            VIA   -    MD0100PA01X+169225Y+052561X0200Y    R090 S0      
327m5830            C653  -1          A01X+168735Y+052551X0120Y0150R180 S1      
327m5831            C795  -1          A01X+173730Y+140149X0120Y0150R090 S1      
317m5831            VIA   -    MD0100PA01X+173720Y+139658X0180Y         S0      
317m5831            VIA   -    MD0080PA01X+153878Y+123602X0160Y    R270 S0      
327m5831            PEX3  -F7         A01X+153878Y+123602X0180Y         S1      
327m5832            C128  -1          A01X+024512Y+137729X0120Y0150R090 S1      
317m5832            VIA   -    MD0100PA01X+024502Y+137238X0180Y         S0      
317m5832            VIA   -    MD0080PA01X+023110Y+122854X0160Y    R270 S0      
327m5832            PEX0  -H24        A01X+023110Y+122854X0180Y         S1      
317m5833            VIA   -    MD0080PA01X+071063Y+122854X0160Y    R270 S0      
317m5833            VIA   -    MD0100PA01X+055396Y+139658X0180Y         S0      
327m5833            C2262 -1          A01X+055406Y+140149X0120Y0150R090 S1      
327m5833            PEX1  -H30        A01X+071063Y+122854X0180Y         S1      
327m5834            C537  -1          A01X+127919Y+137729X0120Y0150R090 S1      
317m5834            VIA   -    MD0100PA01X+127929Y+137238X0180Y         S0      
317m5834            VIA   -    MD0080PA01X+116772Y+122480X0160Y    R270 S0      
327m5834            PEX2  -J30        A01X+116772Y+122480X0180Y         S1      
317m5835            VIA   -    MD0080PA01X+162854Y+109390X0160Y         S0      
327m5835            PEX3  -BD31       A01X+162854Y+109390X0180Y         S1      
317m5835            VIA   -    MD0100PA01X+151995Y+043692X0200Y    R270 S0      
327m5835            C685  -1          A01X+152486Y+043702X0120Y0150     S1      
317m5836            VIA   -    MD0080PA01X+153504Y+122480X0160Y         S0      
317m5836            VIA   -    MD0100PA01X+173380Y+134819X0180Y         S0      
327m5836            C796  -1          A01X+173370Y+135309X0120Y0150R090 S1      
327m5836            PEX3  -J6         A01X+153504Y+122480X0180Y         S1      
317m5837            VIA   -    MD0080PA01X+023110Y+110138X0160Y    R270 S0      
327m5837            PEX0  -BB24       A01X+023110Y+110138X0180Y         S1      
327m5837            C96   -1          A01X+037818Y+011112X0120Y0150R180 S1      
317m5837            VIA   -    MD0100PA01X+038309Y+011122X0200Y    R090 S0      
317m5838            VIA   -    MD0080PA01X+065079Y+110512X0160Y    R270 S0      
327m5838            C286  -1          A01X+063055Y+012890X0120Y0150R180 S1      
317m5838            VIA   -    MD0100PA01X+063545Y+012880X0200Y    R090 S0      
327m5838            PEX1  -BA14       A01X+065079Y+110512X0180Y         S1      
317m5839            VIA   -    MD0080PA01X+111909Y+109764X0160Y    R270 S0      
327m5839            PEX2  -BC17       A01X+111909Y+109764X0180Y         S1      
327m5839            C503  -1          A01X+120040Y+013601X0120Y0150R180 S1      
317m5839            VIA   -    MD0100PA01X+120530Y+013591X0200Y    R090 S0      
317m5840            VIA   -    MD0080PA01X+167716Y+112008X0160Y    R270 S0      
327m5840            PEX3  -AU44       A01X+167716Y+112008X0180Y         S1      
317m5840            VIA   -    MD0100PA01X+169225Y+051144X0200Y    R090 S0      
327m5840            C657  -1          A01X+168735Y+051134X0120Y0150R180 S1      
327m5841            C777  -1          A01X+152607Y+137729X0120Y0150R090 S1      
317m5841            VIA   -    MD0100PA01X+152597Y+137238X0180Y         S0      
317m5841            VIA   -    MD0080PA01X+156870Y+123602X0160Y    R270 S0      
327m5841            PEX3  -F15        A01X+156870Y+123602X0180Y         S1      
317m5842            VIA   -    MD0080PA01X+019744Y+109390X0160Y    R270 S0      
327m5842            PEX0  -BD15       A01X+019744Y+109390X0180Y         S1      
327m5842            C78   -1          A01X+018386Y+011824X0120Y0150R180 S1      
317m5842            VIA   -    MD0100PA01X+018877Y+011834X0200Y    R090 S0      
317m5843            VIA   -    MD0080PA01X+063209Y+109764X0160Y    R270 S0      
327m5843            PEX1  -BC9        A01X+063209Y+109764X0180Y         S1      
327m5843            C276  -1          A01X+053859Y+013601X0120Y0150R180 S1      
317m5843            VIA   -    MD0100PA01X+054349Y+013591X0200Y    R090 S0      
317m5844            VIA   -    MD0080PA01X+108917Y+109764X0160Y    R270 S0      
327m5844            PEX2  -BC9        A01X+108917Y+109764X0180Y         S1      
327m5844            C487  -1          A01X+099567Y+013601X0120Y0150R180 S1      
317m5844            VIA   -    MD0100PA01X+100058Y+013591X0200Y    R090 S0      
317m5845            VIA   -    MD0080PA01X+161732Y+110512X0160Y    R270 S0      
327m5845            PEX3  -BA28       A01X+161732Y+110512X0180Y         S1      
327m5845            C690  -1          A01X+151446Y+041219X0120Y0150     S1      
317m5845            VIA   -    MD0100PA01X+150955Y+041229X0200Y    R270 S0      
327m5846            C823  -1          A01X+162714Y+137729X0120Y0150R090 S1      
317m5846            VIA   -    MD0100PA01X+162704Y+137238X0180Y         S0      
317m5846            VIA   -    MD0080PA01X+154252Y+119114X0160Y         S0      
327m5846            PEX3  -V8         A01X+154252Y+119114X0180Y         S1      
317m5847            VIA   -    MD0080PA01X+020866Y+110138X0160Y    R270 S0      
327m5847            PEX0  -BB18       A01X+020866Y+110138X0180Y         S1      
327m5847            C84   -1          A01X+027582Y+012530X0120Y0150R180 S1      
317m5847            VIA   -    MD0100PA01X+028073Y+012540X0200Y    R090 S0      
317m5848            VIA   -    MD0080PA01X+069193Y+123602X0160Y    R270 S0      
317m5848            VIA   -    MD0100PA01X+051724Y+137238X0180Y         S0      
327m5848            PEX1  -F25        A01X+069193Y+123602X0180Y         S1      
327m5848            C2272 -1          A01X+051734Y+137729X0120Y0150R090 S1      
327m5849            C539  -1          A01X+126695Y+140149X0120Y0150R090 S1      
317m5849            VIA   -    MD0100PA01X+126705Y+139658X0180Y         S0      
317m5849            VIA   -    MD0080PA01X+116398Y+123228X0160Y    R270 S0      
327m5849            PEX2  -G29        A01X+116398Y+123228X0180Y         S1      
327m5850            C668  -1          A01X+151446Y+052759X0120Y0150     S1      
317m5850            VIA   -    MD0100PA01X+150955Y+052769X0200Y    R270 S0      
317m5850            VIA   -    MD0080PA01X+165846Y+109764X0160Y    R270 S0      
327m5850            PEX3  -BC39       A01X+165846Y+109764X0180Y         S1      
327m5851            C783  -1          A01X+147711Y+140149X0120Y0150R090 S1      
317m5851            VIA   -    MD0100PA01X+147701Y+139658X0180Y         S0      
317m5851            VIA   -    MD0080PA01X+157992Y+122854X0160Y         S0      
327m5851            PEX3  -H18        A01X+157992Y+122854X0180Y         S1      
317m5852            VIA   -    MD0080PA01X+019370Y+110512X0160Y    R270 S0      
327m5852            C75   -1          A01X+017346Y+012890X0120Y0150R180 S1      
317m5852            VIA   -    MD0100PA01X+017837Y+012880X0200Y    R090 S0      
327m5852            PEX0  -BA14       A01X+019370Y+110512X0180Y         S1      
317m5853            VIA   -    MD0080PA01X+071437Y+123602X0160Y    R270 S0      
317m5853            VIA   -    MD0100PA01X+056620Y+137238X0180Y         S0      
327m5853            PEX1  -F31        A01X+071437Y+123602X0180Y         S1      
327m5853            C2260 -1          A01X+056630Y+137729X0120Y0150R090 S1      
317m5854            VIA   -    MD0080PA01X+112657Y+109390X0160Y    R270 S0      
327m5854            PEX2  -BD19       A01X+112657Y+109390X0180Y         S1      
327m5854            C508  -1          A01X+120040Y+011824X0120Y0150R180 S1      
317m5854            VIA   -    MD0100PA01X+120530Y+011834X0200Y    R090 S0      
317m5855            VIA   -    MD0080PA01X+166594Y+109390X0160Y    R270 S0      
327m5855            PEX3  -BD41       A01X+166594Y+109390X0180Y         S1      
317m5855            VIA   -    MD0100PA01X+170266Y+061111X0200Y    R090 S0      
327m5855            C635  -1          A01X+169775Y+061101X0120Y0150R180 S1      
327m5856            C785  -1          A01X+148935Y+137729X0120Y0150R090 S1      
317m5856            VIA   -    MD0100PA01X+148925Y+137238X0180Y         S0      
317m5856            VIA   -    MD0080PA01X+158366Y+123602X0160Y    R270 S0      
327m5856            PEX3  -F19        A01X+158366Y+123602X0180Y         S1      
317m5857            VIA   -    MD0080PA01X+021614Y+110138X0160Y    R270 S0      
327m5857            PEX0  -BB20       A01X+021614Y+110138X0180Y         S1      
327m5857            C88   -1          A01X+027582Y+011112X0120Y0150R180 S1      
317m5857            VIA   -    MD0100PA01X+028073Y+011122X0200Y    R090 S0      
317m5858            VIA   -    MD0080PA01X+072559Y+122854X0160Y    R270 S0      
317m5858            VIA   -    MD0100PA01X+052948Y+137238X0180Y         S0      
327m5858            C2254 -1          A01X+052958Y+137729X0120Y0150R090 S1      
327m5858            PEX1  -H34        A01X+072559Y+122854X0180Y         S1      
327m5859            C541  -1          A01X+126695Y+135309X0120Y0150R090 S1      
317m5859            VIA   -    MD0100PA01X+126705Y+134819X0180Y         S0      
317m5859            VIA   -    MD0080PA01X+116024Y+122480X0160Y    R270 S0      
327m5859            PEX2  -J28        A01X+116024Y+122480X0180Y         S1      
317m5860            VIA   -    MD0080PA01X+160610Y+109390X0160Y    R270 S0      
327m5860            PEX3  -BD25       A01X+160610Y+109390X0180Y         S1      
317m5860            VIA   -    MD0100PA01X+151995Y+039440X0200Y    R270 S0      
327m5860            C697  -1          A01X+152486Y+039450X0120Y0150     S1      
327m5861            C811  -1          A01X+167610Y+137729X0120Y0150R090 S1      
317m5861            VIA   -    MD0100PA01X+167600Y+137238X0180Y         S0      
317m5861            VIA   -    MD0080PA01X+154252Y+121358X0160Y         S0      
327m5861            PEX3  -M8         A01X+154252Y+121358X0180Y         S1      
327m5862            C107  -1          A01X+032720Y+135309X0120Y0150R090 S1      
317m5862            VIA   -    MD0100PA01X+032730Y+134819X0180Y         S0      
317m5862            VIA   -    MD0080PA01X+026850Y+122480X0160Y    R270 S0      
327m5862            PEX0  -J34        A01X+026850Y+122480X0180Y         S1      
317m5863            VIA   -    MD0080PA01X+066201Y+109764X0160Y    R270 S0      
327m5863            PEX1  -BC17       A01X+066201Y+109764X0180Y         S1      
327m5863            C292  -1          A01X+074331Y+013601X0120Y0150R180 S1      
317m5863            VIA   -    MD0100PA01X+074822Y+013591X0200Y    R090 S0      
327m5864            C532  -1          A01X+130727Y+137729X0120Y0150R090 S1      
317m5864            VIA   -    MD0100PA01X+130717Y+137238X0180Y         S0      
317m5864            VIA   -    MD0080PA01X+117894Y+123602X0160Y    R270 S0      
327m5864            PEX2  -F33        A01X+117894Y+123602X0180Y         S1      
317m5865            VIA   -    MD0080PA01X+166594Y+112382X0160Y    R270 S0      
327m5865            PEX3  -AT41       A01X+166594Y+112382X0180Y         S1      
317m5865            VIA   -    MD0100PA01X+170266Y+049199X0200Y    R090 S0      
327m5865            C658  -1          A01X+169775Y+049209X0120Y0150R180 S1      
327m5866            C764  -1          A01X+147351Y+137729X0120Y0150R090 S1      
317m5866            VIA   -    MD0100PA01X+147361Y+137238X0180Y         S0      
317m5866            VIA   -    MD0080PA01X+154626Y+123228X0160Y    R270 S0      
327m5866            PEX3  -G9         A01X+154626Y+123228X0180Y         S1      
327m5867            C124  -1          A01X+025736Y+140149X0120Y0150R090 S1      
317m5867            VIA   -    MD0100PA01X+025726Y+139658X0180Y         S0      
317m5867            VIA   -    MD0080PA01X+023858Y+122854X0160Y    R270 S0      
327m5867            PEX0  -H26        A01X+023858Y+122854X0180Y         S1      
317m5868            VIA   -    MD0080PA01X+067323Y+110512X0160Y    R270 S0      
327m5868            PEX1  -BA20       A01X+067323Y+110512X0180Y         S1      
327m5868            C298  -1          A01X+073291Y+011472X0120Y0150R180 S1      
317m5868            VIA   -    MD0100PA01X+073782Y+011462X0200Y    R090 S0      
327m5869            C528  -1          A01X+131951Y+140149X0120Y0150R090 S1      
317m5869            VIA   -    MD0100PA01X+131941Y+139658X0180Y         S0      
317m5869            VIA   -    MD0080PA01X+118642Y+123602X0160Y    R270 S0      
327m5869            PEX2  -F35        A01X+118642Y+123602X0180Y         S1      
317m5870            VIA   -    MD0080PA01X+167342Y+111260X0160Y    R270 S0      
327m5870            PEX3  -AW43       A01X+167342Y+111260X0180Y         S1      
317m5870            VIA   -    MD0100PA01X+169225Y+052901X0200Y    R090 S0      
327m5870            C652  -1          A01X+168735Y+052911X0120Y0150R180 S1      
327m5871            C788  -1          A01X+149799Y+140149X0120Y0150R090 S1      
317m5871            VIA   -    MD0100PA01X+149809Y+139658X0180Y         S0      
317m5871            VIA   -    MD0080PA01X+159114Y+123228X0160Y    R270 S0      
327m5871            PEX3  -G21        A01X+159114Y+123228X0180Y         S1      
327m5872            C123  -1          A01X+025376Y+140149X0120Y0150R090 S1      
317m5872            VIA   -    MD0100PA01X+025386Y+139658X0180Y         S0      
317m5872            VIA   -    MD0080PA01X+023858Y+122480X0160Y    R270 S0      
327m5872            PEX0  -J26        A01X+023858Y+122480X0180Y         S1      
317m5873            VIA   -    MD0100PA01X+051724Y+134819X0180Y         S0      
327m5873            C2258 -1          A01X+051734Y+135309X0120Y0150R090 S1      
317m5873            VIA   -    MD0080PA01X+071811Y+122854X0160Y    R270 S0      
327m5873            PEX1  -H32        A01X+071811Y+122854X0180Y         S1      
317m5874            VIA   -    MD0080PA01X+109291Y+110512X0160Y    R270 S0      
327m5874            PEX2  -BA10       A01X+109291Y+110512X0180Y         S1      
327m5874            C489  -1          A01X+098527Y+012890X0120Y0150R180 S1      
317m5874            VIA   -    MD0100PA01X+099018Y+012880X0200Y    R090 S0      
317m5875            VIA   -    MD0080PA01X+162106Y+109390X0160Y         S0      
317m5875            VIA   -    MD0100PA01X+151995Y+042275X0200Y    R270 S0      
327m5875            C689  -1          A01X+152486Y+042285X0120Y0150     S1      
327m5875            PEX3  -BD29       A01X+162106Y+109390X0180Y         S1      
327m5876            C793  -1          A01X+152607Y+135309X0120Y0150R090 S1      
317m5876            VIA   -    MD0100PA01X+152597Y+134819X0180Y         S0      
317m5876            VIA   -    MD0080PA01X+159862Y+123602X0160Y    R270 S0      
327m5876            PEX3  -F23        A01X+159862Y+123602X0180Y         S1      
327m5877            C109  -1          A01X+031496Y+137729X0120Y0150R090 S1      
317m5877            VIA   -    MD0100PA01X+031506Y+137238X0180Y         S0      
317m5877            VIA   -    MD0080PA01X+026476Y+123228X0160Y    R270 S0      
327m5877            PEX0  -G33        A01X+026476Y+123228X0180Y         S1      
317m5878            VIA   -    MD0080PA01X+068819Y+122854X0160Y    R270 S0      
317m5878            VIA   -    MD0100PA01X+050500Y+139658X0180Y         S0      
327m5878            PEX1  -H24        A01X+068819Y+122854X0180Y         S1      
327m5878            C2274 -1          A01X+050510Y+140149X0120Y0150R090 S1      
327m5879            C530  -1          A01X+131951Y+135309X0120Y0150R090 S1      
317m5879            VIA   -    MD0100PA01X+131941Y+134819X0180Y         S0      
317m5879            VIA   -    MD0080PA01X+118268Y+122854X0160Y    R270 S0      
327m5879            PEX2  -H34        A01X+118268Y+122854X0180Y         S1      
317m5880            VIA   -    MD0080PA01X+169213Y+110138X0160Y    R270 S0      
327m5880            PEX3  -BB48       A01X+169213Y+110138X0180Y         S1      
327m5880            C650  -1          A01X+169775Y+053622X0120Y0150R180 S1      
317m5880            VIA   -    MD0100PA01X+170266Y+053612X0200Y    R090 S0      
317m5881            VIA   -    MD0080PA01X+157244Y+122854X0160Y         S0      
317m5881            VIA   -    MD0100PA01X+146477Y+137238X0180Y         S0      
327m5881            PEX3  -H16        A01X+157244Y+122854X0180Y         S1      
327m5881            C779  -1          A01X+146487Y+137729X0120Y0150R090 S1      
317m5882            VIA   -    MD0080PA01X+020492Y+109764X0160Y    R270 S0      
327m5882            PEX0  -BC17       A01X+020492Y+109764X0180Y         S1      
327m5882            C81   -1          A01X+028622Y+013601X0120Y0150R180 S1      
317m5882            VIA   -    MD0100PA01X+029113Y+013591X0200Y    R090 S0      
317m5883            VIA   -    MD0080PA01X+070689Y+123602X0160Y    R270 S0      
317m5883            VIA   -    MD0100PA01X+055396Y+134819X0180Y         S0      
327m5883            PEX1  -F29        A01X+070689Y+123602X0180Y         S1      
327m5883            C2264 -1          A01X+055406Y+135309X0120Y0150R090 S1      
317m5884            VIA   -    MD0080PA01X+114528Y+110512X0160Y    R270 S0      
327m5884            PEX2  -BA24       A01X+114528Y+110512X0180Y         S1      
317m5884            VIA   -    MD0100PA01X+129726Y+011462X0200Y    R090 S0      
327m5884            C517  -1          A01X+129236Y+011472X0120Y0150R180 S1      
327m5885            C571  -1          A01X+131591Y+137729X0120Y0150R090 S1      
317m5885            VIA   -    MD0100PA01X+131601Y+137238X0180Y         S0      
317m5885            VIA   -    MD0080PA01X+112283Y+122480X0160Y         S0      
327m5885            PEX2  -J18        A01X+112283Y+122480X0180Y         S1      
317m5886            VIA   -    MD0080PA01X+163976Y+110138X0160Y    R270 S0      
327m5886            C679  -1          A01X+152486Y+048000X0120Y0150     S1      
317m5886            VIA   -    MD0100PA01X+151995Y+047990X0200Y    R270 S0      
327m5886            PEX3  -BB34       A01X+163976Y+110138X0180Y         S1      
327m5887            C790  -1          A01X+151023Y+137729X0120Y0150R090 S1      
317m5887            VIA   -    MD0100PA01X+151033Y+137238X0180Y         S0      
317m5887            VIA   -    MD0080PA01X+159488Y+122480X0160Y         S0      
327m5887            PEX3  -J22        A01X+159488Y+122480X0180Y         S1      
C                                                                               
C  ****************************************                                     
C      DUMMY NET PINS & VIAS ON THE BOARD                                       
C  ****************************************                                     
C                                                                               
317_d_dda579d0      VIA   -     D0080PA00X+119951Y+120049X0160Y         S0      
327_d_dda579d0      PEX2  -T39        A01X+120138Y+119862X0180Y         S1      
317_d_dfc0c900      VIA   -     D0080PA00X+165659Y+120049X0160Y         S0      
327_d_dfc0c900      PEX3  -T39        A01X+165846Y+119862X0180Y         S1      
317_d_ddd83420      VIA   -     D0080PA00X+028533Y+120049X0160Y         S0      
327_d_ddd83420      PEX0  -T39        A01X+028720Y+119862X0180Y         S1      
317_d_ddd7e1e8      VIA   -     D0080PA00X+074242Y+120049X0160Y         S0      
327_d_ddd7e1e8      PEX1  -T39        A01X+074429Y+119862X0180Y         S1      
327_d_dfc0ea88      U6    -E13        A01X+135312Y+088499X0160Y         S1      
317_d_dfc0ea88      VIA   -     D0100PA00X+135470Y+088656X0180Y         S0      
317_d_ddd83e98      VIA   -     D0080PA00X+027785Y+120049X0160Y         S0      
327_d_ddd83e98      PEX0  -T36        A01X+027598Y+119862X0180Y         S1      
317_d_ddd83ec0      VIA   -     D0080PA00X+027411Y+117805X0160Y         S0      
327_d_ddd83ec0      PEX0  -AB35       A01X+027224Y+117618X0180Y         S1      
317_d_ddd83e48      VIA   -     D0080PA00X+027785Y+119675X0160Y         S0      
327_d_ddd83e48      PEX0  -U36        A01X+027598Y+119488X0180Y         S1      
317_d_ddd83e20      VIA   -     D0080PA00X+027785Y+120797X0160Y         S0      
327_d_ddd83e20      PEX0  -P36        A01X+027598Y+120610X0180Y         S1      
317_d_ddd83df8      VIA   -     D0080PA00X+019183Y+112943X0160Y         S0      
327_d_ddd83df8      PEX0  -AP14       A01X+019370Y+113130X0180Y         S1      
317_d_ddd83e70      VIA   -     D0080PA00X+027785Y+120423X0160Y         S0      
327_d_ddd83e70      PEX0  -R36        A01X+027598Y+120236X0180Y         S1      
317_d_ddd83dd0      VIA   -     D0080PA00X+019183Y+113317X0160Y         S0      
327_d_ddd83dd0      PEX0  -AN14       A01X+019370Y+113504X0180Y         S1      
317_d_ddd7ec08      VIA   -     D0080PA00X+073494Y+120797X0160Y         S0      
327_d_ddd7ec08      PEX1  -P36        A01X+073307Y+120610X0180Y         S1      
317_d_ddd7ec80      VIA   -     D0080PA00X+073494Y+120049X0160Y         S0      
327_d_ddd7ec80      PEX1  -T36        A01X+073307Y+119862X0180Y         S1      
317_d_ddd7ec58      VIA   -     D0080PA00X+073494Y+120423X0160Y         S0      
327_d_ddd7ec58      PEX1  -R36        A01X+073307Y+120236X0180Y         S1      
317_d_ddd7ebb8      VIA   -     D0080PA00X+064892Y+113317X0160Y         S0      
327_d_ddd7ebb8      PEX1  -AN14       A01X+065079Y+113504X0180Y         S1      
317_d_ddd7ec30      VIA   -     D0080PA00X+073494Y+119675X0160Y         S0      
327_d_ddd7ec30      PEX1  -U36        A01X+073307Y+119488X0180Y         S1      
317_d_ddd7eca8      VIA   -     D0080PA00X+073120Y+117805X0160Y         S0      
327_d_ddd7eca8      PEX1  -AB35       A01X+072933Y+117618X0180Y         S1      
317_d_ddd7ebe0      VIA   -     D0080PA00X+064892Y+112943X0160Y         S0      
327_d_ddd7ebe0      PEX1  -AP14       A01X+065079Y+113130X0180Y         S1      
317_d_dda58218      VIA   -     D0080PA00X+119203Y+120423X0160Y         S0      
327_d_dda58218      PEX2  -R36        A01X+119016Y+120236X0180Y         S1      
317_d_dda581c8      VIA   -     D0080PA00X+119203Y+120797X0160Y         S0      
327_d_dda581c8      PEX2  -P36        A01X+119016Y+120610X0180Y         S1      
317_d_dda58178      VIA   -     D0080PA00X+110600Y+113317X0160Y         S0      
327_d_dda58178      PEX2  -AN14       A01X+110787Y+113504X0180Y         S1      
317_d_dda581a0      VIA   -     D0080PA00X+110600Y+112943X0160Y         S0      
327_d_dda581a0      PEX2  -AP14       A01X+110787Y+113130X0180Y         S1      
317_d_dda58240      VIA   -     D0080PA00X+119203Y+120049X0160Y         S0      
327_d_dda58240      PEX2  -T36        A01X+119016Y+119862X0180Y         S1      
317_d_dda581f0      VIA   -     D0080PA00X+119203Y+119675X0160Y         S0      
327_d_dda581f0      PEX2  -U36        A01X+119016Y+119488X0180Y         S1      
317_d_dda58268      VIA   -     D0080PA00X+118829Y+117805X0160Y         S0      
327_d_dda58268      PEX2  -AB35       A01X+118642Y+117618X0180Y         S1      
317_d_dfc0d348      VIA   -     D0080PA00X+156309Y+113317X0160Y         S0      
327_d_dfc0d348      PEX3  -AN14       A01X+156496Y+113504X0180Y         S1      
317_d_dfc0d410      VIA   -     D0080PA00X+164911Y+120049X0160Y         S0      
327_d_dfc0d410      PEX3  -T36        A01X+164724Y+119862X0180Y         S1      
317_d_dfc0d370      VIA   -     D0080PA00X+156309Y+112943X0160Y         S0      
327_d_dfc0d370      PEX3  -AP14       A01X+156496Y+113130X0180Y         S1      
317_d_dfc0d438      VIA   -     D0080PA00X+164537Y+117805X0160Y         S0      
327_d_dfc0d438      PEX3  -AB35       A01X+164350Y+117618X0180Y         S1      
317_d_dfc0d3c0      VIA   -     D0080PA00X+164911Y+119675X0160Y         S0      
327_d_dfc0d3c0      PEX3  -U36        A01X+164724Y+119488X0180Y         S1      
317_d_dfc0d3e8      VIA   -     D0080PA00X+164911Y+120423X0160Y         S0      
327_d_dfc0d3e8      PEX3  -R36        A01X+164724Y+120236X0180Y         S1      
317_d_dfc0d398      VIA   -     D0080PA00X+164911Y+120797X0160Y         S0      
327_d_dfc0d398      PEX3  -P36        A01X+164724Y+120610X0180Y         S1      
317_d_ddd7c280      VIA   -     D0100PA00X+090027Y+083584X0180Y    R270 S0      
327_d_ddd7c280      U5    -A10        A01X+089869Y+083742X0160Y    R180 S1      
317_d_ddd7bfd8      VIA   -     D0100PA00X+089082Y+084844X0180Y         S0      
327_d_ddd7bfd8      U5    -E12        A01X+089239Y+085002X0160Y    R180 S1      
317_d_ddd7c1b8      VIA   -     D0100PA00X+088137Y+084844X0180Y    R270 S0      
327_d_ddd7c1b8      U5    -E15        A01X+088294Y+085002X0160Y    R180 S1      
317_d_dd97ea48      VIA   -     D0100PA00X+091916Y+084214X0180Y    R270 S0      
327_d_dd97ea48      U5    -C4         A01X+091759Y+084372X0160Y    R180 S1      
317_d_dd754930      VIA   -     D0100PA00X+132320Y+085507X0180Y         S0      
327_d_dd754930      U6    -P4         A01X+132478Y+085664X0160Y         S1      
317_d_dfc0fe10      VIA   -     D0100PA00X+131691Y+085822X0180Y         S0      
327_d_dfc0fe10      U6    -N2         A01X+131848Y+085979X0160Y         S1      
317_d_dfc0fe38      VIA   -     D0100PA00X+131376Y+085507X0180Y    R270 S0      
327_d_dfc0fe38      U6    -R1         A01X+131533Y+085349X0160Y         S1      
317_d_dda56df0      VIA   -     D0080PA00X+107608Y+111073X0160Y         S0      
327_d_dda56df0      PEX2  -AW6        A01X+107795Y+111260X0180Y         S1      
317_d_ddd7d248      VIA   -     D0080PA00X+060778Y+113317X0160Y         S0      
327_d_ddd7d248      PEX1  -AN3        A01X+060965Y+113504X0180Y         S1      
317_d_ddd7e080      VIA   -     D0080PA00X+076112Y+117431X0160Y         S0      
327_d_ddd7e080      PEX1  -AC43       A01X+075925Y+117244X0180Y         S1      
317_d_dda57048      VIA   -     D0080PA00X+108356Y+110325X0160Y         S0      
327_d_dda57048      PEX2  -BA8        A01X+108543Y+110512X0180Y         S1      
317_d_dfc0c090      VIA   -     D0080PA00X+153317Y+110325X0160Y         S0      
327_d_dfc0c090      PEX3  -BA6        A01X+153504Y+110512X0180Y         S1      
317_d_ddd7d338      VIA   -     D0080PA00X+060778Y+111073X0160Y         S0      
327_d_ddd7d338      PEX1  -AW3        A01X+060965Y+111260X0180Y         S1      
317_d_ddd7e120      VIA   -     D0080PA00X+074990Y+114813X0160Y         S0      
327_d_ddd7e120      PEX1  -AK41       A01X+075177Y+114626X0180Y         S1      
317_d_dfc0be10      VIA   -     D0080PA00X+154065Y+111447X0160Y         S0      
327_d_dfc0be10      PEX3  -AV8        A01X+154252Y+111634X0180Y         S1      
317_d_dda56f08      VIA   -     D0080PA00X+108730Y+111447X0160Y         S0      
327_d_dda56f08      PEX2  -AV9        A01X+108917Y+111634X0180Y         S1      
317_d_ddd7d4a0      VIA   -     D0080PA00X+060404Y+112943X0160Y         S0      
327_d_ddd7d4a0      PEX1  -AP2        A01X+060590Y+113130X0180Y         S1      
317_d_ddd7e0d0      VIA   -     D0080PA00X+074990Y+115561X0160Y         S0      
327_d_ddd7e0d0      PEX1  -AH41       A01X+075177Y+115374X0180Y         S1      
317_d_dfc0be38      VIA   -     D0080PA00X+153317Y+111073X0160Y         S0      
327_d_dfc0be38      PEX3  -AW6        A01X+153504Y+111260X0180Y         S1      
317_d_ddd7def0      VIA   -     D0080PA00X+076486Y+118179X0160Y         S0      
327_d_ddd7def0      PEX1  -AA44       A01X+076299Y+117992X0180Y         S1      
317_d_dfc0bfa0      VIA   -     D0080PA00X+153691Y+111073X0160Y         S0      
327_d_dfc0bfa0      PEX3  -AW7        A01X+153878Y+111260X0180Y         S1      
317_d_ddd7d388      VIA   -     D0080PA00X+060778Y+107333X0160Y         S0      
327_d_ddd7d388      PEX1  -BJ3        A01X+060965Y+107520X0180Y         S1      
317_d_ddd7d270      VIA   -     D0080PA00X+060030Y+112943X0160Y         S0      
327_d_ddd7d270      PEX1  -AP1        A01X+060216Y+113130X0180Y         S1      
317_d_ddd7e058      VIA   -     D0080PA00X+076112Y+118179X0160Y         S0      
327_d_ddd7e058      PEX1  -AA43       A01X+075925Y+117992X0180Y         S1      
317_d_ddd7dfb8      VIA   -     D0080PA00X+076486Y+114439X0160Y         S0      
327_d_ddd7dfb8      PEX1  -AL44       A01X+076299Y+114252X0180Y         S1      
317_d_ddd7d478      VIA   -     D0080PA00X+060404Y+113691X0160Y         S0      
327_d_ddd7d478      PEX1  -AM2        A01X+060590Y+113878X0180Y         S1      
317_d_dda56f58      VIA   -     D0080PA00X+106112Y+109951X0160Y         S0      
327_d_dda56f58      PEX2  -BB2        A01X+106299Y+110138X0180Y         S1      
317_d_ddd7df90      VIA   -     D0080PA00X+076486Y+115187X0160Y         S0      
327_d_ddd7df90      PEX1  -AJ44       A01X+076299Y+115000X0180Y         S1      
317_d_ddd7d590      VIA   -     D0080PA00X+060404Y+110699X0160Y         S0      
327_d_ddd7d590      PEX1  -AY2        A01X+060590Y+110886X0180Y         S1      
317_d_dda56eb8      VIA   -     D0080PA00X+107608Y+109951X0160Y         S0      
327_d_dda56eb8      PEX2  -BB6        A01X+107795Y+110138X0180Y         S1      
317_d_dfc0c4f0      VIA   -     D0080PA00X+168278Y+115561X0160Y         S0      
327_d_dfc0c4f0      PEX3  -AG46       A01X+168464Y+115748X0180Y         S1      
317_d_dfc0bf50      VIA   -     D0080PA00X+153691Y+109203X0160Y         S0      
327_d_dfc0bf50      PEX3  -BD7        A01X+153878Y+109390X0180Y         S1      
317_d_e05f5328      VIA   -     D0080PA00X+107234Y+109203X0160Y         S0      
327_d_e05f5328      PEX2  -BD5        A01X+107421Y+109390X0180Y         S1      
317_d_ddd7df68      VIA   -     D0080PA00X+075364Y+115561X0160Y         S0      
327_d_ddd7df68      PEX1  -AH42       A01X+075551Y+115374X0180Y         S1      
317_d_ddd7d540      VIA   -     D0080PA00X+060404Y+111447X0160Y         S0      
327_d_ddd7d540      PEX1  -AV2        A01X+060590Y+111634X0180Y         S1      
317_d_ddd7e0f8      VIA   -     D0080PA00X+076112Y+115187X0160Y         S0      
327_d_ddd7e0f8      PEX1  -AJ43       A01X+075925Y+115000X0180Y         S1      
317_d_ddd7d450      VIA   -     D0080PA00X+062648Y+108081X0160Y         S0      
327_d_ddd7d450      PEX1  -BG8        A01X+062835Y+108268X0180Y         S1      
317_d_dda56fa8      VIA   -     D0080PA00X+106486Y+109577X0160Y         S0      
327_d_dda56fa8      PEX2  -BC3        A01X+106673Y+109764X0180Y         S1      
317_d_ddd7df40      VIA   -     D0080PA00X+075364Y+117057X0160Y         S0      
327_d_ddd7df40      PEX1  -AD42       A01X+075551Y+116870X0180Y         S1      
317_d_dfc0bb40      VIA   -     D0080PA00X+152569Y+108081X0160Y         S0      
327_d_dfc0bb40      PEX3  -BG4        A01X+152756Y+108268X0180Y         S1      
317_d_dfc0c478      VIA   -     D0080PA00X+169400Y+117431X0160Y         S0      
327_d_dfc0c478      PEX3  -AB48       A01X+169213Y+117618X0180Y         S1      
317_d_ddd7e170      VIA   -     D0080PA00X+074990Y+114065X0160Y         S0      
327_d_ddd7e170      PEX1  -AM41       A01X+075177Y+113878X0180Y         S1      
317_d_dfc0baf0      VIA   -     D0080PA00X+151447Y+110699X0160Y         S0      
327_d_dfc0baf0      PEX3  -AY1        A01X+151634Y+110886X0180Y         S1      
317_d_dfc0c428      VIA   -     D0080PA00X+169400Y+118179X0160Y         S0      
327_d_dfc0c428      PEX3  -Y48        A01X+169213Y+118366X0180Y         S1      
317_d_ddd7d310      VIA   -     D0080PA00X+060030Y+111447X0160Y         S0      
327_d_ddd7d310      PEX1  -AV1        A01X+060216Y+111634X0180Y         S1      
317_d_dfc0b9b0      VIA   -     D0080PA00X+151447Y+113691X0160Y         S0      
327_d_dfc0b9b0      PEX3  -AM1        A01X+151634Y+113878X0180Y         S1      
317_d_dda56fd0      VIA   -     D0080PA00X+106860Y+110325X0160Y         S0      
327_d_dda56fd0      PEX2  -BA4        A01X+107047Y+110512X0180Y         S1      
317_d_ddd7df18      VIA   -     D0080PA00X+076486Y+117431X0160Y         S0      
327_d_ddd7df18      PEX1  -AC44       A01X+076299Y+117244X0180Y         S1      
317_d_ddd7d428      VIA   -     D0080PA00X+062274Y+107333X0160Y         S0      
327_d_ddd7d428      PEX1  -BJ7        A01X+062461Y+107520X0180Y         S1      
317_d_ddd7e0a8      VIA   -     D0080PA00X+074990Y+117057X0160Y         S0      
327_d_ddd7e0a8      PEX1  -AD41       A01X+075177Y+116870X0180Y         S1      
317_d_ddd7d2c0      VIA   -     D0080PA00X+060030Y+112195X0160Y         S0      
327_d_ddd7d2c0      PEX1  -AT1        A01X+060216Y+112382X0180Y         S1      
317_d_dfc0bff0      VIA   -     D0080PA00X+151821Y+108829X0160Y         S0      
327_d_dfc0bff0      PEX3  -BE2        A01X+152008Y+109016X0180Y         S1      
317_d_dfc0bde8      VIA   -     D0080PA00X+154065Y+108455X0160Y         S0      
327_d_dfc0bde8      PEX3  -BF8        A01X+154252Y+108642X0180Y         S1      
317_d_ddd7d360      VIA   -     D0080PA00X+060030Y+110699X0160Y         S0      
327_d_ddd7d360      PEX1  -AY1        A01X+060216Y+110886X0180Y         S1      
317_d_dfc0c018      VIA   -     D0080PA00X+152195Y+109577X0160Y         S0      
327_d_dfc0c018      PEX3  -BC3        A01X+152382Y+109764X0180Y         S1      
317_d_dfc0bca8      VIA   -     D0080PA00X+152569Y+111821X0160Y         S0      
327_d_dfc0bca8      PEX3  -AU4        A01X+152756Y+112008X0180Y         S1      
317_d_ddd7e148      VIA   -     D0080PA00X+076112Y+114439X0160Y         S0      
327_d_ddd7e148      PEX1  -AL43       A01X+075925Y+114252X0180Y         S1      
317_d_dfc0beb0      VIA   -     D0080PA00X+152195Y+109203X0160Y         S0      
327_d_dfc0beb0      PEX3  -BD3        A01X+152382Y+109390X0180Y         S1      
317_d_dfc0bd20      VIA   -     D0080PA00X+151821Y+110699X0160Y         S0      
327_d_dfc0bd20      PEX3  -AY2        A01X+152008Y+110886X0180Y         S1      
317_d_dfc0c310      VIA   -     D0080PA00X+168652Y+114813X0160Y         S0      
327_d_dfc0c310      PEX3  -AJ47       A01X+168838Y+115000X0180Y         S1      
317_d_dda56e18      VIA   -     D0080PA00X+105738Y+109951X0160Y         S0      
327_d_dda56e18      PEX2  -BB1        A01X+105925Y+110138X0180Y         S1      
317_d_dfc0c0e0      VIA   -     D0080PA00X+154065Y+110325X0160Y         S0      
327_d_dfc0c0e0      PEX3  -BA8        A01X+154252Y+110512X0180Y         S1      
317_d_dfc0b9d8      VIA   -     D0080PA00X+152195Y+113317X0160Y         S0      
327_d_dfc0b9d8      PEX3  -AN3        A01X+152382Y+113504X0180Y         S1      
317_d_dfc0bc08      VIA   -     D0080PA00X+151821Y+113691X0160Y         S0      
327_d_dfc0bc08      PEX3  -AM2        A01X+152008Y+113878X0180Y         S1      
317_d_dfc0c590      VIA   -     D0080PA00X+168278Y+114065X0160Y         S0      
327_d_dfc0c590      PEX3  -AL46       A01X+168464Y+114252X0180Y         S1      
317_d_dfc0bf28      VIA   -     D0080PA00X+153317Y+109951X0160Y         S0      
327_d_dfc0bf28      PEX3  -BB6        A01X+153504Y+110138X0180Y         S1      
317_d_dfc0c4c8      VIA   -     D0080PA00X+169400Y+115935X0160Y         S0      
327_d_dfc0c4c8      PEX3  -AF48       A01X+169213Y+116122X0180Y         S1      
317_d_dda56dc8      VIA   -     D0080PA00X+108356Y+111447X0160Y         S0      
327_d_dda56dc8      PEX2  -AV8        A01X+108543Y+111634X0180Y         S1      
317_d_dfc0c040      VIA   -     D0080PA00X+152569Y+110325X0160Y         S0      
327_d_dfc0c040      PEX3  -BA4        A01X+152756Y+110512X0180Y         S1      
317_d_dfc0c1f8      VIA   -     D0080PA00X+169774Y+118179X0160Y         S0      
327_d_dfc0c1f8      PEX3  -Y49        A01X+169587Y+118366X0180Y         S1      
317_d_dfc0c068      VIA   -     D0080PA00X+152943Y+109577X0160Y         S0      
327_d_dfc0c068      PEX3  -BC5        A01X+153130Y+109764X0180Y         S1      
317_d_dda56f80      VIA   -     D0080PA00X+106112Y+108829X0160Y         S0      
327_d_dda56f80      PEX2  -BE2        A01X+106299Y+109016X0180Y         S1      
317_d_dfc0be88      VIA   -     D0080PA00X+151447Y+108829X0160Y         S0      
327_d_dfc0be88      PEX3  -BE1        A01X+151634Y+109016X0180Y         S1      
317_d_dfc0c4a0      VIA   -     D0080PA00X+168278Y+117057X0160Y         S0      
327_d_dfc0c4a0      PEX3  -AC46       A01X+168464Y+117244X0180Y         S1      
317_d_dda56e40      VIA   -     D0080PA00X+105738Y+108829X0160Y         S0      
327_d_dda56e40      PEX2  -BE1        A01X+105925Y+109016X0180Y         S1      
317_d_dfc0bed8      VIA   -     D0080PA00X+152569Y+109951X0160Y         S0      
327_d_dfc0bed8      PEX3  -BB4        A01X+152756Y+110138X0180Y         S1      
317_d_dfc0bdc0      VIA   -     D0080PA00X+153691Y+107707X0160Y         S0      
327_d_dfc0bdc0      PEX3  -BH7        A01X+153878Y+107894X0180Y         S1      
317_d_dfc0c388      VIA   -     D0080PA00X+169774Y+113691X0160Y         S0      
327_d_dfc0c388      PEX3  -AM49       A01X+169587Y+113878X0180Y         S1      
317_d_dfc0c298      VIA   -     D0080PA00X+169774Y+115935X0160Y         S0      
327_d_dfc0c298      PEX3  -AF49       A01X+169587Y+116122X0180Y         S1      
317_d_dfc0bf00      VIA   -     D0080PA00X+152943Y+109203X0160Y         S0      
327_d_dfc0bf00      PEX3  -BD5        A01X+153130Y+109390X0180Y         S1      
317_d_dfc0c0b8      VIA   -     D0080PA00X+153691Y+109577X0160Y         S0      
327_d_dfc0c0b8      PEX3  -BC7        A01X+153878Y+109764X0180Y         S1      
317_d_dfc0c1a8      VIA   -     D0080PA00X+169774Y+118927X0160Y         S0      
327_d_dfc0c1a8      PEX3  -V49        A01X+169587Y+119114X0180Y         S1      
317_d_dfc0bfc8      VIA   -     D0080PA00X+151821Y+109951X0160Y         S0      
327_d_dfc0bfc8      PEX3  -BB2        A01X+152008Y+110138X0180Y         S1      
317_d_dfc0c400      VIA   -     D0080PA00X+168278Y+118553X0160Y         S0      
327_d_dfc0c400      PEX3  -W46        A01X+168464Y+118740X0180Y         S1      
317_d_dfc0ba00      VIA   -     D0080PA00X+151447Y+112943X0160Y         S0      
327_d_dfc0ba00      PEX3  -AP1        A01X+151634Y+113130X0180Y         S1      
317_d_dfc0c2c0      VIA   -     D0080PA00X+168652Y+115561X0160Y         S0      
327_d_dfc0c2c0      PEX3  -AG47       A01X+168838Y+115748X0180Y         S1      
317_d_dfc0bb68      VIA   -     D0080PA00X+152943Y+107333X0160Y         S0      
327_d_dfc0bb68      PEX3  -BJ5        A01X+153130Y+107520X0180Y         S1      
317_d_dfc0c220      VIA   -     D0080PA00X+168652Y+117805X0160Y         S0      
327_d_dfc0c220      PEX3  -AA47       A01X+168838Y+117992X0180Y         S1      
317_d_dfc0bbe0      VIA   -     D0080PA00X+154065Y+108081X0160Y         S0      
327_d_dfc0bbe0      PEX3  -BG8        A01X+154252Y+108268X0180Y         S1      
317_d_dfc0c338      VIA   -     D0080PA00X+169774Y+114439X0160Y         S0      
327_d_dfc0c338      PEX3  -AK49       A01X+169587Y+114626X0180Y         S1      
317_d_dfc0bf78      VIA   -     D0080PA00X+154439Y+111447X0160Y         S0      
327_d_dfc0bf78      PEX3  -AV9        A01X+154626Y+111634X0180Y         S1      
317_d_dfc0ba78      VIA   -     D0080PA00X+152195Y+111821X0160Y         S0      
327_d_dfc0ba78      PEX3  -AU3        A01X+152382Y+112008X0180Y         S1      
317_d_dfc0c3d8      VIA   -     D0080PA00X+169400Y+118927X0160Y         S0      
327_d_dfc0c3d8      PEX3  -V48        A01X+169213Y+119114X0180Y         S1      
317_d_dfc0baa0      VIA   -     D0080PA00X+151447Y+111447X0160Y         S0      
327_d_dfc0baa0      PEX3  -AV1        A01X+151634Y+111634X0180Y         S1      
317_d_dfc0c3b0      VIA   -     D0080PA00X+168278Y+119301X0160Y         S0      
327_d_dfc0c3b0      PEX3  -U46        A01X+168464Y+119488X0180Y         S1      
317_d_dfc0ba28      VIA   -     D0080PA00X+152195Y+112569X0160Y         S0      
327_d_dfc0ba28      PEX3  -AR3        A01X+152382Y+112756X0180Y         S1      
317_d_dfc0bd98      VIA   -     D0080PA00X+153317Y+108455X0160Y         S0      
327_d_dfc0bd98      PEX3  -BF6        A01X+153504Y+108642X0180Y         S1      
317_d_dfc0c450      VIA   -     D0080PA00X+168278Y+117805X0160Y         S0      
327_d_dfc0c450      PEX3  -AA46       A01X+168464Y+117992X0180Y         S1      
317_d_dfc0ba50      VIA   -     D0080PA00X+151447Y+112195X0160Y         S0      
327_d_dfc0ba50      PEX3  -AT1        A01X+151634Y+112382X0180Y         S1      
317_d_dfc0bb90      VIA   -     D0080PA00X+153317Y+108081X0160Y         S0      
327_d_dfc0bb90      PEX3  -BG6        A01X+153504Y+108268X0180Y         S1      
317_d_dfc0bc30      VIA   -     D0080PA00X+151821Y+112943X0160Y         S0      
327_d_dfc0bc30      PEX3  -AP2        A01X+152008Y+113130X0180Y         S1      
317_d_dfc0c568      VIA   -     D0080PA00X+169400Y+114439X0160Y         S0      
327_d_dfc0c568      PEX3  -AK48       A01X+169213Y+114626X0180Y         S1      
317_d_dfc0bc80      VIA   -     D0080PA00X+151821Y+112195X0160Y         S0      
327_d_dfc0bc80      PEX3  -AT2        A01X+152008Y+112382X0180Y         S1      
317_d_dfc0c270      VIA   -     D0080PA00X+168652Y+117057X0160Y         S0      
327_d_dfc0c270      PEX3  -AC47       A01X+168838Y+117244X0180Y         S1      
317_d_dfc0bbb8      VIA   -     D0080PA00X+153691Y+107333X0160Y         S0      
327_d_dfc0bbb8      PEX3  -BJ7        A01X+153878Y+107520X0180Y         S1      
317_d_dfc0bd48      VIA   -     D0080PA00X+152569Y+108455X0160Y         S0      
327_d_dfc0bd48      PEX3  -BF4        A01X+152756Y+108642X0180Y         S1      
317_d_dfc0c2e8      VIA   -     D0080PA00X+169774Y+115187X0160Y         S0      
327_d_dfc0c2e8      PEX3  -AH49       A01X+169587Y+115374X0180Y         S1      
317_d_dfc0c180      VIA   -     D0080PA00X+168652Y+119301X0160Y         S0      
327_d_dfc0c180      PEX3  -U47        A01X+168838Y+119488X0180Y         S1      
317_d_dfc0bc58      VIA   -     D0080PA00X+152569Y+112569X0160Y         S0      
327_d_dfc0bc58      PEX3  -AR4        A01X+152756Y+112756X0180Y         S1      
317_d_dfc0bb18      VIA   -     D0080PA00X+152195Y+107333X0160Y         S0      
327_d_dfc0bb18      PEX3  -BJ3        A01X+152382Y+107520X0180Y         S1      
317_d_dfc0c360      VIA   -     D0080PA00X+168652Y+114065X0160Y         S0      
327_d_dfc0c360      PEX3  -AL47       A01X+168838Y+114252X0180Y         S1      
317_d_dfc0bcf8      VIA   -     D0080PA00X+152569Y+111073X0160Y         S0      
327_d_dfc0bcf8      PEX3  -AW4        A01X+152756Y+111260X0180Y         S1      
317_d_dfc0c1d0      VIA   -     D0080PA00X+168652Y+118553X0160Y         S0      
327_d_dfc0c1d0      PEX3  -W47        A01X+168838Y+118740X0180Y         S1      
317_d_dfc0bcd0      VIA   -     D0080PA00X+151821Y+111447X0160Y         S0      
327_d_dfc0bcd0      PEX3  -AV2        A01X+152008Y+111634X0180Y         S1      
317_d_dfc0c518      VIA   -     D0080PA00X+169400Y+115187X0160Y         S0      
327_d_dfc0c518      PEX3  -AH48       A01X+169213Y+115374X0180Y         S1      
317_d_dfc0c540      VIA   -     D0080PA00X+168278Y+114813X0160Y         S0      
327_d_dfc0c540      PEX3  -AJ46       A01X+168464Y+115000X0180Y         S1      
317_d_dfc0c5b8      VIA   -     D0080PA00X+169400Y+113691X0160Y         S0      
327_d_dfc0c5b8      PEX3  -AM48       A01X+169213Y+113878X0180Y         S1      
317_d_dfc0c248      VIA   -     D0080PA00X+169774Y+117431X0160Y         S0      
327_d_dfc0c248      PEX3  -AB49       A01X+169587Y+117618X0180Y         S1      
317_d_dfc0bd70      VIA   -     D0080PA00X+152943Y+107707X0160Y         S0      
327_d_dfc0bd70      PEX3  -BH5        A01X+153130Y+107894X0180Y         S1      
317_d_dfc0bac8      VIA   -     D0080PA00X+152195Y+111073X0160Y         S0      
327_d_dfc0bac8      PEX3  -AW3        A01X+152382Y+111260X0180Y         S1      
317_d_dfc0c680      VIA   -     D0080PA00X+167904Y+117431X0160Y         S0      
327_d_dfc0c680      PEX3  -AC44       A01X+167716Y+117244X0180Y         S1      
317_d_dfc0c8d8      VIA   -     D0080PA00X+166408Y+114065X0160Y         S0      
327_d_dfc0c8d8      PEX3  -AM41       A01X+166594Y+113878X0180Y         S1      
317_d_dfc0c860      VIA   -     D0080PA00X+167530Y+115187X0160Y         S0      
327_d_dfc0c860      PEX3  -AJ43       A01X+167342Y+115000X0180Y         S1      
317_d_dfc0c720      VIA   -     D0080PA00X+167904Y+114439X0160Y         S0      
327_d_dfc0c720      PEX3  -AL44       A01X+167716Y+114252X0180Y         S1      
317_d_dfc0c7c0      VIA   -     D0080PA00X+167530Y+118179X0160Y         S0      
327_d_dfc0c7c0      PEX3  -AA43       A01X+167342Y+117992X0180Y         S1      
317_d_ddd7dcc0      VIA   -     D0080PA00X+077982Y+118179X0160Y         S0      
327_d_ddd7dcc0      PEX1  -Y48        A01X+077795Y+118366X0180Y         S1      
317_d_dfc0c8b0      VIA   -     D0080PA00X+167530Y+114439X0160Y         S0      
327_d_dfc0c8b0      PEX3  -AL43       A01X+167342Y+114252X0180Y         S1      
317_d_dfc0c7e8      VIA   -     D0080PA00X+167530Y+117431X0160Y         S0      
327_d_dfc0c7e8      PEX3  -AC43       A01X+167342Y+117244X0180Y         S1      
317_d_dda56bc0      VIA   -     D0080PA00X+108356Y+108081X0160Y         S0      
327_d_dda56bc0      PEX2  -BG8        A01X+108543Y+108268X0180Y         S1      
317_d_ddd7db30      VIA   -     D0080PA00X+078356Y+115935X0160Y         S0      
327_d_ddd7db30      PEX1  -AF49       A01X+078169Y+116122X0180Y         S1      
317_d_ddd7ddd8      VIA   -     D0080PA00X+076860Y+114813X0160Y         S0      
327_d_ddd7ddd8      PEX1  -AJ46       A01X+077047Y+115000X0180Y         S1      
317_d_dfc0c630      VIA   -     D0080PA00X+167904Y+118927X0160Y         S0      
327_d_dfc0c630      PEX3  -W44        A01X+167716Y+118740X0180Y         S1      
317_d_dda56b98      VIA   -     D0080PA00X+107982Y+107333X0160Y         S0      
327_d_dda56b98      PEX2  -BJ7        A01X+108169Y+107520X0180Y         S1      
317_d_dda56b20      VIA   -     D0080PA00X+106486Y+107333X0160Y         S0      
327_d_dda56b20      PEX2  -BJ3        A01X+106673Y+107520X0180Y         S1      
317_d_dfc0c838      VIA   -     D0080PA00X+166408Y+115561X0160Y         S0      
327_d_dfc0c838      PEX3  -AH41       A01X+166594Y+115374X0180Y         S1      
317_d_e05fa848      VIA   -     D0080PA00X+107234Y+107333X0160Y         S0      
327_d_e05fa848      PEX2  -BJ5        A01X+107421Y+107520X0180Y         S1      
317_d_dfc0c888      VIA   -     D0080PA00X+166408Y+114813X0160Y         S0      
327_d_dfc0c888      PEX3  -AK41       A01X+166594Y+114626X0180Y         S1      
317_d_ddd7dce8      VIA   -     D0080PA00X+076860Y+117805X0160Y         S0      
327_d_ddd7dce8      PEX1  -AA46       A01X+077047Y+117992X0180Y         S1      
317_d_dfc0c6d0      VIA   -     D0080PA00X+166782Y+115561X0160Y         S0      
327_d_dfc0c6d0      PEX3  -AH42       A01X+166968Y+115374X0180Y         S1      
317_d_dda56b70      VIA   -     D0080PA00X+107608Y+108081X0160Y         S0      
327_d_dda56b70      PEX2  -BG6        A01X+107795Y+108268X0180Y         S1      
317_d_ddd7da90      VIA   -     D0080PA00X+078356Y+118179X0160Y         S0      
327_d_ddd7da90      PEX1  -Y49        A01X+078169Y+118366X0180Y         S1      
317_d_dfc0c6a8      VIA   -     D0080PA00X+166782Y+117057X0160Y         S0      
327_d_dfc0c6a8      PEX3  -AD42       A01X+166968Y+116870X0180Y         S1      
317_d_dda57368      VIA   -     D0080PA00X+124065Y+115935X0160Y         S0      
327_d_dda57368      PEX2  -AF49       A01X+123878Y+116122X0180Y         S1      
317_d_ddd7dbf8      VIA   -     D0080PA00X+077234Y+114065X0160Y         S0      
327_d_ddd7dbf8      PEX1  -AL47       A01X+077421Y+114252X0180Y         S1      
317_d_dda56d50      VIA   -     D0080PA00X+107608Y+108455X0160Y         S0      
327_d_dda56d50      PEX2  -BF6        A01X+107795Y+108642X0180Y         S1      
317_d_ddd7de28      VIA   -     D0080PA00X+076860Y+114065X0160Y         S0      
327_d_ddd7de28      PEX1  -AL46       A01X+077047Y+114252X0180Y         S1      
317_d_dfc0c6f8      VIA   -     D0080PA00X+167904Y+115187X0160Y         S0      
327_d_dfc0c6f8      PEX3  -AJ44       A01X+167716Y+115000X0180Y         S1      
317_d_dda57390      VIA   -     D0080PA00X+122943Y+115561X0160Y         S0      
327_d_dda57390      PEX2  -AG47       A01X+123130Y+115748X0180Y         S1      
317_d_ddd7dd88      VIA   -     D0080PA00X+076860Y+115561X0160Y         S0      
327_d_ddd7dd88      PEX1  -AG46       A01X+077047Y+115748X0180Y         S1      
317_d_dfc0c810      VIA   -     D0080PA00X+166408Y+117057X0160Y         S0      
327_d_dfc0c810      PEX3  -AD41       A01X+166594Y+116870X0180Y         S1      
317_d_dda56b48      VIA   -     D0080PA00X+106860Y+108081X0160Y         S0      
327_d_dda56b48      PEX2  -BG4        A01X+107047Y+108268X0180Y         S1      
317_d_dda57520      VIA   -     D0080PA00X+122569Y+117805X0160Y         S0      
327_d_dda57520      PEX2  -AA46       A01X+122756Y+117992X0180Y         S1      
317_d_dfc0c798      VIA   -     D0080PA00X+167530Y+118927X0160Y         S0      
327_d_dfc0c798      PEX3  -W43        A01X+167342Y+118740X0180Y         S1      
317_d_dda57548      VIA   -     D0080PA00X+123691Y+117431X0160Y         S0      
327_d_dda57548      PEX2  -AB48       A01X+123504Y+117618X0180Y         S1      
317_d_dda56be8      VIA   -     D0080PA00X+106112Y+113691X0160Y         S0      
327_d_dda56be8      PEX2  -AM2        A01X+106299Y+113878X0180Y         S1      
317_d_ddd7dd38      VIA   -     D0080PA00X+076860Y+117057X0160Y         S0      
327_d_ddd7dd38      PEX1  -AC46       A01X+077047Y+117244X0180Y         S1      
317_d_dfc0c658      VIA   -     D0080PA00X+167904Y+118179X0160Y         S0      
327_d_dfc0c658      PEX3  -AA44       A01X+167716Y+117992X0180Y         S1      
317_d_dda57598      VIA   -     D0080PA00X+123691Y+115935X0160Y         S0      
327_d_dda57598      PEX2  -AF48       A01X+123504Y+116122X0180Y         S1      
317_d_dda56c60      VIA   -     D0080PA00X+106112Y+112195X0160Y         S0      
327_d_dda56c60      PEX2  -AT2        A01X+106299Y+112382X0180Y         S1      
317_d_dda57250      VIA   -     D0080PA00X+122943Y+119301X0160Y         S0      
327_d_dda57250      PEX2  -U47        A01X+123130Y+119488X0180Y         S1      
317_d_ddd7dbd0      VIA   -     D0080PA00X+078356Y+114439X0160Y         S0      
327_d_ddd7dbd0      PEX1  -AK49       A01X+078169Y+114626X0180Y         S1      
317_d_dda57638      VIA   -     D0080PA00X+123691Y+114439X0160Y         S0      
327_d_dda57638      PEX2  -AK48       A01X+123504Y+114626X0180Y         S1      
317_d_dda572a0      VIA   -     D0080PA00X+122943Y+118553X0160Y         S0      
327_d_dda572a0      PEX2  -W47        A01X+123130Y+118740X0180Y         S1      
317_d_dda57480      VIA   -     D0080PA00X+122569Y+119301X0160Y         S0      
327_d_dda57480      PEX2  -U46        A01X+122756Y+119488X0180Y         S1      
317_d_dda56a58      VIA   -     D0080PA00X+105738Y+112195X0160Y         S0      
327_d_dda56a58      PEX2  -AT1        A01X+105925Y+112382X0180Y         S1      
317_d_ddd7db08      VIA   -     D0080PA00X+077234Y+117057X0160Y         S0      
327_d_ddd7db08      PEX1  -AC47       A01X+077421Y+117244X0180Y         S1      
317_d_dda572f0      VIA   -     D0080PA00X+122943Y+117805X0160Y         S0      
327_d_dda572f0      PEX2  -AA47       A01X+123130Y+117992X0180Y         S1      
317_d_dda574a8      VIA   -     D0080PA00X+123691Y+118927X0160Y         S0      
327_d_dda574a8      PEX2  -V48        A01X+123504Y+119114X0180Y         S1      
317_d_dda569e0      VIA   -     D0080PA00X+106486Y+113317X0160Y         S0      
327_d_dda569e0      PEX2  -AN3        A01X+106673Y+113504X0180Y         S1      
317_d_ddd7dd10      VIA   -     D0080PA00X+077982Y+117431X0160Y         S0      
327_d_ddd7dd10      PEX1  -AB48       A01X+077795Y+117618X0180Y         S1      
317_d_dda57278      VIA   -     D0080PA00X+124065Y+118927X0160Y         S0      
327_d_dda57278      PEX2  -V49        A01X+123878Y+119114X0180Y         S1      
317_d_ddd7de00      VIA   -     D0080PA00X+077982Y+114439X0160Y         S0      
327_d_ddd7de00      PEX1  -AK48       A01X+077795Y+114626X0180Y         S1      
317_d_ddd7ddb0      VIA   -     D0080PA00X+077982Y+115187X0160Y         S0      
327_d_ddd7ddb0      PEX1  -AH48       A01X+077795Y+115374X0180Y         S1      
317_d_dda56d00      VIA   -     D0080PA00X+106112Y+110699X0160Y         S0      
327_d_dda56d00      PEX2  -AY2        A01X+106299Y+110886X0180Y         S1      
317_d_dda574d0      VIA   -     D0080PA00X+122569Y+118553X0160Y         S0      
327_d_dda574d0      PEX2  -W46        A01X+122756Y+118740X0180Y         S1      
317_d_dda569b8      VIA   -     D0080PA00X+105738Y+113691X0160Y         S0      
327_d_dda569b8      PEX2  -AM1        A01X+105925Y+113878X0180Y         S1      
317_d_ddd7db80      VIA   -     D0080PA00X+078356Y+115187X0160Y         S0      
327_d_ddd7db80      PEX1  -AH49       A01X+078169Y+115374X0180Y         S1      
317_d_dda575c0      VIA   -     D0080PA00X+122569Y+115561X0160Y         S0      
327_d_dda575c0      PEX2  -AG46       A01X+122756Y+115748X0180Y         S1      
317_d_dda56c10      VIA   -     D0080PA00X+106112Y+112943X0160Y         S0      
327_d_dda56c10      PEX2  -AP2        A01X+106299Y+113130X0180Y         S1      
317_d_dda57408      VIA   -     D0080PA00X+124065Y+114439X0160Y         S0      
327_d_dda57408      PEX2  -AK49       A01X+123878Y+114626X0180Y         S1      
317_d_dda573e0      VIA   -     D0080PA00X+122943Y+114813X0160Y         S0      
327_d_dda573e0      PEX2  -AJ47       A01X+123130Y+115000X0180Y         S1      
317_d_dda574f8      VIA   -     D0080PA00X+123691Y+118179X0160Y         S0      
327_d_dda574f8      PEX2  -Y48        A01X+123504Y+118366X0180Y         S1      
317_d_dda56a08      VIA   -     D0080PA00X+105738Y+112943X0160Y         S0      
327_d_dda56a08      PEX2  -AP1        A01X+105925Y+113130X0180Y         S1      
317_d_ddd7da18      VIA   -     D0080PA00X+077234Y+119301X0160Y         S0      
327_d_ddd7da18      PEX1  -U47        A01X+077421Y+119488X0180Y         S1      
317_d_dda56af8      VIA   -     D0080PA00X+105738Y+110699X0160Y         S0      
327_d_dda56af8      PEX2  -AY1        A01X+105925Y+110886X0180Y         S1      
317_d_dda57430      VIA   -     D0080PA00X+122943Y+114065X0160Y         S0      
327_d_dda57430      PEX2  -AL47       A01X+123130Y+114252X0180Y         S1      
317_d_dda56a80      VIA   -     D0080PA00X+106486Y+111821X0160Y         S0      
327_d_dda56a80      PEX2  -AU3        A01X+106673Y+112008X0180Y         S1      
317_d_ddd7db58      VIA   -     D0080PA00X+077234Y+115561X0160Y         S0      
327_d_ddd7db58      PEX1  -AG47       A01X+077421Y+115748X0180Y         S1      
317_d_dda572c8      VIA   -     D0080PA00X+124065Y+118179X0160Y         S0      
327_d_dda572c8      PEX2  -Y49        A01X+123878Y+118366X0180Y         S1      
317_d_dda56ad0      VIA   -     D0080PA00X+106486Y+111073X0160Y         S0      
327_d_dda56ad0      PEX2  -AW3        A01X+106673Y+111260X0180Y         S1      
317_d_ddd7dc48      VIA   -     D0080PA00X+076860Y+119301X0160Y         S0      
327_d_ddd7dc48      PEX1  -U46        A01X+077047Y+119488X0180Y         S1      
317_d_dda57660      VIA   -     D0080PA00X+122569Y+114065X0160Y         S0      
327_d_dda57660      PEX2  -AL46       A01X+122756Y+114252X0180Y         S1      
317_d_dda57570      VIA   -     D0080PA00X+122569Y+117057X0160Y         S0      
327_d_dda57570      PEX2  -AC46       A01X+122756Y+117244X0180Y         S1      
317_d_ddd7dae0      VIA   -     D0080PA00X+078356Y+117431X0160Y         S0      
327_d_ddd7dae0      PEX1  -AB49       A01X+078169Y+117618X0180Y         S1      
317_d_dda56d78      VIA   -     D0080PA00X+107982Y+107707X0160Y         S0      
327_d_dda56d78      PEX2  -BH7        A01X+108169Y+107894X0180Y         S1      
317_d_ddd7dba8      VIA   -     D0080PA00X+077234Y+114813X0160Y         S0      
327_d_ddd7dba8      PEX1  -AJ47       A01X+077421Y+115000X0180Y         S1      
317_d_dda56c88      VIA   -     D0080PA00X+106860Y+111821X0160Y         S0      
327_d_dda56c88      PEX2  -AU4        A01X+107047Y+112008X0180Y         S1      
317_d_dda573b8      VIA   -     D0080PA00X+124065Y+115187X0160Y         S0      
327_d_dda573b8      PEX2  -AH49       A01X+123878Y+115374X0180Y         S1      
317_d_dda56d28      VIA   -     D0080PA00X+106860Y+108455X0160Y         S0      
327_d_dda56d28      PEX2  -BF4        A01X+107047Y+108642X0180Y         S1      
317_d_ddd7da68      VIA   -     D0080PA00X+077234Y+118553X0160Y         S0      
327_d_ddd7da68      PEX1  -W47        A01X+077421Y+118740X0180Y         S1      
317_d_ddd7dc70      VIA   -     D0080PA00X+077982Y+118927X0160Y         S0      
327_d_ddd7dc70      PEX1  -V48        A01X+077795Y+119114X0180Y         S1      
317_d_dda57688      VIA   -     D0080PA00X+123691Y+113691X0160Y         S0      
327_d_dda57688      PEX2  -AM48       A01X+123504Y+113878X0180Y         S1      
317_d_dda56cd8      VIA   -     D0080PA00X+106860Y+111073X0160Y         S0      
327_d_dda56cd8      PEX2  -AW4        A01X+107047Y+111260X0180Y         S1      
317_d_dda57340      VIA   -     D0080PA00X+122943Y+117057X0160Y         S0      
327_d_dda57340      PEX2  -AC47       A01X+123130Y+117244X0180Y         S1      
317_d_dda56c38      VIA   -     D0080PA00X+106860Y+112569X0160Y         S0      
327_d_dda56c38      PEX2  -AR4        A01X+107047Y+112756X0180Y         S1      
317_d_ddd7dd60      VIA   -     D0080PA00X+077982Y+115935X0160Y         S0      
327_d_ddd7dd60      PEX1  -AF48       A01X+077795Y+116122X0180Y         S1      
317_d_ddd7dab8      VIA   -     D0080PA00X+077234Y+117805X0160Y         S0      
327_d_ddd7dab8      PEX1  -AA47       A01X+077421Y+117992X0180Y         S1      
317_d_dda56cb0      VIA   -     D0080PA00X+106112Y+111447X0160Y         S0      
327_d_dda56cb0      PEX2  -AV2        A01X+106299Y+111634X0180Y         S1      
317_d_ddd7dc98      VIA   -     D0080PA00X+076860Y+118553X0160Y         S0      
327_d_ddd7dc98      PEX1  -W46        A01X+077047Y+118740X0180Y         S1      
317_d_dda57610      VIA   -     D0080PA00X+122569Y+114813X0160Y         S0      
327_d_dda57610      PEX2  -AJ46       A01X+122756Y+115000X0180Y         S1      
317_d_dda56aa8      VIA   -     D0080PA00X+105738Y+111447X0160Y         S0      
327_d_dda56aa8      PEX2  -AV1        A01X+105925Y+111634X0180Y         S1      
317_d_ddd7da40      VIA   -     D0080PA00X+078356Y+118927X0160Y         S0      
327_d_ddd7da40      PEX1  -V49        A01X+078169Y+119114X0180Y         S1      
317_d_dda575e8      VIA   -     D0080PA00X+123691Y+115187X0160Y         S0      
327_d_dda575e8      PEX2  -AH48       A01X+123504Y+115374X0180Y         S1      
317_d_dda57318      VIA   -     D0080PA00X+124065Y+117431X0160Y         S0      
327_d_dda57318      PEX2  -AB49       A01X+123878Y+117618X0180Y         S1      
317_d_e05f52d8      VIA   -     D0080PA00X+107234Y+107707X0160Y         S0      
327_d_e05f52d8      PEX2  -BH5        A01X+107421Y+107894X0180Y         S1      
317_d_dda57458      VIA   -     D0080PA00X+124065Y+113691X0160Y         S0      
327_d_dda57458      PEX2  -AM49       A01X+123878Y+113878X0180Y         S1      
317_d_ddd7d950      VIA   -     D0080PA00X+062648Y+110325X0160Y         S0      
327_d_ddd7d950      PEX1  -BA8        A01X+062835Y+110512X0180Y         S1      
317_d_dda56a30      VIA   -     D0080PA00X+106486Y+112569X0160Y         S0      
327_d_dda56a30      PEX2  -AR3        A01X+106673Y+112756X0180Y         S1      
317_d_dda56da0      VIA   -     D0080PA00X+108356Y+108455X0160Y         S0      
327_d_dda56da0      PEX2  -BF8        A01X+108543Y+108642X0180Y         S1      
317_d_ddd7d860      VIA   -     D0080PA00X+060404Y+108829X0160Y         S0      
327_d_ddd7d860      PEX1  -BE2        A01X+060590Y+109016X0180Y         S1      
317_d_ddd7d928      VIA   -     D0080PA00X+062274Y+109577X0160Y         S0      
327_d_ddd7d928      PEX1  -BC7        A01X+062461Y+109764X0180Y         S1      
317_d_ddd7d748      VIA   -     D0080PA00X+061152Y+109951X0160Y         S0      
327_d_ddd7d748      PEX1  -BB4        A01X+061339Y+110138X0180Y         S1      
317_d_ddd7d6f8      VIA   -     D0080PA00X+060030Y+108829X0160Y         S0      
327_d_ddd7d6f8      PEX1  -BE1        A01X+060216Y+109016X0180Y         S1      
317_d_ddd7d7c0      VIA   -     D0080PA00X+062274Y+109203X0160Y         S0      
327_d_ddd7d7c0      PEX1  -BD7        A01X+062461Y+109390X0180Y         S1      
317_d_ddd7d838      VIA   -     D0080PA00X+060404Y+109951X0160Y         S0      
327_d_ddd7d838      PEX1  -BB2        A01X+060590Y+110138X0180Y         S1      
317_d_ddd7d798      VIA   -     D0080PA00X+061900Y+109951X0160Y         S0      
327_d_ddd7d798      PEX1  -BB6        A01X+062087Y+110138X0180Y         S1      
317_d_dda578e0      VIA   -     D0080PA00X+120699Y+117057X0160Y         S0      
327_d_dda578e0      PEX2  -AD41       A01X+120886Y+116870X0180Y         S1      
317_d_dda577f0      VIA   -     D0080PA00X+122195Y+114439X0160Y         S0      
327_d_dda577f0      PEX2  -AL44       A01X+122008Y+114252X0180Y         S1      
317_d_ddd7d8b0      VIA   -     D0080PA00X+061152Y+110325X0160Y         S0      
327_d_ddd7d8b0      PEX1  -BA4        A01X+061339Y+110512X0180Y         S1      
317_d_ddd7d7e8      VIA   -     D0080PA00X+063022Y+111447X0160Y         S0      
327_d_ddd7d7e8      PEX1  -AV9        A01X+063209Y+111634X0180Y         S1      
317_d_ddd7d6a8      VIA   -     D0080PA00X+061900Y+111073X0160Y         S0      
327_d_ddd7d6a8      PEX1  -AW6        A01X+062087Y+111260X0180Y         S1      
317_d_dda57700      VIA   -     D0080PA00X+122195Y+118927X0160Y         S0      
327_d_dda57700      PEX2  -W44        A01X+122008Y+118740X0180Y         S1      
317_d_ddd7d770      VIA   -     D0080PA00X+061526Y+109203X0160Y         S0      
327_d_ddd7d770      PEX1  -BD5        A01X+061713Y+109390X0180Y         S1      
317_d_dda577c8      VIA   -     D0080PA00X+122195Y+115187X0160Y         S0      
327_d_dda577c8      PEX2  -AJ44       A01X+122008Y+115000X0180Y         S1      
317_d_ddd7d6d0      VIA   -     D0080PA00X+060030Y+109951X0160Y         S0      
327_d_ddd7d6d0      PEX1  -BB1        A01X+060216Y+110138X0180Y         S1      
317_d_dda579a8      VIA   -     D0080PA00X+120699Y+114065X0160Y         S0      
327_d_dda579a8      PEX2  -AM41       A01X+120886Y+113878X0180Y         S1      
317_d_ddd7d900      VIA   -     D0080PA00X+061900Y+110325X0160Y         S0      
327_d_ddd7d900      PEX1  -BA6        A01X+062087Y+110512X0180Y         S1      
317_d_dda57890      VIA   -     D0080PA00X+121821Y+118179X0160Y         S0      
327_d_dda57890      PEX2  -AA43       A01X+121634Y+117992X0180Y         S1      
317_d_ddd7d8d8      VIA   -     D0080PA00X+061526Y+109577X0160Y         S0      
327_d_ddd7d8d8      PEX1  -BC5        A01X+061713Y+109764X0180Y         S1      
317_d_dda577a0      VIA   -     D0080PA00X+121073Y+115561X0160Y         S0      
327_d_dda577a0      PEX2  -AH42       A01X+121260Y+115374X0180Y         S1      
317_d_ddd7d888      VIA   -     D0080PA00X+060778Y+109577X0160Y         S0      
327_d_ddd7d888      PEX1  -BC3        A01X+060965Y+109764X0180Y         S1      
317_d_ddd7d720      VIA   -     D0080PA00X+060778Y+109203X0160Y         S0      
327_d_ddd7d720      PEX1  -BD3        A01X+060965Y+109390X0180Y         S1      
317_d_ddd7d810      VIA   -     D0080PA00X+062274Y+111073X0160Y         S0      
327_d_ddd7d810      PEX1  -AW7        A01X+062461Y+111260X0180Y         S1      
317_d_ddd7d680      VIA   -     D0080PA00X+062648Y+111447X0160Y         S0      
327_d_ddd7d680      PEX1  -AV8        A01X+062835Y+111634X0180Y         S1      
317_d_dda57750      VIA   -     D0080PA00X+122195Y+117431X0160Y         S0      
327_d_dda57750      PEX2  -AC44       A01X+122008Y+117244X0180Y         S1      
317_d_dda57958      VIA   -     D0080PA00X+120699Y+114813X0160Y         S0      
327_d_dda57958      PEX2  -AK41       A01X+120886Y+114626X0180Y         S1      
317_d_dda57728      VIA   -     D0080PA00X+122195Y+118179X0160Y         S0      
327_d_dda57728      PEX2  -AA44       A01X+122008Y+117992X0180Y         S1      
317_d_dda57908      VIA   -     D0080PA00X+120699Y+115561X0160Y         S0      
327_d_dda57908      PEX2  -AH41       A01X+120886Y+115374X0180Y         S1      
317_d_dda57778      VIA   -     D0080PA00X+121073Y+117057X0160Y         S0      
327_d_dda57778      PEX2  -AD42       A01X+121260Y+116870X0180Y         S1      
317_d_dda578b8      VIA   -     D0080PA00X+121821Y+117431X0160Y         S0      
327_d_dda578b8      PEX2  -AC43       A01X+121634Y+117244X0180Y         S1      
317_d_dda57930      VIA   -     D0080PA00X+121821Y+115187X0160Y         S0      
327_d_dda57930      PEX2  -AJ43       A01X+121634Y+115000X0180Y         S1      
317_d_dda57980      VIA   -     D0080PA00X+121821Y+114439X0160Y         S0      
327_d_dda57980      PEX2  -AL43       A01X+121634Y+114252X0180Y         S1      
317_d_dda57868      VIA   -     D0080PA00X+121821Y+118927X0160Y         S0      
327_d_dda57868      PEX2  -W43        A01X+121634Y+118740X0180Y         S1      
317_d_ddd7d568      VIA   -     D0080PA00X+061152Y+111073X0160Y         S0      
327_d_ddd7d568      PEX1  -AW4        A01X+061339Y+111260X0180Y         S1      
317_d_ddd7d5b8      VIA   -     D0080PA00X+061152Y+108455X0160Y         S0      
327_d_ddd7d5b8      PEX1  -BF4        A01X+061339Y+108642X0180Y         S1      
317_d_ddd7d3b0      VIA   -     D0080PA00X+061152Y+108081X0160Y         S0      
327_d_ddd7d3b0      PEX1  -BG4        A01X+061339Y+108268X0180Y         S1      
317_d_ddd7d298      VIA   -     D0080PA00X+060778Y+112569X0160Y         S0      
327_d_ddd7d298      PEX1  -AR3        A01X+060965Y+112756X0180Y         S1      
317_d_ddd7d220      VIA   -     D0080PA00X+060030Y+113691X0160Y         S0      
327_d_ddd7d220      PEX1  -AM1        A01X+060216Y+113878X0180Y         S1      
317_d_ddd7d4f0      VIA   -     D0080PA00X+060404Y+112195X0160Y         S0      
327_d_ddd7d4f0      PEX1  -AT2        A01X+060590Y+112382X0180Y         S1      
317_d_ddd7d4c8      VIA   -     D0080PA00X+061152Y+112569X0160Y         S0      
327_d_ddd7d4c8      PEX1  -AR4        A01X+061339Y+112756X0180Y         S1      
317_d_ddd7d658      VIA   -     D0080PA00X+062648Y+108455X0160Y         S0      
327_d_ddd7d658      PEX1  -BF8        A01X+062835Y+108642X0180Y         S1      
317_d_dda56ee0      VIA   -     D0080PA00X+107982Y+109203X0160Y         S0      
327_d_dda56ee0      PEX2  -BD7        A01X+108169Y+109390X0180Y         S1      
317_d_ddd7d630      VIA   -     D0080PA00X+062274Y+107707X0160Y         S0      
327_d_ddd7d630      PEX1  -BH7        A01X+062461Y+107894X0180Y         S1      
317_d_ddd7d5e0      VIA   -     D0080PA00X+061526Y+107707X0160Y         S0      
327_d_ddd7d5e0      PEX1  -BH5        A01X+061713Y+107894X0180Y         S1      
317_d_dda56f30      VIA   -     D0080PA00X+107982Y+111073X0160Y         S0      
327_d_dda56f30      PEX2  -AW7        A01X+108169Y+111260X0180Y         S1      
317_d_ddd7d400      VIA   -     D0080PA00X+061900Y+108081X0160Y         S0      
327_d_ddd7d400      PEX1  -BG6        A01X+062087Y+108268X0180Y         S1      
317_d_e05f5300      VIA   -     D0080PA00X+107234Y+109577X0160Y         S0      
327_d_e05f5300      PEX2  -BC5        A01X+107421Y+109764X0180Y         S1      
317_d_ddd7d3d8      VIA   -     D0080PA00X+061526Y+107333X0160Y         S0      
327_d_ddd7d3d8      PEX1  -BJ5        A01X+061713Y+107520X0180Y         S1      
317_d_ddd7d608      VIA   -     D0080PA00X+061900Y+108455X0160Y         S0      
327_d_ddd7d608      PEX1  -BF6        A01X+062087Y+108642X0180Y         S1      
317_d_dfc0be60      VIA   -     D0080PA00X+151447Y+109951X0160Y         S0      
327_d_dfc0be60      PEX3  -BB1        A01X+151634Y+110138X0180Y         S1      
317_d_dda56e68      VIA   -     D0080PA00X+106486Y+109203X0160Y         S0      
327_d_dda56e68      PEX2  -BD3        A01X+106673Y+109390X0180Y         S1      
317_d_dda56e90      VIA   -     D0080PA00X+106860Y+109951X0160Y         S0      
327_d_dda56e90      PEX2  -BB4        A01X+107047Y+110138X0180Y         S1      
317_d_ddd7d2e8      VIA   -     D0080PA00X+060778Y+111821X0160Y         S0      
327_d_ddd7d2e8      PEX1  -AU3        A01X+060965Y+112008X0180Y         S1      
317_d_dda57020      VIA   -     D0080PA00X+107982Y+109577X0160Y         S0      
327_d_dda57020      PEX2  -BC7        A01X+108169Y+109764X0180Y         S1      
317_d_dda56ff8      VIA   -     D0080PA00X+107608Y+110325X0160Y         S0      
327_d_dda56ff8      PEX2  -BA6        A01X+107795Y+110512X0180Y         S1      
317_d_ddd7d518      VIA   -     D0080PA00X+061152Y+111821X0160Y         S0      
327_d_ddd7d518      PEX1  -AU4        A01X+061339Y+112008X0180Y         S1      
317_d_ddd81eb8      VIA   -     D0080PA00X+014321Y+112943X0160Y         S0      
327_d_ddd81eb8      PEX0  -AP1        A01X+014508Y+113130X0180Y         S1      
317_d_ddd81ee0      VIA   -     D0080PA00X+015069Y+112569X0160Y         S0      
327_d_ddd81ee0      PEX0  -AR3        A01X+015256Y+112756X0180Y         S1      
317_d_ddd81f08      VIA   -     D0080PA00X+014321Y+112195X0160Y         S0      
327_d_ddd81f08      PEX0  -AT1        A01X+014508Y+112382X0180Y         S1      
317_d_ddd81f30      VIA   -     D0080PA00X+015069Y+111821X0160Y         S0      
327_d_ddd81f30      PEX0  -AU3        A01X+015256Y+112008X0180Y         S1      
317_d_ddd81f58      VIA   -     D0080PA00X+014321Y+111447X0160Y         S0      
327_d_ddd81f58      PEX0  -AV1        A01X+014508Y+111634X0180Y         S1      
317_d_ddd81f80      VIA   -     D0080PA00X+015069Y+111073X0160Y         S0      
327_d_ddd81f80      PEX0  -AW3        A01X+015256Y+111260X0180Y         S1      
317_d_ddd81fa8      VIA   -     D0080PA00X+014321Y+110699X0160Y         S0      
327_d_ddd81fa8      PEX0  -AY1        A01X+014508Y+110886X0180Y         S1      
317_d_ddd81fd0      VIA   -     D0080PA00X+015069Y+107333X0160Y         S0      
327_d_ddd81fd0      PEX0  -BJ3        A01X+015256Y+107520X0180Y         S1      
317_d_ddd81ff8      VIA   -     D0080PA00X+015443Y+108081X0160Y         S0      
327_d_ddd81ff8      PEX0  -BG4        A01X+015630Y+108268X0180Y         S1      
317_d_ddd82020      VIA   -     D0080PA00X+015817Y+107333X0160Y         S0      
327_d_ddd82020      PEX0  -BJ5        A01X+016004Y+107520X0180Y         S1      
317_d_ddd82048      VIA   -     D0080PA00X+016191Y+108081X0160Y         S0      
327_d_ddd82048      PEX0  -BG6        A01X+016378Y+108268X0180Y         S1      
317_d_ddd82070      VIA   -     D0080PA00X+016565Y+107333X0160Y         S0      
327_d_ddd82070      PEX0  -BJ7        A01X+016752Y+107520X0180Y         S1      
317_d_ddd82098      VIA   -     D0080PA00X+016939Y+108081X0160Y         S0      
327_d_ddd82098      PEX0  -BG8        A01X+017126Y+108268X0180Y         S1      
317_d_ddd820e8      VIA   -     D0080PA00X+014695Y+112943X0160Y         S0      
327_d_ddd820e8      PEX0  -AP2        A01X+014882Y+113130X0180Y         S1      
317_d_ddd82110      VIA   -     D0080PA00X+015443Y+112569X0160Y         S0      
327_d_ddd82110      PEX0  -AR4        A01X+015630Y+112756X0180Y         S1      
317_d_ddd82138      VIA   -     D0080PA00X+014695Y+112195X0160Y         S0      
327_d_ddd82138      PEX0  -AT2        A01X+014882Y+112382X0180Y         S1      
317_d_ddd82160      VIA   -     D0080PA00X+015443Y+111821X0160Y         S0      
327_d_ddd82160      PEX0  -AU4        A01X+015630Y+112008X0180Y         S1      
317_d_ddd82188      VIA   -     D0080PA00X+014695Y+111447X0160Y         S0      
327_d_ddd82188      PEX0  -AV2        A01X+014882Y+111634X0180Y         S1      
317_d_ddd821b0      VIA   -     D0080PA00X+015443Y+111073X0160Y         S0      
327_d_ddd821b0      PEX0  -AW4        A01X+015630Y+111260X0180Y         S1      
317_d_ddd821d8      VIA   -     D0080PA00X+014695Y+110699X0160Y         S0      
327_d_ddd821d8      PEX0  -AY2        A01X+014882Y+110886X0180Y         S1      
317_d_ddd82200      VIA   -     D0080PA00X+015443Y+108455X0160Y         S0      
327_d_ddd82200      PEX0  -BF4        A01X+015630Y+108642X0180Y         S1      
317_d_ddd82228      VIA   -     D0080PA00X+015817Y+107707X0160Y         S0      
327_d_ddd82228      PEX0  -BH5        A01X+016004Y+107894X0180Y         S1      
317_d_ddd82250      VIA   -     D0080PA00X+016191Y+108455X0160Y         S0      
327_d_ddd82250      PEX0  -BF6        A01X+016378Y+108642X0180Y         S1      
317_d_ddd82278      VIA   -     D0080PA00X+016565Y+107707X0160Y         S0      
327_d_ddd82278      PEX0  -BH7        A01X+016752Y+107894X0180Y         S1      
317_d_ddd822a0      VIA   -     D0080PA00X+016939Y+108455X0160Y         S0      
327_d_ddd822a0      PEX0  -BF8        A01X+017126Y+108642X0180Y         S1      
317_d_ddd822c8      VIA   -     D0080PA00X+016191Y+111073X0160Y         S0      
327_d_ddd822c8      PEX0  -AW6        A01X+016378Y+111260X0180Y         S1      
317_d_ddd822f0      VIA   -     D0080PA00X+014321Y+109951X0160Y         S0      
327_d_ddd822f0      PEX0  -BB1        A01X+014508Y+110138X0180Y         S1      
317_d_ddd82318      VIA   -     D0080PA00X+014321Y+108829X0160Y         S0      
327_d_ddd82318      PEX0  -BE1        A01X+014508Y+109016X0180Y         S1      
317_d_ddd82340      VIA   -     D0080PA00X+015069Y+109203X0160Y         S0      
327_d_ddd82340      PEX0  -BD3        A01X+015256Y+109390X0180Y         S1      
317_d_ddd82368      VIA   -     D0080PA00X+015443Y+109951X0160Y         S0      
327_d_ddd82368      PEX0  -BB4        A01X+015630Y+110138X0180Y         S1      
317_d_ddd82390      VIA   -     D0080PA00X+015817Y+109203X0160Y         S0      
327_d_ddd82390      PEX0  -BD5        A01X+016004Y+109390X0180Y         S1      
317_d_ddd823b8      VIA   -     D0080PA00X+016191Y+109951X0160Y         S0      
327_d_ddd823b8      PEX0  -BB6        A01X+016378Y+110138X0180Y         S1      
317_d_ddd823e0      VIA   -     D0080PA00X+016565Y+109203X0160Y         S0      
327_d_ddd823e0      PEX0  -BD7        A01X+016752Y+109390X0180Y         S1      
317_d_ddd82408      VIA   -     D0080PA00X+016565Y+111073X0160Y         S0      
327_d_ddd82408      PEX0  -AW7        A01X+016752Y+111260X0180Y         S1      
317_d_ddd82430      VIA   -     D0080PA00X+014695Y+109951X0160Y         S0      
327_d_ddd82430      PEX0  -BB2        A01X+014882Y+110138X0180Y         S1      
317_d_ddd82458      VIA   -     D0080PA00X+014695Y+108829X0160Y         S0      
327_d_ddd82458      PEX0  -BE2        A01X+014882Y+109016X0180Y         S1      
317_d_ddd82480      VIA   -     D0080PA00X+015069Y+109577X0160Y         S0      
327_d_ddd82480      PEX0  -BC3        A01X+015256Y+109764X0180Y         S1      
317_d_ddd824a8      VIA   -     D0080PA00X+015443Y+110325X0160Y         S0      
327_d_ddd824a8      PEX0  -BA4        A01X+015630Y+110512X0180Y         S1      
317_d_ddd824d0      VIA   -     D0080PA00X+015817Y+109577X0160Y         S0      
327_d_ddd824d0      PEX0  -BC5        A01X+016004Y+109764X0180Y         S1      
317_d_ddd824f8      VIA   -     D0080PA00X+016191Y+110325X0160Y         S0      
327_d_ddd824f8      PEX0  -BA6        A01X+016378Y+110512X0180Y         S1      
317_d_ddd82520      VIA   -     D0080PA00X+016565Y+109577X0160Y         S0      
327_d_ddd82520      PEX0  -BC7        A01X+016752Y+109764X0180Y         S1      
317_d_ddd82548      VIA   -     D0080PA00X+016939Y+110325X0160Y         S0      
327_d_ddd82548      PEX0  -BA8        A01X+017126Y+110512X0180Y         S1      
317_d_ddd82c00      VIA   -     D0080PA00X+031526Y+119301X0160Y         S0      
327_d_ddd82c00      PEX0  -U47        A01X+031712Y+119488X0180Y         S1      
317_d_ddd82c28      VIA   -     D0080PA00X+032648Y+118927X0160Y         S0      
327_d_ddd82c28      PEX0  -V49        A01X+032461Y+119114X0180Y         S1      
317_d_ddd82c50      VIA   -     D0080PA00X+031526Y+118553X0160Y         S0      
327_d_ddd82c50      PEX0  -W47        A01X+031712Y+118740X0180Y         S1      
317_d_ddd82c78      VIA   -     D0080PA00X+032648Y+118179X0160Y         S0      
327_d_ddd82c78      PEX0  -Y49        A01X+032461Y+118366X0180Y         S1      
317_d_ddd82ca0      VIA   -     D0080PA00X+031526Y+117805X0160Y         S0      
327_d_ddd82ca0      PEX0  -AA47       A01X+031712Y+117992X0180Y         S1      
317_d_ddd82cc8      VIA   -     D0080PA00X+032648Y+117431X0160Y         S0      
327_d_ddd82cc8      PEX0  -AB49       A01X+032461Y+117618X0180Y         S1      
317_d_ddd82cf0      VIA   -     D0080PA00X+031526Y+117057X0160Y         S0      
327_d_ddd82cf0      PEX0  -AC47       A01X+031712Y+117244X0180Y         S1      
317_d_ddd82d18      VIA   -     D0080PA00X+032648Y+115935X0160Y         S0      
327_d_ddd82d18      PEX0  -AF49       A01X+032461Y+116122X0180Y         S1      
317_d_ddd82d40      VIA   -     D0080PA00X+031526Y+115561X0160Y         S0      
327_d_ddd82d40      PEX0  -AG47       A01X+031712Y+115748X0180Y         S1      
317_d_ddd82d68      VIA   -     D0080PA00X+032648Y+115187X0160Y         S0      
327_d_ddd82d68      PEX0  -AH49       A01X+032461Y+115374X0180Y         S1      
317_d_ddd82d90      VIA   -     D0080PA00X+031526Y+114813X0160Y         S0      
327_d_ddd82d90      PEX0  -AJ47       A01X+031712Y+115000X0180Y         S1      
317_d_ddd82db8      VIA   -     D0080PA00X+032648Y+114439X0160Y         S0      
327_d_ddd82db8      PEX0  -AK49       A01X+032461Y+114626X0180Y         S1      
317_d_ddd82de0      VIA   -     D0080PA00X+031526Y+114065X0160Y         S0      
327_d_ddd82de0      PEX0  -AL47       A01X+031712Y+114252X0180Y         S1      
317_d_ddd82e08      VIA   -     D0080PA00X+032648Y+113691X0160Y         S0      
327_d_ddd82e08      PEX0  -AM49       A01X+032461Y+113878X0180Y         S1      
317_d_ddd82e30      VIA   -     D0080PA00X+031152Y+119301X0160Y         S0      
327_d_ddd82e30      PEX0  -U46        A01X+031338Y+119488X0180Y         S1      
317_d_ddd82e58      VIA   -     D0080PA00X+032274Y+118927X0160Y         S0      
327_d_ddd82e58      PEX0  -V48        A01X+032087Y+119114X0180Y         S1      
317_d_ddd82e80      VIA   -     D0080PA00X+031152Y+118553X0160Y         S0      
327_d_ddd82e80      PEX0  -W46        A01X+031338Y+118740X0180Y         S1      
317_d_ddd82ea8      VIA   -     D0080PA00X+032274Y+118179X0160Y         S0      
327_d_ddd82ea8      PEX0  -Y48        A01X+032087Y+118366X0180Y         S1      
317_d_ddd82ed0      VIA   -     D0080PA00X+031152Y+117805X0160Y         S0      
327_d_ddd82ed0      PEX0  -AA46       A01X+031338Y+117992X0180Y         S1      
317_d_ddd82ef8      VIA   -     D0080PA00X+032274Y+117431X0160Y         S0      
327_d_ddd82ef8      PEX0  -AB48       A01X+032087Y+117618X0180Y         S1      
317_d_ddd82f20      VIA   -     D0080PA00X+031152Y+117057X0160Y         S0      
327_d_ddd82f20      PEX0  -AC46       A01X+031338Y+117244X0180Y         S1      
317_d_ddd82f48      VIA   -     D0080PA00X+032274Y+115935X0160Y         S0      
327_d_ddd82f48      PEX0  -AF48       A01X+032087Y+116122X0180Y         S1      
317_d_ddd82f70      VIA   -     D0080PA00X+031152Y+115561X0160Y         S0      
327_d_ddd82f70      PEX0  -AG46       A01X+031338Y+115748X0180Y         S1      
317_d_ddd82f98      VIA   -     D0080PA00X+032274Y+115187X0160Y         S0      
327_d_ddd82f98      PEX0  -AH48       A01X+032087Y+115374X0180Y         S1      
317_d_ddd82fc0      VIA   -     D0080PA00X+031152Y+114813X0160Y         S0      
327_d_ddd82fc0      PEX0  -AJ46       A01X+031338Y+115000X0180Y         S1      
317_d_ddd82fe8      VIA   -     D0080PA00X+032274Y+114439X0160Y         S0      
327_d_ddd82fe8      PEX0  -AK48       A01X+032087Y+114626X0180Y         S1      
317_d_ddd83010      VIA   -     D0080PA00X+031152Y+114065X0160Y         S0      
327_d_ddd83010      PEX0  -AL46       A01X+031338Y+114252X0180Y         S1      
317_d_ddd83038      VIA   -     D0080PA00X+032274Y+113691X0160Y         S0      
327_d_ddd83038      PEX0  -AM48       A01X+032087Y+113878X0180Y         S1      
317_d_ddd830b0      VIA   -     D0080PA00X+030778Y+118927X0160Y         S0      
327_d_ddd830b0      PEX0  -W44        A01X+030590Y+118740X0180Y         S1      
317_d_ddd830d8      VIA   -     D0080PA00X+030778Y+118179X0160Y         S0      
327_d_ddd830d8      PEX0  -AA44       A01X+030590Y+117992X0180Y         S1      
317_d_ddd83100      VIA   -     D0080PA00X+030778Y+117431X0160Y         S0      
327_d_ddd83100      PEX0  -AC44       A01X+030590Y+117244X0180Y         S1      
317_d_ddd83128      VIA   -     D0080PA00X+029656Y+117057X0160Y         S0      
327_d_ddd83128      PEX0  -AD42       A01X+029842Y+116870X0180Y         S1      
317_d_ddd83150      VIA   -     D0080PA00X+029656Y+115561X0160Y         S0      
327_d_ddd83150      PEX0  -AH42       A01X+029842Y+115374X0180Y         S1      
317_d_ddd83178      VIA   -     D0080PA00X+030778Y+115187X0160Y         S0      
327_d_ddd83178      PEX0  -AJ44       A01X+030590Y+115000X0180Y         S1      
317_d_ddd831a0      VIA   -     D0080PA00X+030778Y+114439X0160Y         S0      
327_d_ddd831a0      PEX0  -AL44       A01X+030590Y+114252X0180Y         S1      
317_d_ddd83218      VIA   -     D0080PA00X+030404Y+118927X0160Y         S0      
327_d_ddd83218      PEX0  -W43        A01X+030216Y+118740X0180Y         S1      
317_d_ddd83240      VIA   -     D0080PA00X+030404Y+118179X0160Y         S0      
327_d_ddd83240      PEX0  -AA43       A01X+030216Y+117992X0180Y         S1      
317_d_ddd83268      VIA   -     D0080PA00X+030404Y+117431X0160Y         S0      
327_d_ddd83268      PEX0  -AC43       A01X+030216Y+117244X0180Y         S1      
317_d_ddd83290      VIA   -     D0080PA00X+029282Y+117057X0160Y         S0      
327_d_ddd83290      PEX0  -AD41       A01X+029468Y+116870X0180Y         S1      
317_d_ddd832b8      VIA   -     D0080PA00X+029282Y+115561X0160Y         S0      
327_d_ddd832b8      PEX0  -AH41       A01X+029468Y+115374X0180Y         S1      
317_d_ddd832e0      VIA   -     D0080PA00X+030404Y+115187X0160Y         S0      
327_d_ddd832e0      PEX0  -AJ43       A01X+030216Y+115000X0180Y         S1      
317_d_ddd83308      VIA   -     D0080PA00X+029282Y+114813X0160Y         S0      
327_d_ddd83308      PEX0  -AK41       A01X+029468Y+114626X0180Y         S1      
317_d_ddd83330      VIA   -     D0080PA00X+030404Y+114439X0160Y         S0      
327_d_ddd83330      PEX0  -AL43       A01X+030216Y+114252X0180Y         S1      
317_d_ddd83358      VIA   -     D0080PA00X+029282Y+114065X0160Y         S0      
327_d_ddd83358      PEX0  -AM41       A01X+029468Y+113878X0180Y         S1      
317_d_ddd83448      VIA   -     D0080PA00X+028533Y+119675X0160Y         S0      
327_d_ddd83448      PEX0  -U38        A01X+028346Y+119488X0180Y         S1      
317_d_ddd83470      VIA   -     D0080PA00X+014321Y+114813X0160Y         S0      
327_d_ddd83470      PEX0  -AJ1        A01X+014508Y+115000X0180Y         S1      
317_d_ddd83498      VIA   -     D0080PA00X+014695Y+114813X0160Y         S0      
327_d_ddd83498      PEX0  -AJ2        A01X+014882Y+115000X0180Y         S1      
317_d_ddd83808      VIA   -     D0080PA00X+028533Y+113691X0160Y         S0      
327_d_ddd83808      PEX0  -AM38       A01X+028346Y+113878X0180Y         S1      
317_d_ddd83830      VIA   -     D0080PA00X+028907Y+114813X0160Y         S0      
327_d_ddd83830      PEX0  -AJ39       A01X+028720Y+115000X0180Y         S1      
317_d_ddd83858      VIA   -     D0080PA00X+019557Y+111447X0160Y         S0      
327_d_ddd83858      PEX0  -AV15       A01X+019744Y+111634X0180Y         S1      
317_d_ddd83880      VIA   -     D0080PA00X+021053Y+111447X0160Y         S0      
327_d_ddd83880      PEX0  -AV19       A01X+021240Y+111634X0180Y         S1      
317_d_ddd838a8      VIA   -     D0080PA00X+020679Y+111447X0160Y         S0      
327_d_ddd838a8      PEX0  -AV18       A01X+020866Y+111634X0180Y         S1      
317_d_ddd838d0      VIA   -     D0080PA00X+019183Y+111447X0160Y         S0      
327_d_ddd838d0      PEX0  -AV14       A01X+019370Y+111634X0180Y         S1      
317_d_ddd838f8      VIA   -     D0080PA00X+019931Y+111447X0160Y         S0      
327_d_ddd838f8      PEX0  -AV16       A01X+020118Y+111634X0180Y         S1      
317_d_ddd83920      VIA   -     D0080PA00X+020305Y+111447X0160Y         S0      
327_d_ddd83920      PEX0  -AV17       A01X+020492Y+111634X0180Y         S1      
317_d_ddd83948      VIA   -     D0080PA00X+018435Y+111447X0160Y         S0      
327_d_ddd83948      PEX0  -AV12       A01X+018622Y+111634X0180Y         S1      
317_d_ddd83970      VIA   -     D0080PA00X+018809Y+111447X0160Y         S0      
327_d_ddd83970      PEX0  -AV13       A01X+018996Y+111634X0180Y         S1      
317_d_ddd83998      VIA   -     D0080PA00X+027785Y+111447X0160Y         S0      
327_d_ddd83998      PEX0  -AW36       A01X+027598Y+111260X0180Y         S1      
317_d_ddd839c0      VIA   -     D0080PA00X+027411Y+111447X0160Y         S0      
327_d_ddd839c0      PEX0  -AV35       A01X+027224Y+111634X0180Y         S1      
317_d_ddd839e8      VIA   -     D0080PA00X+028159Y+111447X0160Y         S0      
327_d_ddd839e8      PEX0  -AW37       A01X+027972Y+111260X0180Y         S1      
317_d_ddd83a10      VIA   -     D0080PA00X+028533Y+114065X0160Y         S0      
327_d_ddd83a10      PEX0  -AL38       A01X+028346Y+114252X0180Y         S1      
317_d_ddd83a38      VIA   -     D0080PA00X+025167Y+121545X0160Y         S0      
327_d_ddd83a38      PEX0  -M30        A01X+025354Y+121358X0180Y         S1      
317_d_ddd83a60      VIA   -     D0080PA00X+026663Y+121545X0160Y         S0      
327_d_ddd83a60      PEX0  -M34        A01X+026850Y+121358X0180Y         S1      
317_d_ddd83a88      VIA   -     D0080PA00X+025915Y+121545X0160Y         S0      
327_d_ddd83a88      PEX0  -M32        A01X+026102Y+121358X0180Y         S1      
317_d_ddd83ab0      VIA   -     D0080PA00X+021801Y+111447X0160Y         S0      
327_d_ddd83ab0      PEX0  -AV21       A01X+021988Y+111634X0180Y         S1      
317_d_ddd83ad8      VIA   -     D0080PA00X+022175Y+111447X0160Y         S0      
327_d_ddd83ad8      PEX0  -AV22       A01X+022362Y+111634X0180Y         S1      
317_d_ddd83b00      VIA   -     D0080PA00X+022549Y+111447X0160Y         S0      
327_d_ddd83b00      PEX0  -AV23       A01X+022736Y+111634X0180Y         S1      
317_d_ddd83b28      VIA   -     D0080PA00X+022175Y+121545X0160Y         S0      
327_d_ddd83b28      PEX0  -L22        A01X+022362Y+121732X0180Y         S1      
317_d_ddd83b50      VIA   -     D0080PA00X+022175Y+121171X0160Y         S0      
327_d_ddd83b50      PEX0  -M22        A01X+022362Y+121358X0180Y         S1      
317_d_ddd83b78      VIA   -     D0080PA00X+022549Y+121171X0160Y         S0      
327_d_ddd83b78      PEX0  -M23        A01X+022736Y+121358X0180Y         S1      
317_d_ddd83ba0      VIA   -     D0080PA00X+022923Y+121545X0160Y         S0      
327_d_ddd83ba0      PEX0  -L23        A01X+022736Y+121732X0180Y         S1      
317_d_ddd83bc8      VIA   -     D0080PA00X+022923Y+121171X0160Y         S0      
327_d_ddd83bc8      PEX0  -M24        A01X+023110Y+121358X0180Y         S1      
317_d_ddd83c40      VIA   -     D0080PA00X+027785Y+121545X0160Y         S0      
327_d_ddd83c40      PEX0  -M37        A01X+027972Y+121358X0180Y         S1      
317_d_ddd83c68      VIA   -     D0080PA00X+027411Y+121545X0160Y         S0      
327_d_ddd83c68      PEX0  -M36        A01X+027598Y+121358X0180Y         S1      
317_d_ddd83d08      VIA   -     D0080PA00X+016565Y+114439X0160Y         S0      
327_d_ddd83d08      PEX0  -AK7        A01X+016752Y+114626X0180Y         S1      
317_d_ddd83d30      VIA   -     D0080PA00X+016939Y+114813X0160Y         S0      
327_d_ddd83d30      PEX0  -AJ8        A01X+017126Y+115000X0180Y         S1      
317_d_ddd7e210      VIA   -     D0080PA00X+074242Y+119675X0160Y         S0      
327_d_ddd7e210      PEX1  -U38        A01X+074055Y+119488X0180Y         S1      
317_d_ddd7e238      VIA   -     D0080PA00X+060030Y+114813X0160Y         S0      
327_d_ddd7e238      PEX1  -AJ1        A01X+060216Y+115000X0180Y         S1      
317_d_ddd7e260      VIA   -     D0080PA00X+060404Y+114813X0160Y         S0      
327_d_ddd7e260      PEX1  -AJ2        A01X+060590Y+115000X0180Y         S1      
317_d_ddd7e5c8      VIA   -     D0080PA00X+074242Y+113691X0160Y         S0      
327_d_ddd7e5c8      PEX1  -AM38       A01X+074055Y+113878X0180Y         S1      
317_d_ddd7e5f0      VIA   -     D0080PA00X+074616Y+114813X0160Y         S0      
327_d_ddd7e5f0      PEX1  -AJ39       A01X+074429Y+115000X0180Y         S1      
317_d_ddd7e618      VIA   -     D0080PA00X+065266Y+111447X0160Y         S0      
327_d_ddd7e618      PEX1  -AV15       A01X+065453Y+111634X0180Y         S1      
317_d_ddd7e640      VIA   -     D0080PA00X+066762Y+111447X0160Y         S0      
327_d_ddd7e640      PEX1  -AV19       A01X+066949Y+111634X0180Y         S1      
317_d_ddd7e668      VIA   -     D0080PA00X+066388Y+111447X0160Y         S0      
327_d_ddd7e668      PEX1  -AV18       A01X+066575Y+111634X0180Y         S1      
317_d_ddd7e690      VIA   -     D0080PA00X+064892Y+111447X0160Y         S0      
327_d_ddd7e690      PEX1  -AV14       A01X+065079Y+111634X0180Y         S1      
317_d_ddd7e6b8      VIA   -     D0080PA00X+065640Y+111447X0160Y         S0      
327_d_ddd7e6b8      PEX1  -AV16       A01X+065827Y+111634X0180Y         S1      
317_d_ddd7e6e0      VIA   -     D0080PA00X+066014Y+111447X0160Y         S0      
327_d_ddd7e6e0      PEX1  -AV17       A01X+066201Y+111634X0180Y         S1      
317_d_ddd7e708      VIA   -     D0080PA00X+064144Y+111447X0160Y         S0      
327_d_ddd7e708      PEX1  -AV12       A01X+064331Y+111634X0180Y         S1      
317_d_ddd7e730      VIA   -     D0080PA00X+064518Y+111447X0160Y         S0      
327_d_ddd7e730      PEX1  -AV13       A01X+064705Y+111634X0180Y         S1      
317_d_ddd7e758      VIA   -     D0080PA00X+073494Y+111447X0160Y         S0      
327_d_ddd7e758      PEX1  -AW36       A01X+073307Y+111260X0180Y         S1      
317_d_ddd7e780      VIA   -     D0080PA00X+073120Y+111447X0160Y         S0      
327_d_ddd7e780      PEX1  -AV35       A01X+072933Y+111634X0180Y         S1      
317_d_ddd7e7a8      VIA   -     D0080PA00X+073868Y+111447X0160Y         S0      
327_d_ddd7e7a8      PEX1  -AW37       A01X+073681Y+111260X0180Y         S1      
317_d_ddd7e7d0      VIA   -     D0080PA00X+074242Y+114065X0160Y         S0      
327_d_ddd7e7d0      PEX1  -AL38       A01X+074055Y+114252X0180Y         S1      
317_d_ddd7e820      VIA   -     D0080PA00X+070876Y+121545X0160Y         S0      
327_d_ddd7e820      PEX1  -M30        A01X+071063Y+121358X0180Y         S1      
317_d_ddd7e848      VIA   -     D0080PA00X+072372Y+121545X0160Y         S0      
327_d_ddd7e848      PEX1  -M34        A01X+072559Y+121358X0180Y         S1      
317_d_ddd7e870      VIA   -     D0080PA00X+071624Y+121545X0160Y         S0      
327_d_ddd7e870      PEX1  -M32        A01X+071811Y+121358X0180Y         S1      
317_d_ddd7e898      VIA   -     D0080PA00X+067510Y+111447X0160Y         S0      
327_d_ddd7e898      PEX1  -AV21       A01X+067697Y+111634X0180Y         S1      
317_d_ddd7e8c0      VIA   -     D0080PA00X+067884Y+111447X0160Y         S0      
327_d_ddd7e8c0      PEX1  -AV22       A01X+068071Y+111634X0180Y         S1      
317_d_ddd7e8e8      VIA   -     D0080PA00X+068258Y+111447X0160Y         S0      
327_d_ddd7e8e8      PEX1  -AV23       A01X+068445Y+111634X0180Y         S1      
317_d_ddd7e910      VIA   -     D0080PA00X+067884Y+121545X0160Y         S0      
327_d_ddd7e910      PEX1  -L22        A01X+068071Y+121732X0180Y         S1      
317_d_ddd7e938      VIA   -     D0080PA00X+067884Y+121171X0160Y         S0      
327_d_ddd7e938      PEX1  -M22        A01X+068071Y+121358X0180Y         S1      
317_d_ddd7e960      VIA   -     D0080PA00X+068258Y+121171X0160Y         S0      
327_d_ddd7e960      PEX1  -M23        A01X+068445Y+121358X0180Y         S1      
317_d_ddd7e988      VIA   -     D0080PA00X+068632Y+121545X0160Y         S0      
327_d_ddd7e988      PEX1  -L23        A01X+068445Y+121732X0180Y         S1      
317_d_ddd7e9b0      VIA   -     D0080PA00X+068632Y+121171X0160Y         S0      
327_d_ddd7e9b0      PEX1  -M24        A01X+068819Y+121358X0180Y         S1      
317_d_ddd7ea28      VIA   -     D0080PA00X+073494Y+121545X0160Y         S0      
327_d_ddd7ea28      PEX1  -M37        A01X+073681Y+121358X0180Y         S1      
317_d_ddd7ea50      VIA   -     D0080PA00X+073120Y+121545X0160Y         S0      
327_d_ddd7ea50      PEX1  -M36        A01X+073307Y+121358X0180Y         S1      
317_d_ddd7eaf0      VIA   -     D0080PA00X+062274Y+114439X0160Y         S0      
327_d_ddd7eaf0      PEX1  -AK7        A01X+062461Y+114626X0180Y         S1      
317_d_ddd7eb18      VIA   -     D0080PA00X+062648Y+114813X0160Y         S0      
327_d_ddd7eb18      PEX1  -AJ8        A01X+062835Y+115000X0180Y         S1      
317_d_dda579f8      VIA   -     D0080PA00X+119951Y+119675X0160Y         S0      
327_d_dda579f8      PEX2  -U38        A01X+119764Y+119488X0180Y         S1      
317_d_dda57a20      VIA   -     D0080PA00X+105738Y+114813X0160Y         S0      
327_d_dda57a20      PEX2  -AJ1        A01X+105925Y+115000X0180Y         S1      
317_d_dda57a48      VIA   -     D0080PA00X+106112Y+114813X0160Y         S0      
327_d_dda57a48      PEX2  -AJ2        A01X+106299Y+115000X0180Y         S1      
317_d_dda57c00      VIA   -     D0080PA00X+119951Y+113691X0160Y         S0      
327_d_dda57c00      PEX2  -AM38       A01X+119764Y+113878X0180Y         S1      
317_d_dda57c28      VIA   -     D0080PA00X+120325Y+114813X0160Y         S0      
327_d_dda57c28      PEX2  -AJ39       A01X+120138Y+115000X0180Y         S1      
317_d_dda57c50      VIA   -     D0080PA00X+110974Y+111447X0160Y         S0      
327_d_dda57c50      PEX2  -AV15       A01X+111161Y+111634X0180Y         S1      
317_d_dda57c78      VIA   -     D0080PA00X+112470Y+111447X0160Y         S0      
327_d_dda57c78      PEX2  -AV19       A01X+112657Y+111634X0180Y         S1      
317_d_dda57ca0      VIA   -     D0080PA00X+112096Y+111447X0160Y         S0      
327_d_dda57ca0      PEX2  -AV18       A01X+112283Y+111634X0180Y         S1      
317_d_dda57cc8      VIA   -     D0080PA00X+110600Y+111447X0160Y         S0      
327_d_dda57cc8      PEX2  -AV14       A01X+110787Y+111634X0180Y         S1      
317_d_dda57cf0      VIA   -     D0080PA00X+111348Y+111447X0160Y         S0      
327_d_dda57cf0      PEX2  -AV16       A01X+111535Y+111634X0180Y         S1      
317_d_dda57d18      VIA   -     D0080PA00X+111722Y+111447X0160Y         S0      
327_d_dda57d18      PEX2  -AV17       A01X+111909Y+111634X0180Y         S1      
317_d_dda57d40      VIA   -     D0080PA00X+109852Y+111447X0160Y         S0      
327_d_dda57d40      PEX2  -AV12       A01X+110039Y+111634X0180Y         S1      
317_d_dda57d68      VIA   -     D0080PA00X+110226Y+111447X0160Y         S0      
327_d_dda57d68      PEX2  -AV13       A01X+110413Y+111634X0180Y         S1      
317_d_dda57d90      VIA   -     D0080PA00X+119203Y+111447X0160Y         S0      
327_d_dda57d90      PEX2  -AW36       A01X+119016Y+111260X0180Y         S1      
317_d_dda57db8      VIA   -     D0080PA00X+118829Y+111447X0160Y         S0      
327_d_dda57db8      PEX2  -AV35       A01X+118642Y+111634X0180Y         S1      
317_d_dda57de0      VIA   -     D0080PA00X+119577Y+111447X0160Y         S0      
327_d_dda57de0      PEX2  -AW37       A01X+119390Y+111260X0180Y         S1      
317_d_dda57e08      VIA   -     D0080PA00X+119951Y+114065X0160Y         S0      
327_d_dda57e08      PEX2  -AL38       A01X+119764Y+114252X0180Y         S1      
317_d_dda57e58      VIA   -     D0080PA00X+116585Y+121545X0160Y         S0      
327_d_dda57e58      PEX2  -M30        A01X+116772Y+121358X0180Y         S1      
317_d_dda57e80      VIA   -     D0080PA00X+118081Y+121545X0160Y         S0      
327_d_dda57e80      PEX2  -M34        A01X+118268Y+121358X0180Y         S1      
317_d_dda57ea8      VIA   -     D0080PA00X+117333Y+121545X0160Y         S0      
327_d_dda57ea8      PEX2  -M32        A01X+117520Y+121358X0180Y         S1      
317_d_dda57ed0      VIA   -     D0080PA00X+113218Y+111447X0160Y         S0      
327_d_dda57ed0      PEX2  -AV21       A01X+113405Y+111634X0180Y         S1      
317_d_dda57ef8      VIA   -     D0080PA00X+113592Y+111447X0160Y         S0      
327_d_dda57ef8      PEX2  -AV22       A01X+113780Y+111634X0180Y         S1      
317_d_dda57f20      VIA   -     D0080PA00X+113966Y+111447X0160Y         S0      
327_d_dda57f20      PEX2  -AV23       A01X+114154Y+111634X0180Y         S1      
317_d_dda57f48      VIA   -     D0080PA00X+113592Y+121545X0160Y         S0      
327_d_dda57f48      PEX2  -L22        A01X+113780Y+121732X0180Y         S1      
317_d_dda57f70      VIA   -     D0080PA00X+113592Y+121171X0160Y         S0      
327_d_dda57f70      PEX2  -M22        A01X+113780Y+121358X0180Y         S1      
317_d_dda57f98      VIA   -     D0080PA00X+113966Y+121171X0160Y         S0      
327_d_dda57f98      PEX2  -M23        A01X+114154Y+121358X0180Y         S1      
317_d_dda57fc0      VIA   -     D0080PA00X+114340Y+121545X0160Y         S0      
327_d_dda57fc0      PEX2  -L23        A01X+114154Y+121732X0180Y         S1      
317_d_dda57fe8      VIA   -     D0080PA00X+114340Y+121171X0160Y         S0      
327_d_dda57fe8      PEX2  -M24        A01X+114528Y+121358X0180Y         S1      
317_d_dda58010      VIA   -     D0080PA00X+119203Y+121545X0160Y         S0      
327_d_dda58010      PEX2  -M37        A01X+119390Y+121358X0180Y         S1      
317_d_dda58038      VIA   -     D0080PA00X+118829Y+121545X0160Y         S0      
327_d_dda58038      PEX2  -M36        A01X+119016Y+121358X0180Y         S1      
317_d_dda580b0      VIA   -     D0080PA00X+107982Y+114439X0160Y         S0      
327_d_dda580b0      PEX2  -AK7        A01X+108169Y+114626X0180Y         S1      
317_d_dda580d8      VIA   -     D0080PA00X+108356Y+114813X0160Y         S0      
327_d_dda580d8      PEX2  -AJ8        A01X+108543Y+115000X0180Y         S1      
317_d_dfc0c928      VIA   -     D0080PA00X+151447Y+115561X0160Y         S0      
327_d_dfc0c928      PEX3  -AG1        A01X+151634Y+115748X0180Y         S1      
317_d_dfc0c950      VIA   -     D0080PA00X+151821Y+115561X0160Y         S0      
327_d_dfc0c950      PEX3  -AG2        A01X+152008Y+115748X0180Y         S1      
317_d_dfc0c978      VIA   -     D0080PA00X+165659Y+119675X0160Y         S0      
327_d_dfc0c978      PEX3  -U38        A01X+165472Y+119488X0180Y         S1      
317_d_dfc0c9a0      VIA   -     D0080PA00X+151447Y+114813X0160Y         S0      
327_d_dfc0c9a0      PEX3  -AJ1        A01X+151634Y+115000X0180Y         S1      
317_d_dfc0c9c8      VIA   -     D0080PA00X+151821Y+114813X0160Y         S0      
327_d_dfc0c9c8      PEX3  -AJ2        A01X+152008Y+115000X0180Y         S1      
317_d_dfc0cc90      VIA   -     D0080PA00X+165659Y+113691X0160Y         S0      
327_d_dfc0cc90      PEX3  -AM38       A01X+165472Y+113878X0180Y         S1      
317_d_dfc0ccb8      VIA   -     D0080PA00X+166033Y+114813X0160Y         S0      
327_d_dfc0ccb8      PEX3  -AJ39       A01X+165846Y+115000X0180Y         S1      
317_d_dfc0cce0      VIA   -     D0080PA00X+156683Y+111447X0160Y         S0      
327_d_dfc0cce0      PEX3  -AV15       A01X+156870Y+111634X0180Y         S1      
317_d_dfc0cd08      VIA   -     D0080PA00X+158179Y+111447X0160Y         S0      
327_d_dfc0cd08      PEX3  -AV19       A01X+158366Y+111634X0180Y         S1      
317_d_dfc0cd30      VIA   -     D0080PA00X+157805Y+111447X0160Y         S0      
327_d_dfc0cd30      PEX3  -AV18       A01X+157992Y+111634X0180Y         S1      
317_d_dfc0cd58      VIA   -     D0080PA00X+156309Y+111447X0160Y         S0      
327_d_dfc0cd58      PEX3  -AV14       A01X+156496Y+111634X0180Y         S1      
317_d_dfc0cd80      VIA   -     D0080PA00X+157057Y+111447X0160Y         S0      
327_d_dfc0cd80      PEX3  -AV16       A01X+157244Y+111634X0180Y         S1      
317_d_dfc0cda8      VIA   -     D0080PA00X+157431Y+111447X0160Y         S0      
327_d_dfc0cda8      PEX3  -AV17       A01X+157618Y+111634X0180Y         S1      
317_d_dfc0cdd0      VIA   -     D0080PA00X+155561Y+111447X0160Y         S0      
327_d_dfc0cdd0      PEX3  -AV12       A01X+155748Y+111634X0180Y         S1      
317_d_dfc0cdf8      VIA   -     D0080PA00X+155935Y+111447X0160Y         S0      
327_d_dfc0cdf8      PEX3  -AV13       A01X+156122Y+111634X0180Y         S1      
317_d_dfc0ce20      VIA   -     D0080PA00X+163789Y+111447X0160Y    R090 S0      
327_d_dfc0ce20      PEX3  -AW33       A01X+163602Y+111260X0180Y         S1      
317_d_dfc0ce48      VIA   -     D0080PA00X+163789Y+111821X0160Y    R090 S0      
327_d_dfc0ce48      PEX3  -AV33       A01X+163602Y+111634X0180Y         S1      
317_d_dfc0ce70      VIA   -     D0080PA00X+164911Y+111447X0160Y         S0      
327_d_dfc0ce70      PEX3  -AW36       A01X+164724Y+111260X0180Y         S1      
317_d_dfc0ce98      VIA   -     D0080PA00X+164537Y+111447X0160Y         S0      
327_d_dfc0ce98      PEX3  -AV35       A01X+164350Y+111634X0180Y         S1      
317_d_dfc0cec0      VIA   -     D0080PA00X+165285Y+111447X0160Y         S0      
327_d_dfc0cec0      PEX3  -AW37       A01X+165098Y+111260X0180Y         S1      
317_d_dfc0cee8      VIA   -     D0080PA00X+165659Y+114065X0160Y         S0      
327_d_dfc0cee8      PEX3  -AL38       A01X+165472Y+114252X0180Y         S1      
317_d_dfc0cf10      VIA   -     D0080PA00X+165659Y+113317X0160Y         S0      
327_d_dfc0cf10      PEX3  -AN38       A01X+165472Y+113504X0180Y         S1      
317_d_dfc0cf60      VIA   -     D0080PA00X+162293Y+121545X0160Y         S0      
327_d_dfc0cf60      PEX3  -M30        A01X+162480Y+121358X0180Y         S1      
317_d_dfc0cf88      VIA   -     D0080PA00X+163789Y+121545X0160Y         S0      
327_d_dfc0cf88      PEX3  -M34        A01X+163976Y+121358X0180Y         S1      
317_d_dfc0cfb0      VIA   -     D0080PA00X+163041Y+121545X0160Y         S0      
327_d_dfc0cfb0      PEX3  -M32        A01X+163228Y+121358X0180Y         S1      
317_d_dfc0cfd8      VIA   -     D0080PA00X+158927Y+111447X0160Y         S0      
327_d_dfc0cfd8      PEX3  -AV21       A01X+159114Y+111634X0180Y         S1      
317_d_dfc0d000      VIA   -     D0080PA00X+159301Y+111447X0160Y         S0      
327_d_dfc0d000      PEX3  -AV22       A01X+159488Y+111634X0180Y         S1      
317_d_dfc0d028      VIA   -     D0080PA00X+159675Y+111447X0160Y         S0      
327_d_dfc0d028      PEX3  -AV23       A01X+159862Y+111634X0180Y         S1      
317_d_dfc0d050      VIA   -     D0080PA00X+159301Y+121545X0160Y         S0      
327_d_dfc0d050      PEX3  -L22        A01X+159488Y+121732X0180Y         S1      
317_d_dfc0d078      VIA   -     D0080PA00X+159301Y+121171X0160Y         S0      
327_d_dfc0d078      PEX3  -M22        A01X+159488Y+121358X0180Y         S1      
317_d_dfc0d0a0      VIA   -     D0080PA00X+159675Y+121171X0160Y         S0      
327_d_dfc0d0a0      PEX3  -M23        A01X+159862Y+121358X0180Y         S1      
317_d_dfc0d0c8      VIA   -     D0080PA00X+160049Y+121545X0160Y         S0      
327_d_dfc0d0c8      PEX3  -L23        A01X+159862Y+121732X0180Y         S1      
317_d_dfc0d0f0      VIA   -     D0080PA00X+160049Y+121171X0160Y         S0      
327_d_dfc0d0f0      PEX3  -M24        A01X+160236Y+121358X0180Y         S1      
317_d_dfc0d118      VIA   -     D0080PA00X+164911Y+121545X0160Y         S0      
327_d_dfc0d118      PEX3  -M37        A01X+165098Y+121358X0180Y         S1      
317_d_dfc0d140      VIA   -     D0080PA00X+164537Y+121545X0160Y         S0      
327_d_dfc0d140      PEX3  -M36        A01X+164724Y+121358X0180Y         S1      
317_d_dfc0d1b8      VIA   -     D0080PA00X+153691Y+114439X0160Y         S0      
327_d_dfc0d1b8      PEX3  -AK7        A01X+153878Y+114626X0180Y         S1      
317_d_dfc0d1e0      VIA   -     D0080PA00X+154065Y+114813X0160Y         S0      
327_d_dfc0d1e0      PEX3  -AJ8        A01X+154252Y+115000X0180Y         S1      
317_d_dfc0d2d0      VIA   -     D0080PA00X+154065Y+117805X0160Y    R180 S0      
327_d_dfc0d2d0      PEX3  -AB7        A01X+153878Y+117618X0180Y         S1      
317_d_dfc0d2f8      VIA   -     D0080PA00X+154065Y+117057X0160Y    R180 S0      
327_d_dfc0d2f8      PEX3  -AD7        A01X+153878Y+116870X0180Y         S1      
317_d_dfc0d320      VIA   -     D0080PA00X+154065Y+117431X0160Y    R180 S0      
327_d_dfc0d320      PEX3  -AC7        A01X+153878Y+117244X0180Y         S1      
317N/C              J5    -A9   D0122PA00X+069886Y+162240X0282Y    R180 S3      
327N/C              PEX3  -AD4        A01X+152756Y+116870X0180Y         S1      
327N/C              PEX2  -AD4        A01X+107047Y+116870X0180Y         S1      
327N/C              PEX2  -AD5        A01X+107421Y+116870X0180Y         S1      
327N/C              PEX0  -AD5        A01X+016004Y+116870X0180Y         S1      
327N/C              PEX1  -AD5        A01X+061713Y+116870X0180Y         S1      
327N/C              PEX1  -AD4        A01X+061339Y+116870X0180Y         S1      
327N/C              PEX0  -AD4        A01X+015630Y+116870X0180Y         S1      
327N/C              PEX3  -AD5        A01X+153130Y+116870X0180Y         S1      
327N/C              U328  -3          A01X+007869Y+159786X0240Y0520     S1      
327N/C              U329  -3          A01X+176882Y+160436X0240Y0520     S1      
327N/C              U417  -3          A01X+146268Y+002264X0240Y0520R270 S1      
327N/C              U416  -3          A01X+029496Y+001941X0240Y0520R270 S1      
327N/C              J19   -1          A01X+100119Y+071538X0500Y1350R090 S1      
317N/C              J19_12-1          A01X+187650Y+207068X0180Y         S2      
017N/C              J19_12-1          A18X+187650Y+207068X0200Y         S2      
017N/C                    -     D0080PA00X+187650Y+207068                       
327N/C              PEX0  -AA35       A01X+027224Y+117992X0180Y         S1      
327N/C              PEX0  -AR36       A01X+027598Y+112756X0180Y         S1      
327N/C              PEX0  -AP36       A01X+027598Y+113130X0180Y         S1      
327N/C              PEX0  -U14        A01X+019370Y+119488X0180Y         S1      
327N/C              PEX0  -T14        A01X+019370Y+119862X0180Y         S1      
327N/C              PEX0  -AK5        A01X+016004Y+114626X0180Y         S1      
327N/C              PEX0  -AT36       A01X+027598Y+112382X0180Y         S1      
327N/C              PEX0  -AN36       A01X+027598Y+113504X0180Y         S1      
327N/C              PEX0  -AK4        A01X+015630Y+114626X0180Y         S1      
327N/C              PEX1  -AP36       A01X+073307Y+113130X0180Y         S1      
327N/C              PEX1  -U14        A01X+065079Y+119488X0180Y         S1      
327N/C              PEX1  -AR36       A01X+073307Y+112756X0180Y         S1      
327N/C              PEX1  -AK4        A01X+061339Y+114626X0180Y         S1      
327N/C              PEX1  -AK5        A01X+061713Y+114626X0180Y         S1      
327N/C              PEX1  -AT36       A01X+073307Y+112382X0180Y         S1      
327N/C              PEX1  -T14        A01X+065079Y+119862X0180Y         S1      
327N/C              PEX1  -AA35       A01X+072933Y+117992X0180Y         S1      
327N/C              PEX1  -AN36       A01X+073307Y+113504X0180Y         S1      
327N/C              PEX2  -AK5        A01X+107421Y+114626X0180Y         S1      
327N/C              PEX2  -AK4        A01X+107047Y+114626X0180Y         S1      
327N/C              PEX2  -AR36       A01X+119016Y+112756X0180Y         S1      
327N/C              PEX2  -AT36       A01X+119016Y+112382X0180Y         S1      
327N/C              PEX2  -AA35       A01X+118642Y+117992X0180Y         S1      
327N/C              PEX2  -AN36       A01X+119016Y+113504X0180Y         S1      
327N/C              PEX2  -T14        A01X+110787Y+119862X0180Y         S1      
327N/C              PEX2  -AP36       A01X+119016Y+113130X0180Y         S1      
327N/C              PEX2  -U14        A01X+110787Y+119488X0180Y         S1      
327N/C              PEX3  -U14        A01X+156496Y+119488X0180Y         S1      
327N/C              PEX3  -AR36       A01X+164724Y+112756X0180Y         S1      
327N/C              PEX3  -AK5        A01X+153130Y+114626X0180Y         S1      
327N/C              PEX3  -AP36       A01X+164724Y+113130X0180Y         S1      
327N/C              PEX3  -AA35       A01X+164350Y+117992X0180Y         S1      
327N/C              PEX3  -AK4        A01X+152756Y+114626X0180Y         S1      
327N/C              PEX3  -AN36       A01X+164724Y+113504X0180Y         S1      
327N/C              PEX3  -AT36       A01X+164724Y+112382X0180Y         S1      
327N/C              PEX3  -T14        A01X+156496Y+119862X0180Y         S1      
317N/C              H78   -1    D1340UA00X+107047Y+149094X1340Y         S3      
317N/C              H79   -1    D1340UA00X+082008Y+038858X1340Y         S3      
317N/C              H80   -1    D1340UA00X+077047Y+149094X1340Y         S3      
317N/C              H84   -1    D1780UA00X+081004Y+126339X1780Y         S3      
317N/C              H85   -1    D1780UA00X+103090Y+126339X1780Y         S3      
317N/C              H86   -1    D1780UA00X+126712Y+106654X1780Y         S3      
317N/C              H87   -1    D1780UA00X+103090Y+106654X1780Y         S3      
317N/C              H88   -1    D1780UA00X+035295Y+126339X1780Y         S3      
317N/C              H89   -1    D1780UA00X+057382Y+106654X1780Y         S3      
317N/C              H90   -1    D1780UA00X+126712Y+126339X1780Y         S3      
317N/C              H91   -1    D1780UA00X+011673Y+126339X1780Y         S3      
317N/C              H92   -1    D1780UA00X+057382Y+126339X1780Y         S3      
317N/C              H93   -1    D1780UA00X+172421Y+126339X1780Y         S3      
317N/C              H94   -1    D1780UA00X+011673Y+106654X1780Y         S3      
317N/C              H95   -1    D1780UA00X+148799Y+126339X1780Y         S3      
317N/C              H96   -1    D1780UA00X+035295Y+106654X1780Y         S3      
317N/C              H97   -1    D1780UA00X+148799Y+106654X1780Y         S3      
317N/C              H98   -1    D1780UA00X+081004Y+106654X1780Y         S3      
317N/C              H99   -1    D1780UA00X+172421Y+106654X1780Y         S3      
317N/C              J59_12-1          A01X+185903Y+205258X0180Y    R180 S2      
017N/C              J59_12-1          A18X+185903Y+205258X0200Y    R180 S2      
017N/C                    -     D0080PA00X+185903Y+205258                       
317N/C              J60_12-1          A01X+185203Y+205258X0180Y    R180 S2      
017N/C              J60_12-1          A18X+185203Y+205258X0200Y    R180 S2      
017N/C                    -     D0080PA00X+185203Y+205258                       
327N/C              U145  -3          A01X+132056Y+094806X0140Y0440     S1      
327N/C              U145  -4          A01X+132056Y+095594X0140Y0440     S1      
327N/C              J58   -1          A01X+076585Y+142762X0500Y1350R090 S1      
317N/C              J58_12-1          A01X+188613Y+207592X0180Y         S2      
017N/C              J58_12-1          A18X+188613Y+207592X0200Y         S2      
017N/C                    -     D0080PA00X+188613Y+207592                       
317N/C              J11   -W10  D0122PA00X+036106Y+146807X0282Y    R180 S3      
317N/C              J11   -T10  D0122PA00X+036106Y+148343X0282Y    R180 S3      
317N/C              J11   -U9   D0122PA00X+035240Y+147910X0282Y    R180 S3      
317N/C              J11   -U10  D0122PA00X+036106Y+147831X0282Y    R180 S3      
317N/C              J11   -X10  D0122PA00X+036106Y+146295X0282Y    R180 S3      
317N/C              J11   -Y9   D0122PA00X+035240Y+145862X0282Y    R180 S3      
317N/C              J11   -V9   D0122PA00X+035240Y+147398X0282Y    R180 S3      
317N/C              J11   -X9   D0122PA00X+035240Y+146374X0282Y    R180 S3      
327N/C              J55   -1          A01X+140403Y+097447X0500Y1350R090 S1      
327N/C              J57   -3          A01X+144167Y+096608X0500Y1350R090 S1      
327N/C              U344  -11         A01X+144198Y+073048X0160Y0540R270 S1      
327N/C              U344  -16         A01X+146502Y+073560X0160Y0540R270 S1      
327N/C              U344  -7          A01X+144198Y+074072X0160Y0540R270 S1      
327N/C              U345  -7          A01X+145898Y+078222X0160Y0540R270 S1      
327N/C              U345  -11         A01X+145898Y+077198X0160Y0540R270 S1      
327N/C              U345  -16         A01X+148202Y+077710X0160Y0540R270 S1      
327N/C              U346  -11         A01X+144198Y+068648X0160Y0540R270 S1      
327N/C              U346  -7          A01X+144198Y+069672X0160Y0540R270 S1      
327N/C              U346  -16         A01X+146502Y+069160X0160Y0540R270 S1      
327N/C              U347  -7          A01X+135098Y+071222X0160Y0540R270 S1      
327N/C              U347  -11         A01X+135098Y+070198X0160Y0540R270 S1      
327N/C              U347  -16         A01X+137402Y+070710X0160Y0540R270 S1      
327N/C              U348  -7          A01X+135098Y+066522X0160Y0540R270 S1      
327N/C              U348  -11         A01X+135098Y+065498X0160Y0540R270 S1      
327N/C              U348  -16         A01X+137402Y+066010X0160Y0540R270 S1      
327N/C              U349  -16         A01X+137402Y+061560X0160Y0540R270 S1      
327N/C              U349  -11         A01X+135098Y+061048X0160Y0540R270 S1      
327N/C              U349  -7          A01X+135098Y+062072X0160Y0540R270 S1      
327N/C              U343  -7          A01X+145898Y+082622X0160Y0540R270 S1      
327N/C              U343  -11         A01X+145898Y+081598X0160Y0540R270 S1      
327N/C              U343  -16         A01X+148202Y+082110X0160Y0540R270 S1      
327N/C              U350  -11         A01X+135098Y+056398X0160Y0540R270 S1      
327N/C              U350  -16         A01X+137402Y+056910X0160Y0540R270 S1      
327N/C              U350  -7          A01X+135098Y+057422X0160Y0540R270 S1      
327N/C              PEX3  -AU7        A01X+153878Y+112008X0180Y         S1      
327N/C              PEX1  -Y41        A01X+075177Y+118366X0180Y         S1      
327N/C              PEX1  -AG43       A01X+075925Y+115748X0180Y         S1      
327N/C              PEX1  -V41        A01X+075177Y+119114X0180Y         S1      
327N/C              PEX1  -W44        A01X+076299Y+118740X0180Y         S1      
327N/C              PEX3  -AT8        A01X+154252Y+112382X0180Y         S1      
327N/C              PEX1  -AF42       A01X+075551Y+116122X0180Y         S1      
327N/C              PEX2  -AP8        A01X+108543Y+113130X0180Y         S1      
327N/C              PEX1  -AF41       A01X+075177Y+116122X0180Y         S1      
327N/C              PEX2  -AR6        A01X+107795Y+112756X0180Y         S1      
327N/C              PEX1  -AN4        A01X+061339Y+113504X0180Y         S1      
327N/C              PEX1  -AB42       A01X+075551Y+117618X0180Y         S1      
327N/C              PEX1  -AE43       A01X+075925Y+116496X0180Y         S1      
327N/C              PEX2  -AN7        A01X+108169Y+113504X0180Y         S1      
327N/C              PEX3  -AR7        A01X+153878Y+112756X0180Y         S1      
327N/C              PEX1  -AB41       A01X+075177Y+117618X0180Y         S1      
327N/C              PEX1  -V42        A01X+075551Y+119114X0180Y         S1      
327N/C              PEX3  -AU6        A01X+153504Y+112008X0180Y         S1      
327N/C              PEX1  -W43        A01X+075925Y+118740X0180Y         S1      
327N/C              PEX1  -Y42        A01X+075551Y+118366X0180Y         S1      
327N/C              PEX3  -BB8        A01X+154252Y+110138X0180Y         S1      
327N/C              PEX2  -AT9        A01X+108917Y+112382X0180Y         S1      
327N/C              PEX1  -AE44       A01X+076299Y+116496X0180Y         S1      
327N/C              PEX3  -AE46       A01X+168464Y+116496X0180Y         S1      
327N/C              PEX2  -AP9        A01X+108917Y+113130X0180Y         S1      
327N/C              PEX1  -AK42       A01X+075551Y+114626X0180Y         S1      
327N/C              PEX1  -U44        A01X+076299Y+119488X0180Y         S1      
327N/C              PEX1  -AM42       A01X+075551Y+113878X0180Y         S1      
327N/C              PEX2  -AM8        A01X+108543Y+113878X0180Y         S1      
327N/C              PEX1  -AG44       A01X+076299Y+115748X0180Y         S1      
327N/C              PEX1  -U43        A01X+075925Y+119488X0180Y         S1      
327N/C              PEX3  -AM9        A01X+154626Y+113878X0180Y         S1      
327N/C              PEX2  -AU7        A01X+108169Y+112008X0180Y         S1      
327N/C              PEX2  -AM9        A01X+108917Y+113878X0180Y         S1      
327N/C              PEX2  -AN6        A01X+107795Y+113504X0180Y         S1      
327N/C              PEX3  -AE47       A01X+168838Y+116496X0180Y         S1      
327N/C              PEX3  -AN4        A01X+152756Y+113504X0180Y         S1      
327N/C              PEX3  -BG1        A01X+151634Y+108268X0180Y         S1      
327N/C              PEX3  -AP8        A01X+154252Y+113130X0180Y         S1      
327N/C              PEX3  -AT9        A01X+154626Y+112382X0180Y         S1      
327N/C              PEX3  -AM8        A01X+154252Y+113878X0180Y         S1      
327N/C              PEX3  -AP9        A01X+154626Y+113130X0180Y         S1      
327N/C              PEX3  -AD49       A01X+169587Y+116870X0180Y         S1      
327N/C              PEX3  -BH3        A01X+152382Y+107894X0180Y         S1      
327N/C              PEX3  -AR6        A01X+153504Y+112756X0180Y         S1      
327N/C              PEX3  -AD48       A01X+169213Y+116870X0180Y         S1      
327N/C              PEX3  -BG2        A01X+152008Y+108268X0180Y         S1      
327N/C              PEX3  -AM42       A01X+166968Y+113878X0180Y         S1      
327N/C              PEX3  -AF42       A01X+166968Y+116122X0180Y         S1      
327N/C              PEX3  -AK42       A01X+166968Y+114626X0180Y         S1      
327N/C              PEX3  -U44        A01X+167716Y+119488X0180Y         S1      
327N/C              PEX3  -Y41        A01X+166594Y+118366X0180Y         S1      
327N/C              PEX3  -AE44       A01X+167716Y+116496X0180Y         S1      
327N/C              PEX3  -AF41       A01X+166594Y+116122X0180Y         S1      
327N/C              PEX3  -V41        A01X+166594Y+119114X0180Y         S1      
327N/C              PEX3  -AG43       A01X+167342Y+115748X0180Y         S1      
327N/C              PEX2  -AE46       A01X+122756Y+116496X0180Y         S1      
327N/C              PEX3  -AE43       A01X+167342Y+116496X0180Y         S1      
327N/C              PEX2  -BG1        A01X+105925Y+108268X0180Y         S1      
327N/C              PEX3  -U43        A01X+167342Y+119488X0180Y         S1      
327N/C              PEX3  -AB42       A01X+166968Y+117618X0180Y         S1      
327N/C              PEX3  -AG44       A01X+167716Y+115748X0180Y         S1      
327N/C              PEX1  -AM49       A01X+078169Y+113878X0180Y         S1      
327N/C              PEX3  -Y42        A01X+166968Y+118366X0180Y         S1      
327N/C              PEX3  -AB41       A01X+166594Y+117618X0180Y         S1      
327N/C              PEX3  -V42        A01X+166968Y+119114X0180Y         S1      
327N/C              PEX2  -BG2        A01X+106299Y+108268X0180Y         S1      
327N/C              PEX1  -AD48       A01X+077795Y+116870X0180Y         S1      
327N/C              PEX1  -AM48       A01X+077795Y+113878X0180Y         S1      
327N/C              PEX2  -BH3        A01X+106673Y+107894X0180Y         S1      
327N/C              PEX1  -AE47       A01X+077421Y+116496X0180Y         S1      
327N/C              PEX1  -AE46       A01X+077047Y+116496X0180Y         S1      
327N/C              PEX2  -AE47       A01X+123130Y+116496X0180Y         S1      
327N/C              PEX2  -AN4        A01X+107047Y+113504X0180Y         S1      
327N/C              PEX1  -AD49       A01X+078169Y+116870X0180Y         S1      
327N/C              PEX2  -AD49       A01X+123878Y+116870X0180Y         S1      
327N/C              PEX1  -AP8        A01X+062835Y+113130X0180Y         S1      
327N/C              PEX1  -AM9        A01X+063209Y+113878X0180Y         S1      
327N/C              PEX1  -AU7        A01X+062461Y+112008X0180Y         S1      
327N/C              PEX1  -AR6        A01X+062087Y+112756X0180Y         S1      
327N/C              PEX2  -AD48       A01X+123504Y+116870X0180Y         S1      
327N/C              PEX1  -AN7        A01X+062461Y+113504X0180Y         S1      
327N/C              PEX1  -AN6        A01X+062087Y+113504X0180Y         S1      
327N/C              PEX1  -AT9        A01X+063209Y+112382X0180Y         S1      
327N/C              PEX1  -AM8        A01X+062835Y+113878X0180Y         S1      
327N/C              PEX1  -AT8        A01X+062835Y+112382X0180Y         S1      
327N/C              PEX2  -V42        A01X+121260Y+119114X0180Y         S1      
327N/C              PEX1  -BB8        A01X+062835Y+110138X0180Y         S1      
327N/C              PEX2  -V41        A01X+120886Y+119114X0180Y         S1      
327N/C              PEX2  -Y41        A01X+120886Y+118366X0180Y         S1      
327N/C              PEX2  -AF42       A01X+121260Y+116122X0180Y         S1      
327N/C              PEX1  -AP9        A01X+063209Y+113130X0180Y         S1      
327N/C              PEX2  -AB41       A01X+120886Y+117618X0180Y         S1      
327N/C              PEX1  -AR7        A01X+062461Y+112756X0180Y         S1      
327N/C              PEX2  -AF41       A01X+120886Y+116122X0180Y         S1      
327N/C              PEX2  -AK42       A01X+121260Y+114626X0180Y         S1      
327N/C              PEX1  -AU6        A01X+062087Y+112008X0180Y         S1      
327N/C              PEX2  -Y42        A01X+121260Y+118366X0180Y         S1      
327N/C              PEX2  -U44        A01X+122008Y+119488X0180Y         S1      
327N/C              PEX2  -AE43       A01X+121634Y+116496X0180Y         S1      
327N/C              PEX2  -AM42       A01X+121260Y+113878X0180Y         S1      
327N/C              PEX2  -AB42       A01X+121260Y+117618X0180Y         S1      
327N/C              PEX2  -U43        A01X+121634Y+119488X0180Y         S1      
327N/C              PEX2  -AG44       A01X+122008Y+115748X0180Y         S1      
327N/C              PEX2  -AE44       A01X+122008Y+116496X0180Y         S1      
327N/C              PEX2  -AG43       A01X+121634Y+115748X0180Y         S1      
327N/C              PEX2  -AR7        A01X+108169Y+112756X0180Y         S1      
327N/C              PEX1  -BG2        A01X+060590Y+108268X0180Y         S1      
327N/C              PEX2  -AT8        A01X+108543Y+112382X0180Y         S1      
327N/C              PEX2  -AU6        A01X+107795Y+112008X0180Y         S1      
327N/C              PEX2  -BB8        A01X+108543Y+110138X0180Y         S1      
327N/C              PEX1  -BG1        A01X+060216Y+108268X0180Y         S1      
327N/C              PEX1  -BH3        A01X+060965Y+107894X0180Y         S1      
327N/C              PEX3  -AN6        A01X+153504Y+113504X0180Y         S1      
327N/C              PEX3  -AN7        A01X+153878Y+113504X0180Y         S1      
327N/C              J4    -1          A01X+092730Y+051643X0500Y1350R090 S1      
317N/C              J20   -H2   D0440UA00X+019032Y+037486X0440Y         S3      
317N/C              J20   -H1   D0440UA00X+018344Y+063065X0440Y         S3      
327N/C              J20   -A14        A01X+019938Y+054474X0140Y0480R270 S1      
327N/C              J20   -OB11       A01X+018127Y+059984X0140Y0480R270 S1      
327N/C              J20   -OA11       A01X+019938Y+059984X0140Y0480R270 S1      
327N/C              J20   -A15        A01X+019938Y+054238X0140Y0480R270 S1      
327N/C              J20   -OB12       A01X+018127Y+059748X0140Y0480R270 S1      
327N/C              J20   -OA12       A01X+019938Y+059748X0140Y0480R270 S1      
327N/C              J20   -B68        A01X+018127Y+038679X0140Y0480R270 S1      
327N/C              J20   -B69        A01X+018127Y+038443X0140Y0480R270 S1      
327N/C              J20   -A68        A01X+019938Y+038679X0140Y0480R270 S1      
327N/C              J20   -A69        A01X+019938Y+038443X0140Y0480R270 S1      
327N/C              J20   -OA3        A01X+019938Y+061874X0140Y0480R270 S1      
317N/C              J21   -H2   D0440UA00X+027936Y+063065X0440Y    R180 S3      
317N/C              J21   -H1   D0440UA00X+028625Y+037486X0440Y    R180 S3      
327N/C              J21   -A14        A01X+027030Y+046077X0140Y0480R090 S1      
327N/C              J21   -OB11       A01X+028842Y+040567X0140Y0480R090 S1      
327N/C              J21   -OA11       A01X+027030Y+040567X0140Y0480R090 S1      
327N/C              J21   -A15        A01X+027030Y+046313X0140Y0480R090 S1      
327N/C              J21   -OB12       A01X+028842Y+040803X0140Y0480R090 S1      
327N/C              J21   -OA12       A01X+027030Y+040803X0140Y0480R090 S1      
327N/C              J21   -B68        A01X+028842Y+061872X0140Y0480R090 S1      
327N/C              J21   -B69        A01X+028842Y+062108X0140Y0480R090 S1      
327N/C              J21   -A68        A01X+027030Y+061872X0140Y0480R090 S1      
327N/C              J21   -A69        A01X+027030Y+062108X0140Y0480R090 S1      
327N/C              J21   -OA3        A01X+027030Y+038677X0140Y0480R090 S1      
317N/C              J22   -H2   D0440UA00X+064741Y+037486X0440Y         S3      
317N/C              J22   -H1   D0440UA00X+064052Y+063065X0440Y         S3      
327N/C              J22   -A14        A01X+065647Y+054474X0140Y0480R270 S1      
327N/C              J22   -OB11       A01X+063836Y+059984X0140Y0480R270 S1      
327N/C              J22   -OA11       A01X+065647Y+059984X0140Y0480R270 S1      
327N/C              J22   -A15        A01X+065647Y+054238X0140Y0480R270 S1      
327N/C              J22   -OB12       A01X+063836Y+059748X0140Y0480R270 S1      
327N/C              J22   -OA12       A01X+065647Y+059748X0140Y0480R270 S1      
327N/C              J22   -B68        A01X+063836Y+038679X0140Y0480R270 S1      
327N/C              J22   -B69        A01X+063836Y+038443X0140Y0480R270 S1      
327N/C              J22   -A68        A01X+065647Y+038679X0140Y0480R270 S1      
327N/C              J22   -A69        A01X+065647Y+038443X0140Y0480R270 S1      
327N/C              J22   -OA3        A01X+065647Y+061874X0140Y0480R270 S1      
317N/C              J23   -H2   D0440UA00X+073645Y+063065X0440Y    R180 S3      
317N/C              J23   -H1   D0440UA00X+074334Y+037486X0440Y    R180 S3      
327N/C              J23   -A14        A01X+072739Y+046077X0140Y0480R090 S1      
327N/C              J23   -OB11       A01X+074550Y+040567X0140Y0480R090 S1      
327N/C              J23   -OA11       A01X+072739Y+040567X0140Y0480R090 S1      
327N/C              J23   -A15        A01X+072739Y+046313X0140Y0480R090 S1      
327N/C              J23   -OB12       A01X+074550Y+040803X0140Y0480R090 S1      
327N/C              J23   -OA12       A01X+072739Y+040803X0140Y0480R090 S1      
327N/C              J23   -B68        A01X+074550Y+061872X0140Y0480R090 S1      
327N/C              J23   -B69        A01X+074550Y+062108X0140Y0480R090 S1      
327N/C              J23   -A68        A01X+072739Y+061872X0140Y0480R090 S1      
327N/C              J23   -A69        A01X+072739Y+062108X0140Y0480R090 S1      
327N/C              J23   -OA3        A01X+072739Y+038677X0140Y0480R090 S1      
317N/C              J24   -H2   D0440UA00X+110450Y+037486X0440Y         S3      
317N/C              J24   -H1   D0440UA00X+109761Y+063065X0440Y         S3      
327N/C              J24   -A14        A01X+111355Y+054474X0140Y0480R270 S1      
327N/C              J24   -OB11       A01X+109544Y+059984X0140Y0480R270 S1      
327N/C              J24   -OA11       A01X+111355Y+059984X0140Y0480R270 S1      
327N/C              J24   -A15        A01X+111355Y+054238X0140Y0480R270 S1      
327N/C              J24   -OB12       A01X+109544Y+059748X0140Y0480R270 S1      
327N/C              J24   -OA12       A01X+111355Y+059748X0140Y0480R270 S1      
327N/C              J24   -B68        A01X+109544Y+038679X0140Y0480R270 S1      
327N/C              J24   -B69        A01X+109544Y+038443X0140Y0480R270 S1      
327N/C              J24   -A68        A01X+111355Y+038679X0140Y0480R270 S1      
327N/C              J24   -A69        A01X+111355Y+038443X0140Y0480R270 S1      
327N/C              J24   -OA3        A01X+111355Y+061874X0140Y0480R270 S1      
317N/C              J25   -H2   D0440UA00X+119353Y+063065X0440Y    R180 S3      
317N/C              J25   -H1   D0440UA00X+120042Y+037486X0440Y    R180 S3      
327N/C              J25   -A14        A01X+118448Y+046077X0140Y0480R090 S1      
327N/C              J25   -OB11       A01X+120259Y+040567X0140Y0480R090 S1      
327N/C              J25   -OA11       A01X+118448Y+040567X0140Y0480R090 S1      
327N/C              J25   -A15        A01X+118448Y+046313X0140Y0480R090 S1      
327N/C              J25   -OB12       A01X+120259Y+040803X0140Y0480R090 S1      
327N/C              J25   -OA12       A01X+118448Y+040803X0140Y0480R090 S1      
327N/C              J25   -B68        A01X+120259Y+061872X0140Y0480R090 S1      
327N/C              J25   -B69        A01X+120259Y+062108X0140Y0480R090 S1      
327N/C              J25   -A68        A01X+118448Y+061872X0140Y0480R090 S1      
327N/C              J25   -A69        A01X+118448Y+062108X0140Y0480R090 S1      
327N/C              J25   -OA3        A01X+118448Y+038677X0140Y0480R090 S1      
317N/C              J26   -H2   D0440UA00X+156158Y+037486X0440Y         S3      
317N/C              J26   -H1   D0440UA00X+155470Y+063065X0440Y         S3      
327N/C              J26   -A14        A01X+157064Y+054474X0140Y0480R270 S1      
327N/C              J26   -OB11       A01X+155253Y+059984X0140Y0480R270 S1      
327N/C              J26   -OA11       A01X+157064Y+059984X0140Y0480R270 S1      
327N/C              J26   -A15        A01X+157064Y+054238X0140Y0480R270 S1      
327N/C              J26   -OB12       A01X+155253Y+059748X0140Y0480R270 S1      
327N/C              J26   -OA12       A01X+157064Y+059748X0140Y0480R270 S1      
327N/C              J26   -B68        A01X+155253Y+038679X0140Y0480R270 S1      
327N/C              J26   -B69        A01X+155253Y+038443X0140Y0480R270 S1      
327N/C              J26   -A68        A01X+157064Y+038679X0140Y0480R270 S1      
327N/C              J26   -A69        A01X+157064Y+038443X0140Y0480R270 S1      
327N/C              J26   -OA3        A01X+157064Y+061874X0140Y0480R270 S1      
317N/C              J27   -H2   D0440UA00X+165062Y+063065X0440Y    R180 S3      
317N/C              J27   -H1   D0440UA00X+165751Y+037486X0440Y    R180 S3      
327N/C              J27   -A14        A01X+164156Y+046077X0140Y0480R090 S1      
327N/C              J27   -OB11       A01X+165968Y+040567X0140Y0480R090 S1      
327N/C              J27   -OA11       A01X+164156Y+040567X0140Y0480R090 S1      
327N/C              J27   -A15        A01X+164156Y+046313X0140Y0480R090 S1      
327N/C              J27   -OB12       A01X+165968Y+040803X0140Y0480R090 S1      
327N/C              J27   -OA12       A01X+164156Y+040803X0140Y0480R090 S1      
327N/C              J27   -B68        A01X+165968Y+061872X0140Y0480R090 S1      
327N/C              J27   -B69        A01X+165968Y+062108X0140Y0480R090 S1      
327N/C              J27   -A68        A01X+164156Y+061872X0140Y0480R090 S1      
327N/C              J27   -A69        A01X+164156Y+062108X0140Y0480R090 S1      
327N/C              J27   -OA3        A01X+164156Y+038677X0140Y0480R090 S1      
327N/C              J56   -1          A01X+129882Y+100963X0500Y1350R090 S1      
317N/C              J55_12-1          A01X+187670Y+218317X0180Y    R180 S2      
017N/C              J55_12-1          A18X+187670Y+218317X0200Y    R180 S2      
017N/C                    -     D0080PA00X+187670Y+218317                       
317N/C              J56_12-1          A01X+188670Y+218317X0180Y    R180 S2      
017N/C              J56_12-1          A18X+188670Y+218317X0200Y    R180 S2      
017N/C                    -     D0080PA00X+188670Y+218317                       
317N/C              J57_12-1          A01X+185456Y+207793X0180Y    R180 S2      
017N/C              J57_12-1          A18X+185456Y+207793X0200Y    R180 S2      
017N/C                    -     D0080PA00X+185456Y+207793                       
327N/C              J54   -4          A01X+179644Y+082646X0170Y0590R090 S1      
327N/C              JPEX0 -6          A01X+009693Y+089530X0200Y0600R090 S1      
327N/C              JPEX0 -5          A01X+009693Y+089030X0200Y0600R090 S1      
327N/C              JPEX0 -4          A01X+009693Y+088530X0200Y0600R090 S1      
327N/C              JPEX0 -11         A01X+005913Y+089530X0200Y0600R090 S1      
327N/C              JPEX0 -12         A01X+005913Y+089030X0200Y0600R090 S1      
327N/C              JPEX0 -13         A01X+005913Y+088530X0200Y0600R090 S1      
327N/C              JPEX0 -14         A01X+005913Y+088030X0200Y0600R090 S1      
327N/C              JPEX1 -6          A01X+055387Y+089530X0200Y0600R090 S1      
327N/C              JPEX1 -5          A01X+055387Y+089030X0200Y0600R090 S1      
327N/C              JPEX1 -4          A01X+055387Y+088530X0200Y0600R090 S1      
327N/C              JPEX1 -11         A01X+051607Y+089530X0200Y0600R090 S1      
327N/C              JPEX1 -12         A01X+051607Y+089030X0200Y0600R090 S1      
327N/C              JPEX1 -13         A01X+051607Y+088530X0200Y0600R090 S1      
327N/C              JPEX1 -14         A01X+051607Y+088030X0200Y0600R090 S1      
327N/C              JPEX2 -6          A01X+101063Y+089530X0200Y0600R090 S1      
327N/C              JPEX2 -5          A01X+101063Y+089030X0200Y0600R090 S1      
327N/C              JPEX2 -4          A01X+101063Y+088530X0200Y0600R090 S1      
327N/C              JPEX2 -11         A01X+097283Y+089530X0200Y0600R090 S1      
327N/C              JPEX2 -12         A01X+097283Y+089030X0200Y0600R090 S1      
327N/C              JPEX2 -13         A01X+097283Y+088530X0200Y0600R090 S1      
327N/C              JPEX2 -14         A01X+097283Y+088030X0200Y0600R090 S1      
327N/C              JPEX3 -6          A01X+146804Y+089530X0200Y0600R090 S1      
327N/C              JPEX3 -5          A01X+146804Y+089030X0200Y0600R090 S1      
327N/C              JPEX3 -4          A01X+146804Y+088530X0200Y0600R090 S1      
327N/C              JPEX3 -11         A01X+143025Y+089530X0200Y0600R090 S1      
327N/C              JPEX3 -12         A01X+143025Y+089030X0200Y0600R090 S1      
327N/C              JPEX3 -13         A01X+143025Y+088530X0200Y0600R090 S1      
327N/C              JPEX3 -14         A01X+143025Y+088030X0200Y0600R090 S1      
327N/C              PEX0  -BG1        A01X+014508Y+108268X0180Y         S1      
327N/C              PEX0  -BG2        A01X+014882Y+108268X0180Y         S1      
327N/C              PEX0  -BH3        A01X+015256Y+107894X0180Y         S1      
327N/C              PEX0  -AP8        A01X+017126Y+113130X0180Y         S1      
327N/C              PEX0  -AR6        A01X+016378Y+112756X0180Y         S1      
327N/C              PEX0  -AT8        A01X+017126Y+112382X0180Y         S1      
327N/C              PEX0  -AU6        A01X+016378Y+112008X0180Y         S1      
327N/C              PEX0  -AV8        A01X+017126Y+111634X0180Y         S1      
327N/C              PEX0  -BB8        A01X+017126Y+110138X0180Y         S1      
327N/C              PEX0  -AP9        A01X+017500Y+113130X0180Y         S1      
327N/C              PEX0  -AR7        A01X+016752Y+112756X0180Y         S1      
327N/C              PEX0  -AT9        A01X+017500Y+112382X0180Y         S1      
327N/C              PEX0  -AU7        A01X+016752Y+112008X0180Y         S1      
327N/C              PEX0  -AV9        A01X+017500Y+111634X0180Y         S1      
327N/C              PEX0  -AD49       A01X+032461Y+116870X0180Y         S1      
327N/C              PEX0  -AE47       A01X+031712Y+116496X0180Y         S1      
327N/C              PEX0  -AD48       A01X+032087Y+116870X0180Y         S1      
327N/C              PEX0  -AE46       A01X+031338Y+116496X0180Y         S1      
327N/C              PEX0  -U44        A01X+030590Y+119488X0180Y         S1      
327N/C              PEX0  -V42        A01X+029842Y+119114X0180Y         S1      
327N/C              PEX0  -Y42        A01X+029842Y+118366X0180Y         S1      
327N/C              PEX0  -AB42       A01X+029842Y+117618X0180Y         S1      
327N/C              PEX0  -AE44       A01X+030590Y+116496X0180Y         S1      
327N/C              PEX0  -AF42       A01X+029842Y+116122X0180Y         S1      
327N/C              PEX0  -AG44       A01X+030590Y+115748X0180Y         S1      
327N/C              PEX0  -AK42       A01X+029842Y+114626X0180Y         S1      
327N/C              PEX0  -AM42       A01X+029842Y+113878X0180Y         S1      
327N/C              PEX0  -U43        A01X+030216Y+119488X0180Y         S1      
327N/C              PEX0  -V41        A01X+029468Y+119114X0180Y         S1      
327N/C              PEX0  -Y41        A01X+029468Y+118366X0180Y         S1      
327N/C              PEX0  -AB41       A01X+029468Y+117618X0180Y         S1      
327N/C              PEX0  -AE43       A01X+030216Y+116496X0180Y         S1      
327N/C              PEX0  -AF41       A01X+029468Y+116122X0180Y         S1      
327N/C              PEX0  -AG43       A01X+030216Y+115748X0180Y         S1      
327N/C              PEX0  -R39        A01X+028720Y+120236X0180Y         S1      
327N/C              PEX0  -AF4        A01X+015630Y+116122X0180Y         S1      
327N/C              PEX0  -AF5        A01X+016004Y+116122X0180Y         S1      
327N/C              PEX0  -U39        A01X+028720Y+119488X0180Y         S1      
327N/C              PEX0  -AG1        A01X+014508Y+115748X0180Y         S1      
327N/C              PEX0  -AG2        A01X+014882Y+115748X0180Y         S1      
327N/C              PEX0  -R38        A01X+028346Y+120236X0180Y         S1      
327N/C              PEX0  -AH4        A01X+015630Y+115374X0180Y         S1      
327N/C              PEX0  -AH5        A01X+016004Y+115374X0180Y         S1      
327N/C              PEX0  -AW39       A01X+028720Y+111260X0180Y         S1      
327N/C              PEX0  -AV34       A01X+026850Y+111634X0180Y         S1      
327N/C              PEX0  -AN39       A01X+028720Y+113504X0180Y         S1      
327N/C              PEX0  -AW35       A01X+027224Y+111260X0180Y         S1      
327N/C              PEX0  -AU39       A01X+028720Y+112008X0180Y         S1      
327N/C              PEX0  -AV36       A01X+027598Y+111634X0180Y         S1      
327N/C              PEX0  -AW19       A01X+021240Y+111260X0180Y         S1      
327N/C              PEX0  -AW15       A01X+019744Y+111260X0180Y         S1      
327N/C              PEX0  -AT39       A01X+028720Y+112382X0180Y         S1      
327N/C              PEX0  -AW18       A01X+020866Y+111260X0180Y         S1      
327N/C              PEX0  -AW14       A01X+019370Y+111260X0180Y         S1      
327N/C              PEX0  -AW17       A01X+020492Y+111260X0180Y         S1      
327N/C              PEX0  -AW13       A01X+018996Y+111260X0180Y         S1      
327N/C              PEX0  -AW16       A01X+020118Y+111260X0180Y         S1      
327N/C              PEX0  -AW12       A01X+018622Y+111260X0180Y         S1      
327N/C              PEX0  -AV39       A01X+028720Y+111634X0180Y         S1      
327N/C              PEX0  -AW33       A01X+026476Y+111260X0180Y         S1      
327N/C              PEX0  -AT38       A01X+028346Y+112382X0180Y         S1      
327N/C              PEX0  -AV33       A01X+026476Y+111634X0180Y         S1      
327N/C              PEX0  -AV38       A01X+028346Y+111634X0180Y         S1      
327N/C              PEX0  -AV37       A01X+027972Y+111634X0180Y         S1      
327N/C              PEX0  -AU38       A01X+028346Y+112008X0180Y         S1      
327N/C              PEX0  -AN38       A01X+028346Y+113504X0180Y         S1      
327N/C              PEX0  -L35        A01X+027224Y+121732X0180Y         S1      
327N/C              PEX0  -M31        A01X+025728Y+121358X0180Y         S1      
327N/C              PEX0  -L33        A01X+026476Y+121732X0180Y         S1      
327N/C              PEX0  -AW23       A01X+022736Y+111260X0180Y         S1      
327N/C              PEX0  -AW21       A01X+021988Y+111260X0180Y         S1      
327N/C              PEX0  -M33        A01X+026476Y+121358X0180Y         S1      
327N/C              PEX0  -L29        A01X+024980Y+121732X0180Y         S1      
327N/C              PEX0  -AM39       A01X+028720Y+113878X0180Y         S1      
327N/C              PEX0  -N39        A01X+028720Y+120984X0180Y         S1      
327N/C              PEX0  -L31        A01X+025728Y+121732X0180Y         S1      
327N/C              PEX0  -AW22       A01X+022362Y+111260X0180Y         S1      
327N/C              PEX0  -L24        A01X+023110Y+121732X0180Y         S1      
327N/C              PEX0  -AP38       A01X+028346Y+113130X0180Y         S1      
327N/C              PEX0  -AR38       A01X+028346Y+112756X0180Y         S1      
327N/C              PEX0  -AP39       A01X+028720Y+113130X0180Y         S1      
327N/C              PEX0  -AR39       A01X+028720Y+112756X0180Y         S1      
327N/C              PEX0  -L38        A01X+028346Y+121732X0180Y         S1      
327N/C              PEX0  -L36        A01X+027598Y+121732X0180Y         S1      
327N/C              PEX0  -AE7        A01X+016752Y+116496X0180Y         S1      
327N/C              PEX0  -AB8        A01X+017126Y+117618X0180Y         S1      
327N/C              PEX0  -AB7        A01X+016752Y+117618X0180Y         S1      
327N/C              PEX0  -AD7        A01X+016752Y+116870X0180Y         S1      
327N/C              PEX0  -AC7        A01X+016752Y+117244X0180Y         S1      
327N/C              PEX0  -AD8        A01X+017126Y+116870X0180Y         S1      
327N/C              PEX0  -AC8        A01X+017126Y+117244X0180Y         S1      
327N/C              PEX0  -AE8        A01X+017126Y+116496X0180Y         S1      
327N/C              U112  -12         A01X+093084Y+036522X0100Y0290R090 S1      
327N/C              U112  -15         A01X+092725Y+037275X0100Y0290R180 S1      
327N/C              U112  -13         A01X+093084Y+036719X0100Y0290R090 S1      
327N/C              U112  -16         A01X+092528Y+037275X0100Y0290R180 S1      
327N/C              U112  -26         A01X+091184Y+036129X0100Y0290R090 S1      
327N/C              U113  -A25        A01X+102924Y+031666X0070Y0220     S1      
327N/C              U113  -A24        A01X+102727Y+031666X0070Y0220     S1      
327N/C              U113  -A23        A01X+102530Y+031666X0070Y0220     S1      
327N/C              U113  -A22        A01X+102333Y+031666X0070Y0220     S1      
327N/C              U113  -A21        A01X+102137Y+031666X0070Y0220     S1      
327N/C              U113  -A20        A01X+101940Y+031666X0070Y0220     S1      
327N/C              U113  -A19        A01X+101743Y+031666X0070Y0220     S1      
327N/C              U113  -A18        A01X+101546Y+031666X0070Y0220     S1      
327N/C              U113  -A5         A01X+100709Y+033684X0070Y0220R090 S1      
327N/C              U113  -A4         A01X+100709Y+033880X0070Y0220R090 S1      
327N/C              U113  -A3         A01X+100709Y+034077X0070Y0220R090 S1      
327N/C              U113  -A2         A01X+100709Y+034274X0070Y0220R090 S1      
327N/C              U113  -A56        A01X+100956Y+034717X0070Y0220     S1      
327N/C              U113  -A55        A01X+101152Y+034717X0070Y0220     S1      
327N/C              U113  -A52        A01X+101743Y+034717X0070Y0220     S1      
327N/C              U113  -A51        A01X+101940Y+034717X0070Y0220     S1      
327N/C              U113  -A50        A01X+102137Y+034717X0070Y0220     S1      
327N/C              U113  -A49        A01X+102333Y+034717X0070Y0220     S1      
327N/C              U113  -A48        A01X+102530Y+034717X0070Y0220     S1      
327N/C              U113  -A47        A01X+102727Y+034717X0070Y0220     S1      
327N/C              U113  -A46        A01X+102924Y+034717X0070Y0220     S1      
327N/C              U113  -A45        A01X+103121Y+034717X0070Y0220     S1      
327N/C              U113  -A44        A01X+103318Y+034717X0070Y0220     S1      
327N/C              U113  -A43        A01X+103514Y+034717X0070Y0220     S1      
327N/C              U113  -A42        A01X+103761Y+034471X0070Y0220R270 S1      
327N/C              U113  -A41        A01X+103761Y+034274X0070Y0220R270 S1      
327N/C              U113  -A40        A01X+103761Y+034077X0070Y0220R270 S1      
327N/C              U113  -A39        A01X+103761Y+033880X0070Y0220R270 S1      
327N/C              U113  -A38        A01X+103761Y+033684X0070Y0220R270 S1      
327N/C              U113  -A37        A01X+103761Y+033487X0070Y0220R270 S1      
327N/C              U113  -A36        A01X+103761Y+033290X0070Y0220R270 S1      
327N/C              U113  -A35        A01X+103761Y+033093X0070Y0220R270 S1      
327N/C              U113  -A15        A01X+100956Y+031666X0070Y0220     S1      
327N/C              U113  -B13        A01X+101448Y+031961X0110Y0180     S1      
327N/C              U113  -B16        A01X+102038Y+031961X0110Y0180     S1      
327N/C              U113  -B18        A01X+102432Y+031961X0110Y0180     S1      
327N/C              U113  -B2         A01X+101005Y+033979X0110Y0180R090 S1      
327N/C              U113  -B20        A01X+102826Y+031961X0110Y0180     S1      
327N/C              U113  -B22        A01X+103219Y+031961X0110Y0180     S1      
327N/C              U113  -B24        A01X+103465Y+032404X0110Y0180R270 S1      
327N/C              U113  -B25        A01X+103465Y+032601X0110Y0180R270 S1      
327N/C              U113  -B26        A01X+103465Y+032798X0110Y0180R270 S1      
327N/C              U113  -B28        A01X+103465Y+033192X0110Y0180R270 S1      
327N/C              U113  -B3         A01X+101005Y+033782X0110Y0180R090 S1      
327N/C              U113  -B30        A01X+103465Y+033585X0110Y0180R270 S1      
327N/C              U113  -B31        A01X+103465Y+033782X0110Y0180R270 S1      
327N/C              U113  -B33        A01X+103465Y+034176X0110Y0180R270 S1      
327N/C              U113  -B34        A01X+103219Y+034422X0110Y0180     S1      
327N/C              U113  -B36        A01X+102826Y+034422X0110Y0180     S1      
327N/C              U113  -B37        A01X+102629Y+034422X0110Y0180     S1      
327N/C              U113  -B39        A01X+102235Y+034422X0110Y0180     S1      
327N/C              U113  -B41        A01X+101841Y+034422X0110Y0180     S1      
327N/C              U113  -B44        A01X+101251Y+034422X0110Y0180     S1      
327N/C              U113  -B5         A01X+101005Y+033388X0110Y0180R090 S1      
327N/C              U113  -B7         A01X+101005Y+032995X0110Y0180R090 S1      
327N/C              U114  -A3         A01X+051563Y+071024X0090Y         S1      
327N/C              U114  -A2         A01X+051367Y+071024X0090Y         S1      
327N/C              U114  -A1         A01X+051170Y+071024X0090Y         S1      
327N/C              U114  -B1         A01X+051170Y+070827X0090Y         S1      
327N/C              U114  -C1         A01X+051170Y+070630X0090Y         S1      
327N/C              U114  -D1         A01X+051170Y+070433X0090Y         S1      
327N/C              U114  -E1         A01X+051170Y+070236X0090Y         S1      
327N/C              U114  -F1         A01X+051170Y+070040X0090Y         S1      
327N/C              U114  -M7         A01X+052351Y+068858X0090Y         S1      
327N/C              U114  -M8         A01X+052548Y+068858X0090Y         S1      
327N/C              U114  -B3         A01X+051563Y+070827X0090Y         S1      
327N/C              U114  -G2         A01X+051367Y+069843X0090Y         S1      
327N/C              U114  -G11        A01X+053138Y+069843X0090Y         S1      
327N/C              U114  -J2         A01X+051367Y+069449X0090Y         S1      
327N/C              U114  -J11        A01X+053138Y+069449X0090Y         S1      
327N/C              U114  -K2         A01X+051367Y+069252X0090Y         S1      
327N/C              U114  -L6         A01X+052154Y+069055X0090Y         S1      
327N/C              U114  -L7         A01X+052351Y+069055X0090Y         S1      
327N/C              U114  -L3         A01X+051563Y+069055X0090Y         S1      
327N/C              U114  -L9         A01X+052744Y+069055X0090Y         S1      
327N/C              U114  -B5         A01X+051957Y+070827X0090Y         S1      
327N/C              U114  -B7         A01X+052351Y+070827X0090Y         S1      
327N/C              U114  -B9         A01X+052744Y+070827X0090Y         S1      
327N/C              U114  -C2         A01X+051367Y+070630X0090Y         S1      
327N/C              U114  -D2         A01X+051367Y+070433X0090Y         S1      
327N/C              U114  -D11        A01X+053138Y+070433X0090Y         S1      
327N/C              U114  -F2         A01X+051367Y+070040X0090Y         S1      
327N/C              U114  -F11        A01X+053138Y+070040X0090Y         S1      
327N/C              U115  -9          A01X+041689Y+033456X0070Y0340R270 S1      
327N/C              U115  -8          A01X+041689Y+033614X0070Y0340R270 S1      
327N/C              U115  -12         A01X+041689Y+032984X0070Y0340R270 S1      
327N/C              U115  -20         A01X+043086Y+032689X0070Y0340     S1      
327N/C              U115  -43         A01X+042771Y+035011X0070Y0340R180 S1      
327N/C              U115  -45         A01X+042456Y+035011X0070Y0340R180 S1      
327N/C              U115  -46         A01X+042299Y+035011X0070Y0340R180 S1      
327N/C              U116  -9          A01X+131947Y+033766X0070Y0340R270 S1      
327N/C              U116  -8          A01X+131947Y+033923X0070Y0340R270 S1      
327N/C              U116  -12         A01X+131947Y+033293X0070Y0340R270 S1      
327N/C              U116  -20         A01X+133345Y+032998X0070Y0340     S1      
327N/C              U116  -43         A01X+133030Y+035321X0070Y0340R180 S1      
327N/C              U116  -45         A01X+132715Y+035321X0070Y0340R180 S1      
327N/C              U116  -46         A01X+132557Y+035321X0070Y0340R180 S1      
327N/C              U118  -9          A18X+042545Y+129597X0100Y0220     S2      
327N/C              U118  -8          A18X+042791Y+129843X0100Y0220R090 S2      
327N/C              U118  -10         A18X+042348Y+129597X0100Y0220     S2      
327N/C              U118  -11         A18X+042151Y+129597X0100Y0220     S2      
327N/C              U118  -17         A18X+040921Y+129843X0100Y0220R270 S2      
327N/C              U118  -30         A18X+042151Y+131467X0100Y0220R180 S2      
317N/C              J12   -B10  D0122PA00X+053429Y+161650X0282Y    R180 S3      
317N/C              J12   -C10  D0122PA00X+053429Y+161138X0282Y    R180 S3      
317N/C              J12   -E10  D0122PA00X+053429Y+160114X0282Y    R180 S3      
317N/C              J12   -F10  D0122PA00X+053429Y+159602X0282Y    R180 S3      
317N/C              J12   -I9   D0122PA00X+052563Y+158146X0282Y    R180 S3      
317N/C              J12   -J9   D0122PA00X+052563Y+157634X0282Y    R180 S3      
317N/C              J12   -K10  D0122PA00X+053429Y+157043X0282Y    R180 S3      
317N/C              J12   -L10  D0122PA00X+053429Y+156532X0282Y    R180 S3      
317N/C              J12   -L9   D0122PA00X+052563Y+156610X0282Y    R180 S3      
317N/C              J12   -M9   D0122PA00X+052563Y+156098X0282Y    R180 S3      
317N/C              J12   -N10  D0122PA00X+053429Y+151413X0282Y    R180 S3      
317N/C              J12   -O10  D0122PA00X+053429Y+150902X0282Y    R180 S3      
317N/C              J12   -O9   D0122PA00X+052563Y+150980X0282Y    R180 S3      
317N/C              J12   -P9   D0122PA00X+052563Y+150468X0282Y    R180 S3      
317N/C              J12   -Q10  D0122PA00X+053429Y+149878X0282Y    R180 S3      
317N/C              J12   -R10  D0122PA00X+053429Y+149366X0282Y    R180 S3      
317N/C              J12   -R9   D0122PA00X+052563Y+149445X0282Y    R180 S3      
317N/C              J12   -S9   D0122PA00X+052563Y+148933X0282Y    R180 S3      
317N/C              J12   -T10  D0122PA00X+053429Y+148343X0282Y    R180 S3      
317N/C              J12   -U10  D0122PA00X+053429Y+147831X0282Y    R180 S3      
317N/C              J12   -U9   D0122PA00X+052563Y+147910X0282Y    R180 S3      
317N/C              J12   -V9   D0122PA00X+052563Y+147398X0282Y    R180 S3      
317N/C              J12   -W10  D0122PA00X+053429Y+146807X0282Y    R180 S3      
317N/C              J12   -X10  D0122PA00X+053429Y+146295X0282Y    R180 S3      
317N/C              J12   -X9   D0122PA00X+052563Y+146374X0282Y    R180 S3      
317N/C              J12   -Y9   D0122PA00X+052563Y+145862X0282Y    R180 S3      
327N/C              U51   -6          A01X+009093Y+018836X0090Y0240R180 S1      
327N/C              U51   -7          A01X+008896Y+018836X0090Y0240R180 S1      
327N/C              U51   -8          A01X+008699Y+018836X0090Y0240R180 S1      
327N/C              U51   -14         A01X+008896Y+017734X0090Y0240R180 S1      
327N/C              U51   -15         A01X+009093Y+017734X0090Y0240R180 S1      
327N/C              U51   -16         A01X+009290Y+017734X0090Y0240R180 S1      
327N/C              U54   -6          A01X+019329Y+018836X0090Y0240R180 S1      
327N/C              U54   -7          A01X+019132Y+018836X0090Y0240R180 S1      
327N/C              U54   -8          A01X+018935Y+018836X0090Y0240R180 S1      
327N/C              U54   -14         A01X+019132Y+017734X0090Y0240R180 S1      
327N/C              U54   -15         A01X+019329Y+017734X0090Y0240R180 S1      
327N/C              U54   -16         A01X+019526Y+017734X0090Y0240R180 S1      
327N/C              U55   -6          A01X+029565Y+018836X0090Y0240R180 S1      
327N/C              U55   -7          A01X+029368Y+018836X0090Y0240R180 S1      
327N/C              U55   -8          A01X+029172Y+018836X0090Y0240R180 S1      
327N/C              U55   -14         A01X+029368Y+017734X0090Y0240R180 S1      
327N/C              U55   -15         A01X+029565Y+017734X0090Y0240R180 S1      
327N/C              U55   -16         A01X+029762Y+017734X0090Y0240R180 S1      
327N/C              PEX1  -R39        A01X+074429Y+120236X0180Y         S1      
327N/C              PEX1  -AF4        A01X+061339Y+116122X0180Y         S1      
327N/C              PEX1  -AF5        A01X+061713Y+116122X0180Y         S1      
327N/C              PEX1  -U39        A01X+074429Y+119488X0180Y         S1      
327N/C              PEX1  -AG1        A01X+060216Y+115748X0180Y         S1      
327N/C              PEX1  -AG2        A01X+060590Y+115748X0180Y         S1      
327N/C              PEX1  -R38        A01X+074055Y+120236X0180Y         S1      
327N/C              PEX1  -AH4        A01X+061339Y+115374X0180Y         S1      
327N/C              PEX1  -AH5        A01X+061713Y+115374X0180Y         S1      
327N/C              PEX1  -AW39       A01X+074429Y+111260X0180Y         S1      
327N/C              PEX1  -AV34       A01X+072559Y+111634X0180Y         S1      
327N/C              PEX1  -AN39       A01X+074429Y+113504X0180Y         S1      
327N/C              PEX1  -AW35       A01X+072933Y+111260X0180Y         S1      
327N/C              PEX1  -AU39       A01X+074429Y+112008X0180Y         S1      
327N/C              PEX1  -AV36       A01X+073307Y+111634X0180Y         S1      
327N/C              PEX1  -AW19       A01X+066949Y+111260X0180Y         S1      
327N/C              PEX1  -AW15       A01X+065453Y+111260X0180Y         S1      
327N/C              PEX1  -AT39       A01X+074429Y+112382X0180Y         S1      
327N/C              PEX1  -AW18       A01X+066575Y+111260X0180Y         S1      
327N/C              PEX1  -AW14       A01X+065079Y+111260X0180Y         S1      
327N/C              PEX1  -AW17       A01X+066201Y+111260X0180Y         S1      
327N/C              PEX1  -AW13       A01X+064705Y+111260X0180Y         S1      
327N/C              PEX1  -AW16       A01X+065827Y+111260X0180Y         S1      
327N/C              PEX1  -AW12       A01X+064331Y+111260X0180Y         S1      
327N/C              PEX1  -AV39       A01X+074429Y+111634X0180Y         S1      
327N/C              PEX1  -AW33       A01X+072185Y+111260X0180Y         S1      
327N/C              PEX1  -AT38       A01X+074055Y+112382X0180Y         S1      
327N/C              PEX1  -AV33       A01X+072185Y+111634X0180Y         S1      
327N/C              PEX1  -AV38       A01X+074055Y+111634X0180Y         S1      
327N/C              PEX1  -AV37       A01X+073681Y+111634X0180Y         S1      
327N/C              PEX1  -AU38       A01X+074055Y+112008X0180Y         S1      
327N/C              PEX1  -AN38       A01X+074055Y+113504X0180Y         S1      
327N/C              PEX1  -L35        A01X+072933Y+121732X0180Y         S1      
327N/C              PEX1  -M31        A01X+071437Y+121358X0180Y         S1      
327N/C              PEX1  -L33        A01X+072185Y+121732X0180Y         S1      
327N/C              PEX1  -AW23       A01X+068445Y+111260X0180Y         S1      
327N/C              PEX1  -AW21       A01X+067697Y+111260X0180Y         S1      
327N/C              PEX1  -M33        A01X+072185Y+121358X0180Y         S1      
327N/C              PEX1  -L29        A01X+070689Y+121732X0180Y         S1      
327N/C              PEX1  -AM39       A01X+074429Y+113878X0180Y         S1      
327N/C              PEX1  -N39        A01X+074429Y+120984X0180Y         S1      
327N/C              PEX1  -L31        A01X+071437Y+121732X0180Y         S1      
327N/C              PEX1  -AW22       A01X+068071Y+111260X0180Y         S1      
327N/C              PEX1  -L24        A01X+068819Y+121732X0180Y         S1      
327N/C              PEX1  -AP38       A01X+074055Y+113130X0180Y         S1      
327N/C              PEX1  -AR38       A01X+074055Y+112756X0180Y         S1      
327N/C              PEX1  -AP39       A01X+074429Y+113130X0180Y         S1      
327N/C              PEX1  -AR39       A01X+074429Y+112756X0180Y         S1      
327N/C              PEX1  -L38        A01X+074055Y+121732X0180Y         S1      
327N/C              PEX1  -L36        A01X+073307Y+121732X0180Y         S1      
327N/C              PEX1  -AE7        A01X+062461Y+116496X0180Y         S1      
327N/C              PEX1  -AB8        A01X+062835Y+117618X0180Y         S1      
327N/C              PEX1  -AB7        A01X+062461Y+117618X0180Y         S1      
327N/C              PEX1  -AD7        A01X+062461Y+116870X0180Y         S1      
327N/C              PEX1  -AC7        A01X+062461Y+117244X0180Y         S1      
327N/C              PEX1  -AD8        A01X+062835Y+116870X0180Y         S1      
327N/C              PEX1  -AC8        A01X+062835Y+117244X0180Y         S1      
327N/C              PEX1  -AE8        A01X+062835Y+116496X0180Y         S1      
327N/C              PEX2  -R39        A01X+120138Y+120236X0180Y         S1      
327N/C              PEX2  -AF4        A01X+107047Y+116122X0180Y         S1      
327N/C              PEX2  -AF5        A01X+107421Y+116122X0180Y         S1      
327N/C              PEX2  -U39        A01X+120138Y+119488X0180Y         S1      
327N/C              PEX2  -AG1        A01X+105925Y+115748X0180Y         S1      
327N/C              PEX2  -AG2        A01X+106299Y+115748X0180Y         S1      
327N/C              PEX2  -R38        A01X+119764Y+120236X0180Y         S1      
327N/C              PEX2  -AH4        A01X+107047Y+115374X0180Y         S1      
327N/C              PEX2  -AH5        A01X+107421Y+115374X0180Y         S1      
327N/C              PEX2  -AW39       A01X+120138Y+111260X0180Y         S1      
327N/C              PEX2  -AV34       A01X+118268Y+111634X0180Y         S1      
327N/C              PEX2  -AN39       A01X+120138Y+113504X0180Y         S1      
327N/C              PEX2  -AW35       A01X+118642Y+111260X0180Y         S1      
327N/C              PEX2  -AU39       A01X+120138Y+112008X0180Y         S1      
327N/C              PEX2  -AV36       A01X+119016Y+111634X0180Y         S1      
327N/C              PEX2  -AW19       A01X+112657Y+111260X0180Y         S1      
327N/C              PEX2  -AW15       A01X+111161Y+111260X0180Y         S1      
327N/C              PEX2  -AT39       A01X+120138Y+112382X0180Y         S1      
327N/C              PEX2  -AW18       A01X+112283Y+111260X0180Y         S1      
327N/C              PEX2  -AW14       A01X+110787Y+111260X0180Y         S1      
327N/C              PEX2  -AW17       A01X+111909Y+111260X0180Y         S1      
327N/C              PEX2  -AW13       A01X+110413Y+111260X0180Y         S1      
327N/C              PEX2  -AW16       A01X+111535Y+111260X0180Y         S1      
327N/C              PEX2  -AW12       A01X+110039Y+111260X0180Y         S1      
327N/C              PEX2  -AV39       A01X+120138Y+111634X0180Y         S1      
327N/C              PEX2  -AW33       A01X+117894Y+111260X0180Y         S1      
327N/C              PEX2  -AT38       A01X+119764Y+112382X0180Y         S1      
327N/C              PEX2  -AV33       A01X+117894Y+111634X0180Y         S1      
327N/C              PEX2  -AV38       A01X+119764Y+111634X0180Y         S1      
327N/C              PEX2  -AV37       A01X+119390Y+111634X0180Y         S1      
327N/C              PEX2  -AU38       A01X+119764Y+112008X0180Y         S1      
327N/C              PEX2  -AN38       A01X+119764Y+113504X0180Y         S1      
327N/C              PEX2  -L35        A01X+118642Y+121732X0180Y         S1      
327N/C              PEX2  -M31        A01X+117146Y+121358X0180Y         S1      
327N/C              PEX2  -L33        A01X+117894Y+121732X0180Y         S1      
327N/C              PEX2  -AW23       A01X+114154Y+111260X0180Y         S1      
327N/C              PEX2  -AW21       A01X+113405Y+111260X0180Y         S1      
327N/C              PEX2  -M33        A01X+117894Y+121358X0180Y         S1      
327N/C              PEX2  -L29        A01X+116398Y+121732X0180Y         S1      
327N/C              PEX2  -AM39       A01X+120138Y+113878X0180Y         S1      
327N/C              PEX2  -N39        A01X+120138Y+120984X0180Y         S1      
327N/C              PEX2  -L31        A01X+117146Y+121732X0180Y         S1      
327N/C              PEX2  -AW22       A01X+113780Y+111260X0180Y         S1      
327N/C              PEX2  -L24        A01X+114528Y+121732X0180Y         S1      
327N/C              PEX2  -AP38       A01X+119764Y+113130X0180Y         S1      
327N/C              PEX2  -AR38       A01X+119764Y+112756X0180Y         S1      
327N/C              PEX2  -AP39       A01X+120138Y+113130X0180Y         S1      
327N/C              PEX2  -AR39       A01X+120138Y+112756X0180Y         S1      
327N/C              PEX2  -L38        A01X+119764Y+121732X0180Y         S1      
327N/C              PEX2  -L36        A01X+119016Y+121732X0180Y         S1      
327N/C              PEX2  -AE7        A01X+108169Y+116496X0180Y         S1      
327N/C              PEX2  -AB8        A01X+108543Y+117618X0180Y         S1      
327N/C              PEX2  -AB7        A01X+108169Y+117618X0180Y         S1      
327N/C              PEX2  -AD7        A01X+108169Y+116870X0180Y         S1      
327N/C              PEX2  -AC7        A01X+108169Y+117244X0180Y         S1      
327N/C              PEX2  -AD8        A01X+108543Y+116870X0180Y         S1      
327N/C              PEX2  -AC8        A01X+108543Y+117244X0180Y         S1      
327N/C              PEX2  -AE8        A01X+108543Y+116496X0180Y         S1      
327N/C              PEX3  -R39        A01X+165846Y+120236X0180Y         S1      
327N/C              PEX3  -AF4        A01X+152756Y+116122X0180Y         S1      
327N/C              PEX3  -AF5        A01X+153130Y+116122X0180Y         S1      
327N/C              PEX3  -U39        A01X+165846Y+119488X0180Y         S1      
327N/C              PEX3  -R38        A01X+165472Y+120236X0180Y         S1      
327N/C              PEX3  -AH4        A01X+152756Y+115374X0180Y         S1      
327N/C              PEX3  -AH5        A01X+153130Y+115374X0180Y         S1      
327N/C              PEX3  -AW39       A01X+165846Y+111260X0180Y         S1      
327N/C              PEX3  -AV34       A01X+163976Y+111634X0180Y         S1      
327N/C              PEX3  -AN39       A01X+165846Y+113504X0180Y         S1      
327N/C              PEX3  -AW35       A01X+164350Y+111260X0180Y         S1      
327N/C              PEX3  -AU39       A01X+165846Y+112008X0180Y         S1      
327N/C              PEX3  -AV36       A01X+164724Y+111634X0180Y         S1      
327N/C              PEX3  -AW19       A01X+158366Y+111260X0180Y         S1      
327N/C              PEX3  -AW15       A01X+156870Y+111260X0180Y         S1      
327N/C              PEX3  -AT39       A01X+165846Y+112382X0180Y         S1      
327N/C              PEX3  -AW18       A01X+157992Y+111260X0180Y         S1      
327N/C              PEX3  -AW14       A01X+156496Y+111260X0180Y         S1      
327N/C              PEX3  -AW17       A01X+157618Y+111260X0180Y         S1      
327N/C              PEX3  -AW13       A01X+156122Y+111260X0180Y         S1      
327N/C              PEX3  -AW16       A01X+157244Y+111260X0180Y         S1      
327N/C              PEX3  -AW12       A01X+155748Y+111260X0180Y         S1      
327N/C              PEX3  -AV39       A01X+165846Y+111634X0180Y         S1      
327N/C              PEX3  -AT38       A01X+165472Y+112382X0180Y         S1      
327N/C              PEX3  -AV38       A01X+165472Y+111634X0180Y         S1      
327N/C              PEX3  -AV37       A01X+165098Y+111634X0180Y         S1      
327N/C              PEX3  -AU38       A01X+165472Y+112008X0180Y         S1      
327N/C              PEX3  -L35        A01X+164350Y+121732X0180Y         S1      
327N/C              PEX3  -M31        A01X+162854Y+121358X0180Y         S1      
327N/C              PEX3  -L33        A01X+163602Y+121732X0180Y         S1      
327N/C              PEX3  -AW23       A01X+159862Y+111260X0180Y         S1      
327N/C              PEX3  -AW21       A01X+159114Y+111260X0180Y         S1      
327N/C              PEX3  -M33        A01X+163602Y+121358X0180Y         S1      
327N/C              PEX3  -L29        A01X+162106Y+121732X0180Y         S1      
327N/C              PEX3  -AM39       A01X+165846Y+113878X0180Y         S1      
327N/C              PEX3  -N39        A01X+165846Y+120984X0180Y         S1      
327N/C              PEX3  -L31        A01X+162854Y+121732X0180Y         S1      
327N/C              PEX3  -AW22       A01X+159488Y+111260X0180Y         S1      
327N/C              PEX3  -L24        A01X+160236Y+121732X0180Y         S1      
327N/C              PEX3  -AP38       A01X+165472Y+113130X0180Y         S1      
327N/C              PEX3  -AR38       A01X+165472Y+112756X0180Y         S1      
327N/C              PEX3  -AP39       A01X+165846Y+113130X0180Y         S1      
327N/C              PEX3  -AR39       A01X+165846Y+112756X0180Y         S1      
327N/C              PEX3  -L38        A01X+165472Y+121732X0180Y         S1      
327N/C              PEX3  -L36        A01X+164724Y+121732X0180Y         S1      
327N/C              PEX3  -AE7        A01X+153878Y+116496X0180Y         S1      
327N/C              PEX3  -AB8        A01X+154252Y+117618X0180Y         S1      
327N/C              PEX3  -AD8        A01X+154252Y+116870X0180Y         S1      
327N/C              PEX3  -AC8        A01X+154252Y+117244X0180Y         S1      
327N/C              PEX3  -AE8        A01X+154252Y+116496X0180Y         S1      
327N/C              U45   -1          A01X+167454Y+034744X0160Y0360R270 S1      
327N/C              U40   -1          A01X+155811Y+065828X0160Y0360R270 S1      
327N/C              U35   -1          A01X+121746Y+034744X0160Y0360R270 S1      
327N/C              U30   -1          A01X+110102Y+065828X0160Y0360R270 S1      
327N/C              U25   -1          A01X+076037Y+034744X0160Y0360R270 S1      
327N/C              U20   -1          A01X+064393Y+065828X0160Y0360R270 S1      
327N/C              U15   -1          A01X+030328Y+034744X0160Y0360R270 S1      
327N/C              U10   -1          A18X+022802Y+060266X0160Y0360R270 S2      
327N/C              J45   -B8         A01X+173844Y+009051X0150Y0500R090 S1      
327N/C              J45   -A15        A01X+172033Y+010705X0150Y0500R090 S1      
327N/C              J45   -A14        A01X+172033Y+010468X0150Y0500R090 S1      
327N/C              J45   -B7         A01X+173844Y+008815X0150Y0500R090 S1      
317N/C              J45   -H1   D0440UA00X+173628Y+006681X0440Y    R090 S3      
317N/C              J45   -H2   D0440UA00X+172939Y+014410X0440Y    R090 S3      
327N/C              J44   -B8         A01X+163608Y+009051X0150Y0500R090 S1      
327N/C              J44   -A15        A01X+161797Y+010705X0150Y0500R090 S1      
327N/C              J44   -A14        A01X+161797Y+010468X0150Y0500R090 S1      
327N/C              J44   -B7         A01X+163608Y+008815X0150Y0500R090 S1      
317N/C              J44   -H1   D0440UA00X+163392Y+006681X0440Y    R090 S3      
317N/C              J44   -H2   D0440UA00X+162703Y+014410X0440Y    R090 S3      
327N/C              J43   -B8         A01X+153372Y+009051X0150Y0500R090 S1      
327N/C              J43   -A15        A01X+151561Y+010705X0150Y0500R090 S1      
327N/C              J43   -A14        A01X+151561Y+010468X0150Y0500R090 S1      
327N/C              J43   -B7         A01X+153372Y+008815X0150Y0500R090 S1      
317N/C              J43   -H1   D0440UA00X+153156Y+006681X0440Y    R090 S3      
317N/C              J43   -H2   D0440UA00X+152466Y+014410X0440Y    R090 S3      
327N/C              J42   -B8         A01X+143136Y+009051X0150Y0500R090 S1      
327N/C              J42   -A15        A01X+141325Y+010705X0150Y0500R090 S1      
327N/C              J42   -A14        A01X+141325Y+010468X0150Y0500R090 S1      
327N/C              J42   -B7         A01X+143136Y+008815X0150Y0500R090 S1      
317N/C              J42   -H1   D0440UA00X+142919Y+006681X0440Y    R090 S3      
317N/C              J42   -H2   D0440UA00X+142230Y+014410X0440Y    R090 S3      
327N/C              J41   -B8         A01X+128136Y+009051X0150Y0500R090 S1      
327N/C              J41   -A15        A01X+126325Y+010705X0150Y0500R090 S1      
327N/C              J41   -A14        A01X+126325Y+010468X0150Y0500R090 S1      
327N/C              J41   -B7         A01X+128136Y+008815X0150Y0500R090 S1      
317N/C              J41   -H1   D0440UA00X+127919Y+006681X0440Y    R090 S3      
317N/C              J41   -H2   D0440UA00X+127230Y+014410X0440Y    R090 S3      
327N/C              J40   -B8         A01X+117900Y+009051X0150Y0500R090 S1      
327N/C              J40   -A15        A01X+116088Y+010705X0150Y0500R090 S1      
327N/C              J40   -A14        A01X+116088Y+010468X0150Y0500R090 S1      
327N/C              J40   -B7         A01X+117900Y+008815X0150Y0500R090 S1      
317N/C              J40   -H1   D0440UA00X+117683Y+006681X0440Y    R090 S3      
317N/C              J40   -H2   D0440UA00X+116994Y+014410X0440Y    R090 S3      
327N/C              J39   -B8         A01X+107663Y+009051X0150Y0500R090 S1      
327N/C              J39   -A15        A01X+105852Y+010705X0150Y0500R090 S1      
327N/C              J39   -A14        A01X+105852Y+010468X0150Y0500R090 S1      
327N/C              J39   -B7         A01X+107663Y+008815X0150Y0500R090 S1      
317N/C              J39   -H1   D0440UA00X+107447Y+006681X0440Y    R090 S3      
317N/C              J39   -H2   D0440UA00X+106758Y+014410X0440Y    R090 S3      
327N/C              J38   -B8         A01X+097427Y+009051X0150Y0500R090 S1      
327N/C              J38   -A15        A01X+095616Y+010705X0150Y0500R090 S1      
327N/C              J38   -A14        A01X+095616Y+010468X0150Y0500R090 S1      
327N/C              J38   -B7         A01X+097427Y+008815X0150Y0500R090 S1      
317N/C              J38   -H1   D0440UA00X+097211Y+006681X0440Y    R090 S3      
317N/C              J38   -H2   D0440UA00X+096522Y+014410X0440Y    R090 S3      
327N/C              J37   -B8         A01X+082427Y+009051X0150Y0500R090 S1      
327N/C              J37   -A15        A01X+080616Y+010705X0150Y0500R090 S1      
327N/C              J37   -A14        A01X+080616Y+010468X0150Y0500R090 S1      
327N/C              J37   -B7         A01X+082427Y+008815X0150Y0500R090 S1      
317N/C              J37   -H1   D0440UA00X+082211Y+006681X0440Y    R090 S3      
317N/C              J37   -H2   D0440UA00X+081522Y+014410X0440Y    R090 S3      
327N/C              J36   -B8         A01X+072191Y+009051X0150Y0500R090 S1      
327N/C              J36   -A15        A01X+070380Y+010705X0150Y0500R090 S1      
327N/C              J36   -A14        A01X+070380Y+010468X0150Y0500R090 S1      
327N/C              J36   -B7         A01X+072191Y+008815X0150Y0500R090 S1      
317N/C              J36   -H1   D0440UA00X+071974Y+006681X0440Y    R090 S3      
317N/C              J36   -H2   D0440UA00X+071285Y+014410X0440Y    R090 S3      
327N/C              J35   -B8         A01X+061955Y+009051X0150Y0500R090 S1      
327N/C              J35   -A15        A01X+060144Y+010705X0150Y0500R090 S1      
327N/C              J35   -A14        A01X+060144Y+010468X0150Y0500R090 S1      
327N/C              J35   -B7         A01X+061955Y+008815X0150Y0500R090 S1      
317N/C              J35   -H1   D0440UA00X+061738Y+006681X0440Y    R090 S3      
317N/C              J35   -H2   D0440UA00X+061049Y+014410X0440Y    R090 S3      
327N/C              J34   -B8         A01X+051718Y+009051X0150Y0500R090 S1      
327N/C              J34   -A15        A01X+049908Y+010705X0150Y0500R090 S1      
327N/C              J34   -A14        A01X+049908Y+010468X0150Y0500R090 S1      
327N/C              J34   -B7         A01X+051718Y+008815X0150Y0500R090 S1      
317N/C              J34   -H1   D0440UA00X+051502Y+006681X0440Y    R090 S3      
317N/C              J34   -H2   D0440UA00X+050813Y+014410X0440Y    R090 S3      
317N/C              H44   -1    D1250UA00X+180988Y+012079X1250Y         S3      
317N/C              H43   -1    D1250UA00X+179685Y+151789X1250Y         S3      
317N/C              H42   -1    D1250UA00X+002679Y+137367X1250Y         S3      
317N/C              H131  -1          A01X+083748Y+006161X1660Y1970R180 S3      
017N/C              H131  -1          A18X+083748Y+006161X1580Y    R180 S3      
017N/C                    -     D0790PA00X+083748Y+006161                       
317N/C              H130  -1          A01X+079297Y+008160X1660Y1970     S3      
017N/C              H130  -1          A18X+079297Y+008160X1580Y         S3      
017N/C                    -     D0790PA00X+079297Y+008160                       
317N/C              H129  -1          A01X+053039Y+006161X1660Y1970R180 S3      
017N/C              H129  -1          A18X+053039Y+006161X1580Y    R180 S3      
017N/C                    -     D0790PA00X+053039Y+006161                       
317N/C              H128  -1          A01X+007331Y+006161X1660Y1970R180 S3      
017N/C              H128  -1          A18X+007331Y+006161X1580Y    R180 S3      
017N/C                    -     D0790PA00X+007331Y+006161                       
317N/C              H127  -1          A01X+002882Y+008158X1660Y1970     S3      
017N/C              H127  -1          A18X+002882Y+008158X1580Y         S3      
017N/C                    -     D0790PA00X+002882Y+008158                       
317N/C              H126  -1          A01X+144457Y+006161X1660Y1970R180 S3      
017N/C              H126  -1          A18X+144457Y+006161X1580Y    R180 S3      
017N/C                    -     D0790PA00X+144457Y+006161                       
317N/C              H125  -1          A01X+154693Y+006161X1660Y1970R180 S3      
017N/C              H125  -1          A18X+154693Y+006161X1580Y    R180 S3      
017N/C                    -     D0790PA00X+154693Y+006161                       
317N/C              H124  -1          A01X+094297Y+008160X1660Y1970     S3      
017N/C              H124  -1          A18X+094297Y+008160X1580Y         S3      
017N/C                    -     D0790PA00X+094297Y+008160                       
317N/C              H123  -1          A01X+175165Y+006161X1660Y1970R180 S3      
017N/C              H123  -1          A18X+175165Y+006161X1580Y    R180 S3      
017N/C                    -     D0790PA00X+175165Y+006161                       
317N/C              H122  -1          A01X+125006Y+008160X1660Y1970     S3      
017N/C              H122  -1          A18X+125006Y+008160X1580Y         S3      
017N/C                    -     D0790PA00X+125006Y+008160                       
317N/C              H121  -1          A01X+119220Y+006161X1660Y1970R180 S3      
017N/C              H121  -1          A18X+119220Y+006161X1580Y    R180 S3      
017N/C                    -     D0790PA00X+119220Y+006161                       
317N/C              H120  -1          A01X+108984Y+006161X1660Y1970R180 S3      
017N/C              H120  -1          A18X+108984Y+006161X1580Y    R180 S3      
017N/C                    -     D0790PA00X+108984Y+006161                       
317N/C              H119  -1          A01X+069061Y+008160X1660Y1970     S3      
017N/C              H119  -1          A18X+069061Y+008160X1580Y         S3      
017N/C                    -     D0790PA00X+069061Y+008160                       
317N/C              H118  -1          A01X+038039Y+006161X1660Y1970R180 S3      
017N/C              H118  -1          A18X+038039Y+006161X1580Y    R180 S3      
017N/C                    -     D0790PA00X+038039Y+006161                       
317N/C              H117  -1          A01X+023354Y+008158X1660Y1970     S3      
017N/C              H117  -1          A18X+023354Y+008158X1580Y         S3      
017N/C                    -     D0790PA00X+023354Y+008158                       
317N/C              H116  -1          A01X+027803Y+006161X1660Y1970R180 S3      
017N/C              H116  -1          A18X+027803Y+006161X1580Y    R180 S3      
017N/C                    -     D0790PA00X+027803Y+006161                       
317N/C              H115  -1          A01X+150244Y+008158X1660Y1970     S3      
017N/C              H115  -1          A18X+150244Y+008158X1580Y         S3      
017N/C                    -     D0790PA00X+150244Y+008158                       
317N/C              H114  -1          A01X+164929Y+006161X1660Y1970R180 S3      
017N/C              H114  -1          A18X+164929Y+006161X1580Y    R180 S3      
017N/C                    -     D0790PA00X+164929Y+006161                       
317N/C              H113  -1          A01X+114770Y+008160X1660Y1970     S3      
017N/C              H113  -1          A18X+114770Y+008160X1580Y         S3      
017N/C                    -     D0790PA00X+114770Y+008160                       
317N/C              H112  -1          A01X+104534Y+008160X1660Y1970     S3      
017N/C              H112  -1          A18X+104534Y+008160X1580Y         S3      
017N/C                    -     D0790PA00X+104534Y+008160                       
317N/C              H111  -1          A01X+098748Y+006161X1660Y1970R180 S3      
017N/C              H111  -1          A18X+098748Y+006161X1580Y    R180 S3      
017N/C                    -     D0790PA00X+098748Y+006161                       
317N/C              H110  -1          A01X+058825Y+008159X1660Y1970     S3      
017N/C              H110  -1          A18X+058825Y+008159X1580Y         S3      
017N/C                    -     D0790PA00X+058825Y+008159                       
317N/C              H109  -1          A01X+063276Y+006161X1660Y1970R180 S3      
017N/C              H109  -1          A18X+063276Y+006161X1580Y    R180 S3      
017N/C                    -     D0790PA00X+063276Y+006161                       
317N/C              H108  -1          A01X+013118Y+008158X1660Y1970     S3      
017N/C              H108  -1          A18X+013118Y+008158X1580Y         S3      
017N/C                    -     D0790PA00X+013118Y+008158                       
317N/C              H107  -1          A01X+033591Y+008158X1660Y1970     S3      
017N/C              H107  -1          A18X+033591Y+008158X1580Y         S3      
017N/C                    -     D0790PA00X+033591Y+008158                       
317N/C              H106  -1          A01X+129457Y+006161X1660Y1970R180 S3      
017N/C              H106  -1          A18X+129457Y+006161X1580Y    R180 S3      
017N/C                    -     D0790PA00X+129457Y+006161                       
317N/C              H105  -1          A01X+160478Y+008160X1660Y1970     S3      
017N/C              H105  -1          A18X+160478Y+008160X1580Y         S3      
017N/C                    -     D0790PA00X+160478Y+008160                       
317N/C              H104  -1          A01X+140006Y+008160X1660Y1970     S3      
017N/C              H104  -1          A18X+140006Y+008160X1580Y         S3      
017N/C                    -     D0790PA00X+140006Y+008160                       
317N/C              H103  -1          A01X+170715Y+008160X1660Y1970     S3      
017N/C              H103  -1          A18X+170715Y+008160X1580Y         S3      
017N/C                    -     D0790PA00X+170715Y+008160                       
317N/C              H102  -1          A01X+048589Y+008160X1660Y1970     S3      
017N/C              H102  -1          A18X+048589Y+008160X1580Y         S3      
017N/C                    -     D0790PA00X+048589Y+008160                       
317N/C              H101  -1          A01X+073512Y+006161X1660Y1970R180 S3      
017N/C              H101  -1          A18X+073512Y+006161X1580Y    R180 S3      
017N/C                    -     D0790PA00X+073512Y+006161                       
317N/C              H100  -1          A01X+017567Y+006161X1660Y1970R180 S3      
017N/C              H100  -1          A18X+017567Y+006161X1580Y    R180 S3      
017N/C                    -     D0790PA00X+017567Y+006161                       
327N/C              U6    -B22        A01X+138147Y+089444X0160Y         S1      
327N/C              J33   -B8         A01X+036718Y+009051X0150Y0500R090 S1      
327N/C              J33   -A15        A01X+034907Y+010705X0150Y0500R090 S1      
327N/C              J33   -A14        A01X+034907Y+010468X0150Y0500R090 S1      
327N/C              J33   -B7         A01X+036718Y+008815X0150Y0500R090 S1      
317N/C              J33   -H1   D0440UA00X+036502Y+006681X0440Y    R090 S3      
317N/C              J33   -H2   D0440UA00X+035813Y+014410X0440Y    R090 S3      
327N/C              J32   -B8         A01X+026482Y+009051X0150Y0500R090 S1      
327N/C              J32   -A15        A01X+024671Y+010705X0150Y0500R090 S1      
327N/C              J32   -A14        A01X+024671Y+010468X0150Y0500R090 S1      
327N/C              J32   -B7         A01X+026482Y+008815X0150Y0500R090 S1      
317N/C              J32   -H1   D0440UA00X+026266Y+006681X0440Y    R090 S3      
317N/C              J32   -H2   D0440UA00X+025577Y+014410X0440Y    R090 S3      
327N/C              J31   -B8         A01X+016246Y+009051X0150Y0500R090 S1      
327N/C              J31   -A15        A01X+014435Y+010705X0150Y0500R090 S1      
327N/C              J31   -A14        A01X+014435Y+010468X0150Y0500R090 S1      
327N/C              J31   -B7         A01X+016246Y+008815X0150Y0500R090 S1      
317N/C              J31   -H1   D0440UA00X+016030Y+006681X0440Y    R090 S3      
317N/C              J31   -H2   D0440UA00X+015340Y+014410X0440Y    R090 S3      
327N/C              J30   -B8         A01X+006010Y+009051X0150Y0500R090 S1      
327N/C              J30   -A15        A01X+004199Y+010705X0150Y0500R090 S1      
327N/C              J30   -A14        A01X+004199Y+010468X0150Y0500R090 S1      
327N/C              J30   -B7         A01X+006010Y+008815X0150Y0500R090 S1      
317N/C              J30   -H1   D0440UA00X+005793Y+006681X0440Y    R090 S3      
317N/C              J30   -H2   D0440UA00X+005104Y+014410X0440Y    R090 S3      
327N/C              U96   -16         A01X+038486Y+096314X0090Y0240     S1      
327N/C              U96   -15         A01X+038682Y+096314X0090Y0240     S1      
327N/C              U96   -14         A01X+038879Y+096314X0090Y0240     S1      
327N/C              U96   -8          A01X+039076Y+095212X0090Y0240     S1      
327N/C              U96   -7          A01X+038879Y+095212X0090Y0240     S1      
327N/C              U96   -6          A01X+038682Y+095212X0090Y0240     S1      
327N/C              U95   -16         A01X+181031Y+108864X0090Y0240R180 S1      
327N/C              U95   -15         A01X+180834Y+108864X0090Y0240R180 S1      
327N/C              U95   -14         A01X+180637Y+108864X0090Y0240R180 S1      
327N/C              U95   -8          A01X+180440Y+109967X0090Y0240R180 S1      
327N/C              U95   -7          A01X+180637Y+109967X0090Y0240R180 S1      
327N/C              U95   -6          A01X+180834Y+109967X0090Y0240R180 S1      
327N/C              U94   -16         A01X+096633Y+108816X0090Y0240R180 S1      
327N/C              U94   -15         A01X+096436Y+108816X0090Y0240R180 S1      
327N/C              U94   -14         A01X+096239Y+108816X0090Y0240R180 S1      
327N/C              U94   -8          A01X+096042Y+109918X0090Y0240R180 S1      
327N/C              U94   -7          A01X+096239Y+109918X0090Y0240R180 S1      
327N/C              U94   -6          A01X+096436Y+109918X0090Y0240R180 S1      
327N/C              U90   -16         A01X+090235Y+108816X0090Y0240R180 S1      
327N/C              U90   -15         A01X+090038Y+108816X0090Y0240R180 S1      
327N/C              U90   -14         A01X+089841Y+108816X0090Y0240R180 S1      
327N/C              U90   -8          A01X+089644Y+109918X0090Y0240R180 S1      
327N/C              U90   -7          A01X+089841Y+109918X0090Y0240R180 S1      
327N/C              U90   -6          A01X+090038Y+109918X0090Y0240R180 S1      
327N/C              U87   -16         A01X+005566Y+107915X0090Y0240R180 S1      
327N/C              U87   -15         A01X+005369Y+107915X0090Y0240R180 S1      
327N/C              U87   -14         A01X+005172Y+107915X0090Y0240R180 S1      
327N/C              U87   -8          A01X+004975Y+109018X0090Y0240R180 S1      
327N/C              U87   -7          A01X+005172Y+109018X0090Y0240R180 S1      
327N/C              U87   -6          A01X+005369Y+109018X0090Y0240R180 S1      
327N/C              U86   -16         A01X+172524Y+039157X0090Y0240R090 S1      
327N/C              U86   -15         A01X+172524Y+039354X0090Y0240R090 S1      
327N/C              U86   -14         A01X+172524Y+039551X0090Y0240R090 S1      
327N/C              U86   -8          A01X+173627Y+039748X0090Y0240R090 S1      
327N/C              U86   -7          A01X+173627Y+039551X0090Y0240R090 S1      
327N/C              U86   -6          A01X+173627Y+039354X0090Y0240R090 S1      
327N/C              U85   -16         A01X+145027Y+059080X0090Y0240R270 S1      
327N/C              U85   -15         A01X+145027Y+058883X0090Y0240R270 S1      
327N/C              U85   -14         A01X+145027Y+058686X0090Y0240R270 S1      
327N/C              U85   -8          A01X+143925Y+058490X0090Y0240R270 S1      
327N/C              U85   -7          A01X+143925Y+058686X0090Y0240R270 S1      
327N/C              U85   -6          A01X+143925Y+058883X0090Y0240R270 S1      
327N/C              U84   -16         A01X+126816Y+039157X0090Y0240R090 S1      
327N/C              U84   -15         A01X+126816Y+039354X0090Y0240R090 S1      
327N/C              U84   -14         A01X+126816Y+039551X0090Y0240R090 S1      
327N/C              U84   -8          A01X+127918Y+039748X0090Y0240R090 S1      
327N/C              U84   -7          A01X+127918Y+039551X0090Y0240R090 S1      
327N/C              U84   -6          A01X+127918Y+039354X0090Y0240R090 S1      
327N/C              U83   -16         A01X+099318Y+059080X0090Y0240R270 S1      
327N/C              U83   -15         A01X+099318Y+058883X0090Y0240R270 S1      
327N/C              U83   -14         A01X+099318Y+058686X0090Y0240R270 S1      
327N/C              U83   -8          A01X+098216Y+058490X0090Y0240R270 S1      
327N/C              U83   -7          A01X+098216Y+058686X0090Y0240R270 S1      
327N/C              U83   -6          A01X+098216Y+058883X0090Y0240R270 S1      
327N/C              U82   -16         A01X+085474Y+039957X0090Y0240R090 S1      
327N/C              U82   -15         A01X+085474Y+040154X0090Y0240R090 S1      
327N/C              U82   -14         A01X+085474Y+040351X0090Y0240R090 S1      
327N/C              U82   -8          A01X+086576Y+040548X0090Y0240R090 S1      
327N/C              U82   -7          A01X+086576Y+040351X0090Y0240R090 S1      
327N/C              U82   -6          A01X+086576Y+040154X0090Y0240R090 S1      
327N/C              U81   -16         A01X+053610Y+059080X0090Y0240R270 S1      
327N/C              U81   -15         A01X+053610Y+058883X0090Y0240R270 S1      
327N/C              U81   -14         A01X+053610Y+058686X0090Y0240R270 S1      
327N/C              U81   -8          A01X+052507Y+058490X0090Y0240R270 S1      
327N/C              U81   -7          A01X+052507Y+058686X0090Y0240R270 S1      
327N/C              U81   -6          A01X+052507Y+058883X0090Y0240R270 S1      
327N/C              U80   -16         A01X+035398Y+039157X0090Y0240R090 S1      
327N/C              U80   -15         A01X+035398Y+039354X0090Y0240R090 S1      
327N/C              U80   -14         A01X+035398Y+039551X0090Y0240R090 S1      
327N/C              U80   -8          A01X+036501Y+039748X0090Y0240R090 S1      
327N/C              U80   -7          A01X+036501Y+039551X0090Y0240R090 S1      
327N/C              U80   -6          A01X+036501Y+039354X0090Y0240R090 S1      
327N/C              U79   -16         A01X+007901Y+059080X0090Y0240R270 S1      
327N/C              U79   -15         A01X+007901Y+058883X0090Y0240R270 S1      
327N/C              U79   -14         A01X+007901Y+058686X0090Y0240R270 S1      
327N/C              U79   -8          A01X+006799Y+058490X0090Y0240R270 S1      
327N/C              U79   -7          A01X+006799Y+058686X0090Y0240R270 S1      
327N/C              U79   -6          A01X+006799Y+058883X0090Y0240R270 S1      
327N/C              U78   -16         A01X+177124Y+017734X0090Y0240R180 S1      
327N/C              U78   -15         A01X+176928Y+017734X0090Y0240R180 S1      
327N/C              U78   -14         A01X+176731Y+017734X0090Y0240R180 S1      
327N/C              U78   -8          A01X+176534Y+018836X0090Y0240R180 S1      
327N/C              U78   -7          A01X+176731Y+018836X0090Y0240R180 S1      
327N/C              U78   -6          A01X+176928Y+018836X0090Y0240R180 S1      
327N/C              U77   -16         A01X+166888Y+017734X0090Y0240R180 S1      
327N/C              U77   -15         A01X+166691Y+017734X0090Y0240R180 S1      
327N/C              U77   -14         A01X+166494Y+017734X0090Y0240R180 S1      
327N/C              U77   -8          A01X+166298Y+018836X0090Y0240R180 S1      
327N/C              U77   -7          A01X+166494Y+018836X0090Y0240R180 S1      
327N/C              U77   -6          A01X+166691Y+018836X0090Y0240R180 S1      
327N/C              U76   -16         A01X+156652Y+017734X0090Y0240R180 S1      
327N/C              U76   -15         A01X+156455Y+017734X0090Y0240R180 S1      
327N/C              U76   -14         A01X+156258Y+017734X0090Y0240R180 S1      
327N/C              U76   -8          A01X+156061Y+018836X0090Y0240R180 S1      
327N/C              U76   -7          A01X+156258Y+018836X0090Y0240R180 S1      
327N/C              U76   -6          A01X+156455Y+018836X0090Y0240R180 S1      
327N/C              U75   -16         A01X+146416Y+017734X0090Y0240R180 S1      
327N/C              U75   -15         A01X+146219Y+017734X0090Y0240R180 S1      
327N/C              U75   -14         A01X+146022Y+017734X0090Y0240R180 S1      
327N/C              U75   -8          A01X+145825Y+018836X0090Y0240R180 S1      
327N/C              U75   -7          A01X+146022Y+018836X0090Y0240R180 S1      
327N/C              U75   -6          A01X+146219Y+018836X0090Y0240R180 S1      
327N/C              U74   -16         A01X+131416Y+017734X0090Y0240R180 S1      
327N/C              U74   -15         A01X+131219Y+017734X0090Y0240R180 S1      
327N/C              U74   -14         A01X+131022Y+017734X0090Y0240R180 S1      
327N/C              U74   -8          A01X+130825Y+018836X0090Y0240R180 S1      
327N/C              U74   -7          A01X+131022Y+018836X0090Y0240R180 S1      
327N/C              U74   -6          A01X+131219Y+018836X0090Y0240R180 S1      
327N/C              U73   -16         A01X+121180Y+017734X0090Y0240R180 S1      
327N/C              U73   -15         A01X+120983Y+017734X0090Y0240R180 S1      
327N/C              U73   -14         A01X+120786Y+017734X0090Y0240R180 S1      
327N/C              U73   -8          A01X+120589Y+018836X0090Y0240R180 S1      
327N/C              U73   -7          A01X+120786Y+018836X0090Y0240R180 S1      
327N/C              U73   -6          A01X+120983Y+018836X0090Y0240R180 S1      
327N/C              U72   -16         A01X+110943Y+017734X0090Y0240R180 S1      
327N/C              U72   -15         A01X+110746Y+017734X0090Y0240R180 S1      
327N/C              U72   -14         A01X+110550Y+017734X0090Y0240R180 S1      
327N/C              U72   -8          A01X+110353Y+018836X0090Y0240R180 S1      
327N/C              U72   -7          A01X+110550Y+018836X0090Y0240R180 S1      
327N/C              U72   -6          A01X+110746Y+018836X0090Y0240R180 S1      
327N/C              U71   -16         A01X+100707Y+017734X0090Y0240R180 S1      
327N/C              U71   -15         A01X+100510Y+017734X0090Y0240R180 S1      
327N/C              U71   -14         A01X+100313Y+017734X0090Y0240R180 S1      
327N/C              U71   -8          A01X+100116Y+018836X0090Y0240R180 S1      
327N/C              U71   -7          A01X+100313Y+018836X0090Y0240R180 S1      
327N/C              U71   -6          A01X+100510Y+018836X0090Y0240R180 S1      
327N/C              U62   -16         A01X+085707Y+017734X0090Y0240R180 S1      
327N/C              U62   -15         A01X+085510Y+017734X0090Y0240R180 S1      
327N/C              U62   -14         A01X+085313Y+017734X0090Y0240R180 S1      
327N/C              U62   -8          A01X+085116Y+018836X0090Y0240R180 S1      
327N/C              U62   -7          A01X+085313Y+018836X0090Y0240R180 S1      
327N/C              U62   -6          A01X+085510Y+018836X0090Y0240R180 S1      
327N/C              U61   -16         A01X+075471Y+017734X0090Y0240R180 S1      
327N/C              U61   -15         A01X+075274Y+017734X0090Y0240R180 S1      
327N/C              U61   -14         A01X+075077Y+017734X0090Y0240R180 S1      
327N/C              U61   -8          A01X+074880Y+018836X0090Y0240R180 S1      
327N/C              U61   -7          A01X+075077Y+018836X0090Y0240R180 S1      
327N/C              U61   -6          A01X+075274Y+018836X0090Y0240R180 S1      
327N/C              U60   -16         A01X+065235Y+017734X0090Y0240R180 S1      
327N/C              U60   -15         A01X+065038Y+017734X0090Y0240R180 S1      
327N/C              U60   -14         A01X+064841Y+017734X0090Y0240R180 S1      
327N/C              U60   -8          A01X+064644Y+018836X0090Y0240R180 S1      
327N/C              U60   -7          A01X+064841Y+018836X0090Y0240R180 S1      
327N/C              U60   -6          A01X+065038Y+018836X0090Y0240R180 S1      
327N/C              U59   -16         A01X+054998Y+017734X0090Y0240R180 S1      
327N/C              U59   -15         A01X+054802Y+017734X0090Y0240R180 S1      
327N/C              U59   -14         A01X+054605Y+017734X0090Y0240R180 S1      
327N/C              U59   -8          A01X+054408Y+018836X0090Y0240R180 S1      
327N/C              U59   -7          A01X+054605Y+018836X0090Y0240R180 S1      
327N/C              U59   -6          A01X+054802Y+018836X0090Y0240R180 S1      
327N/C              U56   -16         A01X+039998Y+017734X0090Y0240R180 S1      
327N/C              U56   -15         A01X+039802Y+017734X0090Y0240R180 S1      
327N/C              U56   -14         A01X+039605Y+017734X0090Y0240R180 S1      
327N/C              U56   -8          A01X+039408Y+018836X0090Y0240R180 S1      
327N/C              U56   -7          A01X+039605Y+018836X0090Y0240R180 S1      
327N/C              U56   -6          A01X+039802Y+018836X0090Y0240R180 S1      
317N/C              J9    -Z10  D0122PA00X+172949Y+145272X0282Y    R180 S3      
317N/C              J9    -Y9   D0122PA00X+172083Y+145862X0282Y    R180 S3      
317N/C              J9    -X9   D0122PA00X+172083Y+146374X0282Y    R180 S3      
317N/C              J9    -X10  D0122PA00X+172949Y+146295X0282Y    R180 S3      
317N/C              J9    -W10  D0122PA00X+172949Y+146807X0282Y    R180 S3      
317N/C              J9    -V9   D0122PA00X+172083Y+147398X0282Y    R180 S3      
317N/C              J9    -U9   D0122PA00X+172083Y+147910X0282Y    R180 S3      
317N/C              J9    -U10  D0122PA00X+172949Y+147831X0282Y    R180 S3      
317N/C              J9    -T10  D0122PA00X+172949Y+148343X0282Y    R180 S3      
317N/C              J9    -S9   D0122PA00X+172083Y+148933X0282Y    R180 S3      
317N/C              J9    -R9   D0122PA00X+172083Y+149445X0282Y    R180 S3      
317N/C              J9    -R10  D0122PA00X+172949Y+149366X0282Y    R180 S3      
317N/C              J9    -Q10  D0122PA00X+172949Y+149878X0282Y    R180 S3      
317N/C              J9    -P9   D0122PA00X+172083Y+150468X0282Y    R180 S3      
317N/C              J9    -O9   D0122PA00X+172083Y+150980X0282Y    R180 S3      
317N/C              J9    -O10  D0122PA00X+172949Y+150902X0282Y    R180 S3      
317N/C              J9    -N10  D0122PA00X+172949Y+151413X0282Y    R180 S3      
317N/C              J9    -M9   D0122PA00X+172083Y+156098X0282Y    R180 S3      
317N/C              J9    -L9   D0122PA00X+172083Y+156610X0282Y    R180 S3      
317N/C              J9    -L10  D0122PA00X+172949Y+156532X0282Y    R180 S3      
317N/C              J9    -K10  D0122PA00X+172949Y+157043X0282Y    R180 S3      
317N/C              J9    -J9   D0122PA00X+172083Y+157634X0282Y    R180 S3      
317N/C              J9    -I9   D0122PA00X+172083Y+158146X0282Y    R180 S3      
317N/C              J9    -H10  D0122PA00X+172949Y+158579X0282Y    R180 S3      
317N/C              J9    -F9   D0122PA00X+172083Y+159681X0282Y    R180 S3      
317N/C              J9    -F10  D0122PA00X+172949Y+159602X0282Y    R180 S3      
317N/C              J9    -E10  D0122PA00X+172949Y+160114X0282Y    R180 S3      
317N/C              J9    -C9   D0122PA00X+172083Y+161217X0282Y    R180 S3      
317N/C              J9    -C10  D0122PA00X+172949Y+161138X0282Y    R180 S3      
317N/C              J9    -B10  D0122PA00X+172949Y+161650X0282Y    R180 S3      
317N/C              J9    -Z8   D0122PA00X+171216Y+145272X0282Y    R180 S3      
317N/C              J9    -Z6   D0122PA00X+169484Y+145272X0282Y    R180 S3      
317N/C              J9    -A5   D0122PA00X+168618Y+162240X0282Y    R180 S3      
317N/C              J9    -Z4   D0122PA00X+167752Y+145272X0282Y    R180 S3      
317N/C              J9    -A3   D0122PA00X+166886Y+162240X0282Y    R180 S3      
317N/C              J9    -Z2   D0122PA00X+166020Y+145272X0282Y    R180 S3      
317N/C              J9    -A1   D0122PA00X+165154Y+162240X0282Y0282R180 S3      
317N/C              J7    -Z10  D0122PA00X+120980Y+145272X0282Y    R180 S3      
317N/C              J7    -Y9   D0122PA00X+120114Y+145862X0282Y    R180 S3      
317N/C              J7    -X9   D0122PA00X+120114Y+146374X0282Y    R180 S3      
317N/C              J7    -X10  D0122PA00X+120980Y+146295X0282Y    R180 S3      
317N/C              J7    -W10  D0122PA00X+120980Y+146807X0282Y    R180 S3      
317N/C              J7    -V9   D0122PA00X+120114Y+147398X0282Y    R180 S3      
317N/C              J7    -U9   D0122PA00X+120114Y+147910X0282Y    R180 S3      
317N/C              J7    -U10  D0122PA00X+120980Y+147831X0282Y    R180 S3      
317N/C              J7    -T10  D0122PA00X+120980Y+148343X0282Y    R180 S3      
317N/C              J7    -S9   D0122PA00X+120114Y+148933X0282Y    R180 S3      
317N/C              J7    -R9   D0122PA00X+120114Y+149445X0282Y    R180 S3      
317N/C              J7    -R10  D0122PA00X+120980Y+149366X0282Y    R180 S3      
317N/C              J7    -Q10  D0122PA00X+120980Y+149878X0282Y    R180 S3      
317N/C              J7    -P9   D0122PA00X+120114Y+150468X0282Y    R180 S3      
317N/C              J7    -O9   D0122PA00X+120114Y+150980X0282Y    R180 S3      
317N/C              J7    -O10  D0122PA00X+120980Y+150902X0282Y    R180 S3      
317N/C              J7    -N10  D0122PA00X+120980Y+151413X0282Y    R180 S3      
317N/C              J7    -M9   D0122PA00X+120114Y+156098X0282Y    R180 S3      
317N/C              J7    -L9   D0122PA00X+120114Y+156610X0282Y    R180 S3      
317N/C              J7    -L10  D0122PA00X+120980Y+156532X0282Y    R180 S3      
317N/C              J7    -K10  D0122PA00X+120980Y+157043X0282Y    R180 S3      
317N/C              J7    -J9   D0122PA00X+120114Y+157634X0282Y    R180 S3      
317N/C              J7    -I9   D0122PA00X+120114Y+158146X0282Y    R180 S3      
317N/C              J7    -I10  D0122PA00X+120980Y+158067X0282Y    R180 S3      
317N/C              J7    -H10  D0122PA00X+120980Y+158579X0282Y    R180 S3      
317N/C              J7    -G9   D0122PA00X+120114Y+159169X0282Y    R180 S3      
317N/C              J7    -F9   D0122PA00X+120114Y+159681X0282Y    R180 S3      
317N/C              J7    -F10  D0122PA00X+120980Y+159602X0282Y    R180 S3      
317N/C              J7    -E10  D0122PA00X+120980Y+160114X0282Y    R180 S3      
317N/C              J7    -D9   D0122PA00X+120114Y+160705X0282Y    R180 S3      
317N/C              J7    -C9   D0122PA00X+120114Y+161217X0282Y    R180 S3      
317N/C              J7    -C10  D0122PA00X+120980Y+161138X0282Y    R180 S3      
317N/C              J7    -B10  D0122PA00X+120980Y+161650X0282Y    R180 S3      
317N/C              J7    -A9   D0122PA00X+120114Y+162240X0282Y    R180 S3      
317N/C              J7    -Z8   D0122PA00X+119248Y+145272X0282Y    R180 S3      
317N/C              J7    -Z6   D0122PA00X+117516Y+145272X0282Y    R180 S3      
317N/C              J7    -Z4   D0122PA00X+115783Y+145272X0282Y    R180 S3      
317N/C              J7    -Z2   D0122PA00X+114051Y+145272X0282Y    R180 S3      
317N/C              J5    -Y9   D0122PA00X+069886Y+145862X0282Y    R180 S3      
317N/C              J5    -X9   D0122PA00X+069886Y+146374X0282Y    R180 S3      
317N/C              J5    -X10  D0122PA00X+070752Y+146295X0282Y    R180 S3      
317N/C              J5    -W10  D0122PA00X+070752Y+146807X0282Y    R180 S3      
317N/C              J5    -V9   D0122PA00X+069886Y+147398X0282Y    R180 S3      
317N/C              J5    -U9   D0122PA00X+069886Y+147910X0282Y    R180 S3      
317N/C              J5    -U10  D0122PA00X+070752Y+147831X0282Y    R180 S3      
317N/C              J5    -T10  D0122PA00X+070752Y+148343X0282Y    R180 S3      
317N/C              J5    -S9   D0122PA00X+069886Y+148933X0282Y    R180 S3      
317N/C              J5    -R9   D0122PA00X+069886Y+149445X0282Y    R180 S3      
317N/C              J5    -R10  D0122PA00X+070752Y+149366X0282Y    R180 S3      
317N/C              J5    -Q10  D0122PA00X+070752Y+149878X0282Y    R180 S3      
317N/C              J5    -P9   D0122PA00X+069886Y+150468X0282Y    R180 S3      
317N/C              J5    -O9   D0122PA00X+069886Y+150980X0282Y    R180 S3      
317N/C              J5    -O10  D0122PA00X+070752Y+150902X0282Y    R180 S3      
317N/C              J5    -N10  D0122PA00X+070752Y+151413X0282Y    R180 S3      
317N/C              J5    -M9   D0122PA00X+069886Y+156098X0282Y    R180 S3      
317N/C              J5    -L9   D0122PA00X+069886Y+156610X0282Y    R180 S3      
317N/C              J5    -L10  D0122PA00X+070752Y+156532X0282Y    R180 S3      
317N/C              J5    -K10  D0122PA00X+070752Y+157043X0282Y    R180 S3      
317N/C              J5    -J9   D0122PA00X+069886Y+157634X0282Y    R180 S3      
317N/C              J5    -I9   D0122PA00X+069886Y+158146X0282Y    R180 S3      
317N/C              J5    -F10  D0122PA00X+070752Y+159602X0282Y    R180 S3      
317N/C              J5    -E10  D0122PA00X+070752Y+160114X0282Y    R180 S3      
317N/C              J5    -C10  D0122PA00X+070752Y+161138X0282Y    R180 S3      
317N/C              J5    -B10  D0122PA00X+070752Y+161650X0282Y    R180 S3      
317N/C              J14   -Y9   D0122PA00X+154760Y+145862X0282Y    R180 S3      
317N/C              J14   -X9   D0122PA00X+154760Y+146374X0282Y    R180 S3      
317N/C              J14   -X10  D0122PA00X+155626Y+146295X0282Y    R180 S3      
317N/C              J14   -W10  D0122PA00X+155626Y+146807X0282Y    R180 S3      
317N/C              J14   -V9   D0122PA00X+154760Y+147398X0282Y    R180 S3      
317N/C              J14   -U9   D0122PA00X+154760Y+147910X0282Y    R180 S3      
317N/C              J14   -U10  D0122PA00X+155626Y+147831X0282Y    R180 S3      
317N/C              J14   -T10  D0122PA00X+155626Y+148343X0282Y    R180 S3      
317N/C              J14   -S9   D0122PA00X+154760Y+148933X0282Y    R180 S3      
317N/C              J14   -R9   D0122PA00X+154760Y+149445X0282Y    R180 S3      
317N/C              J14   -R10  D0122PA00X+155626Y+149366X0282Y    R180 S3      
317N/C              J14   -Q10  D0122PA00X+155626Y+149878X0282Y    R180 S3      
317N/C              J14   -P9   D0122PA00X+154760Y+150468X0282Y    R180 S3      
317N/C              J14   -O9   D0122PA00X+154760Y+150980X0282Y    R180 S3      
317N/C              J14   -O10  D0122PA00X+155626Y+150902X0282Y    R180 S3      
317N/C              J14   -N10  D0122PA00X+155626Y+151413X0282Y    R180 S3      
317N/C              J14   -M9   D0122PA00X+154760Y+156098X0282Y    R180 S3      
317N/C              J14   -L9   D0122PA00X+154760Y+156610X0282Y    R180 S3      
317N/C              J14   -L10  D0122PA00X+155626Y+156532X0282Y    R180 S3      
317N/C              J14   -K10  D0122PA00X+155626Y+157043X0282Y    R180 S3      
317N/C              J14   -J9   D0122PA00X+154760Y+157634X0282Y    R180 S3      
317N/C              J14   -I9   D0122PA00X+154760Y+158146X0282Y    R180 S3      
317N/C              J14   -F10  D0122PA00X+155626Y+159602X0282Y    R180 S3      
317N/C              J14   -E10  D0122PA00X+155626Y+160114X0282Y    R180 S3      
317N/C              J14   -C10  D0122PA00X+155626Y+161138X0282Y    R180 S3      
317N/C              J14   -B10  D0122PA00X+155626Y+161650X0282Y    R180 S3      
317N/C              J14   -A5   D0122PA00X+151295Y+162240X0282Y    R180 S3      
317N/C              J13   -Y9   D0122PA00X+137437Y+145862X0282Y    R180 S3      
317N/C              J13   -X9   D0122PA00X+137437Y+146374X0282Y    R180 S3      
317N/C              J13   -X10  D0122PA00X+138303Y+146295X0282Y    R180 S3      
317N/C              J13   -W10  D0122PA00X+138303Y+146807X0282Y    R180 S3      
317N/C              J13   -V9   D0122PA00X+137437Y+147398X0282Y    R180 S3      
317N/C              J13   -U9   D0122PA00X+137437Y+147910X0282Y    R180 S3      
317N/C              J13   -U10  D0122PA00X+138303Y+147831X0282Y    R180 S3      
317N/C              J13   -T10  D0122PA00X+138303Y+148343X0282Y    R180 S3      
317N/C              J13   -S9   D0122PA00X+137437Y+148933X0282Y    R180 S3      
317N/C              J13   -R9   D0122PA00X+137437Y+149445X0282Y    R180 S3      
317N/C              J13   -R10  D0122PA00X+138303Y+149366X0282Y    R180 S3      
317N/C              J13   -Q10  D0122PA00X+138303Y+149878X0282Y    R180 S3      
317N/C              J13   -P9   D0122PA00X+137437Y+150468X0282Y    R180 S3      
317N/C              J13   -O9   D0122PA00X+137437Y+150980X0282Y    R180 S3      
317N/C              J13   -O10  D0122PA00X+138303Y+150902X0282Y    R180 S3      
317N/C              J13   -N10  D0122PA00X+138303Y+151413X0282Y    R180 S3      
317N/C              J13   -M9   D0122PA00X+137437Y+156098X0282Y    R180 S3      
317N/C              J13   -L9   D0122PA00X+137437Y+156610X0282Y    R180 S3      
317N/C              J13   -L10  D0122PA00X+138303Y+156532X0282Y    R180 S3      
317N/C              J13   -K10  D0122PA00X+138303Y+157043X0282Y    R180 S3      
317N/C              J13   -J9   D0122PA00X+137437Y+157634X0282Y    R180 S3      
317N/C              J13   -I9   D0122PA00X+137437Y+158146X0282Y    R180 S3      
317N/C              J13   -I10  D0122PA00X+138303Y+158067X0282Y    R180 S3      
317N/C              J13   -H10  D0122PA00X+138303Y+158579X0282Y    R180 S3      
317N/C              J13   -G9   D0122PA00X+137437Y+159169X0282Y    R180 S3      
317N/C              J13   -F9   D0122PA00X+137437Y+159681X0282Y    R180 S3      
317N/C              J13   -F10  D0122PA00X+138303Y+159602X0282Y    R180 S3      
317N/C              J13   -E10  D0122PA00X+138303Y+160114X0282Y    R180 S3      
317N/C              J13   -D9   D0122PA00X+137437Y+160705X0282Y    R180 S3      
317N/C              J13   -C9   D0122PA00X+137437Y+161217X0282Y    R180 S3      
317N/C              J13   -C10  D0122PA00X+138303Y+161138X0282Y    R180 S3      
317N/C              J13   -B10  D0122PA00X+138303Y+161650X0282Y    R180 S3      
317N/C              J13   -Z6   D0122PA00X+134839Y+145272X0282Y    R180 S3      
317N/C              J13   -Z4   D0122PA00X+133106Y+145272X0282Y    R180 S3      
327N/C              U98   -36         A01X+055829Y+083440X0110Y0540     S1      
327N/C              U98   -60         A01X+052690Y+080498X0110Y0540R090 S1      
327N/C              U98   -59         A01X+052690Y+080694X0110Y0540R090 S1      
327N/C              U98   -58         A01X+052690Y+080891X0110Y0540R090 S1      
327N/C              U98   -57         A01X+052690Y+081088X0110Y0540R090 S1      
327N/C              U98   -55         A01X+052690Y+081482X0110Y0540R090 S1      
327N/C              U98   -54         A01X+052690Y+081679X0110Y0540R090 S1      
327N/C              U98   -53         A01X+052690Y+081876X0110Y0540R090 S1      
327N/C              U98   -46         A01X+053861Y+083440X0110Y0540     S1      
327N/C              U98   -45         A01X+054058Y+083440X0110Y0540     S1      
327N/C              U98   -44         A01X+054255Y+083440X0110Y0540     S1      
327N/C              U98   -43         A01X+054452Y+083440X0110Y0540     S1      
327N/C              U98   -41         A01X+054845Y+083440X0110Y0540     S1      
327N/C              U98   -40         A01X+055042Y+083440X0110Y0540     S1      
327N/C              U98   -34         A01X+056223Y+083440X0110Y0540     S1      
327N/C              U98   -33         A01X+056420Y+083440X0110Y0540     S1      
327N/C              U98   -32         A01X+057198Y+082663X0110Y0540R090 S1      
327N/C              U98   -30         A01X+057198Y+082269X0110Y0540R090 S1      
327N/C              U98   -29         A01X+057198Y+082072X0110Y0540R090 S1      
327N/C              U98   -28         A01X+057198Y+081876X0110Y0540R090 S1      
327N/C              U98   -24         A01X+057198Y+081088X0110Y0540R090 S1      
327N/C              U98   -23         A01X+057198Y+080891X0110Y0540R090 S1      
327N/C              U98   -22         A01X+057198Y+080694X0110Y0540R090 S1      
327N/C              U98   -21         A01X+057198Y+080498X0110Y0540R090 S1      
327N/C              U98   -19         A01X+057198Y+080104X0110Y0540R090 S1      
327N/C              U98   -18         A01X+057198Y+079907X0110Y0540R090 S1      
327N/C              U70   -36         A01X+152305Y+096176X0110Y0540     S1      
327N/C              U70   -60         A01X+149166Y+093233X0110Y0540R090 S1      
327N/C              U70   -59         A01X+149166Y+093430X0110Y0540R090 S1      
327N/C              U70   -58         A01X+149166Y+093626X0110Y0540R090 S1      
327N/C              U70   -57         A01X+149166Y+093823X0110Y0540R090 S1      
327N/C              U70   -55         A01X+149166Y+094217X0110Y0540R090 S1      
327N/C              U70   -54         A01X+149166Y+094414X0110Y0540R090 S1      
327N/C              U70   -53         A01X+149166Y+094611X0110Y0540R090 S1      
327N/C              U70   -46         A01X+150337Y+096176X0110Y0540     S1      
327N/C              U70   -45         A01X+150534Y+096176X0110Y0540     S1      
327N/C              U70   -44         A01X+150730Y+096176X0110Y0540     S1      
327N/C              U70   -43         A01X+150927Y+096176X0110Y0540     S1      
327N/C              U70   -41         A01X+151321Y+096176X0110Y0540     S1      
327N/C              U70   -40         A01X+151518Y+096176X0110Y0540     S1      
327N/C              U70   -34         A01X+152699Y+096176X0110Y0540     S1      
327N/C              U70   -33         A01X+152896Y+096176X0110Y0540     S1      
327N/C              U70   -32         A01X+153673Y+095398X0110Y0540R090 S1      
327N/C              U70   -30         A01X+153673Y+095004X0110Y0540R090 S1      
327N/C              U70   -29         A01X+153673Y+094808X0110Y0540R090 S1      
327N/C              U70   -28         A01X+153673Y+094611X0110Y0540R090 S1      
327N/C              U70   -24         A01X+153673Y+093823X0110Y0540R090 S1      
327N/C              U70   -23         A01X+153673Y+093626X0110Y0540R090 S1      
327N/C              U70   -22         A01X+153673Y+093430X0110Y0540R090 S1      
327N/C              U70   -21         A01X+153673Y+093233X0110Y0540R090 S1      
327N/C              U70   -19         A01X+153673Y+092839X0110Y0540R090 S1      
327N/C              U70   -18         A01X+153673Y+092642X0110Y0540R090 S1      
327N/C              U362  -1          A01X+087073Y+072718X0400Y0150     S1      
327N/C              U358  -3          A01X+094609Y+071990X0220Y0560     S1      
327N/C              U350  -20         A01X+137402Y+057934X0160Y0540R270 S1      
327N/C              U350  -19         A01X+137402Y+057678X0160Y0540R270 S1      
327N/C              U350  -18         A01X+137402Y+057422X0160Y0540R270 S1      
327N/C              U350  -17         A01X+137402Y+057166X0160Y0540R270 S1      
327N/C              U349  -20         A01X+137402Y+062584X0160Y0540R270 S1      
327N/C              U349  -19         A01X+137402Y+062328X0160Y0540R270 S1      
327N/C              U349  -18         A01X+137402Y+062072X0160Y0540R270 S1      
327N/C              U349  -17         A01X+137402Y+061816X0160Y0540R270 S1      
327N/C              U348  -20         A01X+137402Y+067034X0160Y0540R270 S1      
327N/C              U348  -19         A01X+137402Y+066778X0160Y0540R270 S1      
327N/C              U348  -18         A01X+137402Y+066522X0160Y0540R270 S1      
327N/C              U348  -17         A01X+137402Y+066266X0160Y0540R270 S1      
327N/C              U347  -20         A01X+137402Y+071734X0160Y0540R270 S1      
327N/C              U347  -19         A01X+137402Y+071478X0160Y0540R270 S1      
327N/C              U347  -18         A01X+137402Y+071222X0160Y0540R270 S1      
327N/C              U347  -17         A01X+137402Y+070966X0160Y0540R270 S1      
327N/C              U346  -20         A01X+146502Y+070184X0160Y0540R270 S1      
327N/C              U346  -19         A01X+146502Y+069928X0160Y0540R270 S1      
327N/C              U346  -18         A01X+146502Y+069672X0160Y0540R270 S1      
327N/C              U346  -17         A01X+146502Y+069416X0160Y0540R270 S1      
327N/C              U345  -20         A01X+148202Y+078734X0160Y0540R270 S1      
327N/C              U345  -19         A01X+148202Y+078478X0160Y0540R270 S1      
327N/C              U345  -18         A01X+148202Y+078222X0160Y0540R270 S1      
327N/C              U345  -17         A01X+148202Y+077966X0160Y0540R270 S1      
327N/C              U344  -20         A01X+146502Y+074584X0160Y0540R270 S1      
327N/C              U344  -19         A01X+146502Y+074328X0160Y0540R270 S1      
327N/C              U344  -18         A01X+146502Y+074072X0160Y0540R270 S1      
327N/C              U344  -17         A01X+146502Y+073816X0160Y0540R270 S1      
327N/C              U343  -20         A01X+148202Y+083134X0160Y0540R270 S1      
327N/C              U343  -19         A01X+148202Y+082878X0160Y0540R270 S1      
327N/C              U343  -18         A01X+148202Y+082622X0160Y0540R270 S1      
327N/C              U343  -17         A01X+148202Y+082366X0160Y0540R270 S1      
327N/C              U336  -1          A01X+128594Y+090467X0160Y0360     S1      
327N/C              U321  -14         A01X+142962Y+088030X0320Y0750R270 S1      
327N/C              U321  -13         A01X+142962Y+088530X0320Y0750R270 S1      
327N/C              U321  -12         A01X+142962Y+089030X0320Y0750R270 S1      
327N/C              U321  -11         A01X+142962Y+089530X0320Y0750R270 S1      
327N/C              U321  -6          A01X+146804Y+089530X0320Y0750R090 S1      
327N/C              U321  -5          A01X+146804Y+089030X0320Y0750R090 S1      
327N/C              U321  -4          A01X+146804Y+088530X0320Y0750R090 S1      
327N/C              U320  -14         A01X+051544Y+088030X0320Y0750R270 S1      
327N/C              U320  -13         A01X+051544Y+088530X0320Y0750R270 S1      
327N/C              U320  -12         A01X+051544Y+089030X0320Y0750R270 S1      
327N/C              U320  -11         A01X+051544Y+089530X0320Y0750R270 S1      
327N/C              U320  -6          A01X+055387Y+089530X0320Y0750R090 S1      
327N/C              U320  -5          A01X+055387Y+089030X0320Y0750R090 S1      
327N/C              U320  -4          A01X+055387Y+088530X0320Y0750R090 S1      
327N/C              U319  -14         A01X+097283Y+088030X0320Y0750R270 S1      
327N/C              U319  -13         A01X+097283Y+088530X0320Y0750R270 S1      
327N/C              U319  -12         A01X+097283Y+089030X0320Y0750R270 S1      
327N/C              U319  -11         A01X+097283Y+089530X0320Y0750R270 S1      
327N/C              U319  -6          A01X+101126Y+089530X0320Y0750R090 S1      
327N/C              U319  -5          A01X+101126Y+089030X0320Y0750R090 S1      
327N/C              U319  -4          A01X+101126Y+088530X0320Y0750R090 S1      
327N/C              U317  -14         A01X+005850Y+088030X0320Y0750R270 S1      
327N/C              U317  -13         A01X+005850Y+088530X0320Y0750R270 S1      
327N/C              U317  -12         A01X+005850Y+089030X0320Y0750R270 S1      
327N/C              U317  -11         A01X+005850Y+089530X0320Y0750R270 S1      
327N/C              U317  -6          A01X+009693Y+089530X0320Y0750R090 S1      
327N/C              U317  -5          A01X+009693Y+089030X0320Y0750R090 S1      
327N/C              U317  -4          A01X+009693Y+088530X0320Y0750R090 S1      
327N/C              U117  -B7         A01X+090196Y+056699X0110Y0180R180 S1      
327N/C              U117  -B5         A01X+089802Y+056699X0110Y0180R180 S1      
327N/C              U117  -B44        A01X+088768Y+056945X0110Y0180R090 S1      
327N/C              U117  -B41        A01X+088768Y+057536X0110Y0180R090 S1      
327N/C              U117  -B39        A01X+088768Y+057929X0110Y0180R090 S1      
327N/C              U117  -B37        A01X+088768Y+058323X0110Y0180R090 S1      
327N/C              U117  -B36        A01X+088768Y+058520X0110Y0180R090 S1      
327N/C              U117  -B34        A01X+088768Y+058914X0110Y0180R090 S1      
327N/C              U117  -B33        A01X+089014Y+059160X0110Y0180     S1      
327N/C              U117  -B31        A01X+089408Y+059160X0110Y0180     S1      
327N/C              U117  -B30        A01X+089605Y+059160X0110Y0180     S1      
327N/C              U117  -B3         A01X+089408Y+056699X0110Y0180R180 S1      
327N/C              U117  -B28        A01X+089999Y+059160X0110Y0180     S1      
327N/C              U117  -B26        A01X+090392Y+059160X0110Y0180     S1      
327N/C              U117  -B25        A01X+090589Y+059160X0110Y0180     S1      
327N/C              U117  -B24        A01X+090786Y+059160X0110Y0180     S1      
327N/C              U117  -B22        A01X+091229Y+058914X0110Y0180R090 S1      
327N/C              U117  -B20        A01X+091229Y+058520X0110Y0180R090 S1      
327N/C              U117  -B2         A01X+089211Y+056699X0110Y0180R180 S1      
327N/C              U117  -B18        A01X+091229Y+058126X0110Y0180R090 S1      
327N/C              U117  -B16        A01X+091229Y+057732X0110Y0180R090 S1      
327N/C              U117  -B13        A01X+091229Y+057142X0110Y0180R090 S1      
327N/C              U117  -A15        A01X+091524Y+056650X0070Y0220R090 S1      
327N/C              U117  -A35        A01X+090097Y+059455X0070Y0220     S1      
327N/C              U117  -A36        A01X+089900Y+059455X0070Y0220     S1      
327N/C              U117  -A37        A01X+089704Y+059455X0070Y0220     S1      
327N/C              U117  -A38        A01X+089507Y+059455X0070Y0220     S1      
327N/C              U117  -A39        A01X+089310Y+059455X0070Y0220     S1      
327N/C              U117  -A40        A01X+089113Y+059455X0070Y0220     S1      
327N/C              U117  -A41        A01X+088916Y+059455X0070Y0220     S1      
327N/C              U117  -A42        A01X+088719Y+059455X0070Y0220     S1      
327N/C              U117  -A43        A01X+088473Y+059209X0070Y0220R090 S1      
327N/C              U117  -A44        A01X+088473Y+059012X0070Y0220R090 S1      
327N/C              U117  -A45        A01X+088473Y+058815X0070Y0220R090 S1      
327N/C              U117  -A46        A01X+088473Y+058618X0070Y0220R090 S1      
327N/C              U117  -A47        A01X+088473Y+058421X0070Y0220R090 S1      
327N/C              U117  -A48        A01X+088473Y+058225X0070Y0220R090 S1      
327N/C              U117  -A49        A01X+088473Y+058028X0070Y0220R090 S1      
327N/C              U117  -A50        A01X+088473Y+057831X0070Y0220R090 S1      
327N/C              U117  -A51        A01X+088473Y+057634X0070Y0220R090 S1      
327N/C              U117  -A52        A01X+088473Y+057437X0070Y0220R090 S1      
327N/C              U117  -A55        A01X+088473Y+056847X0070Y0220R090 S1      
327N/C              U117  -A56        A01X+088473Y+056650X0070Y0220R090 S1      
327N/C              U117  -A2         A01X+088916Y+056404X0070Y0220R180 S1      
327N/C              U117  -A3         A01X+089113Y+056404X0070Y0220R180 S1      
327N/C              U117  -A4         A01X+089310Y+056404X0070Y0220R180 S1      
327N/C              U117  -A5         A01X+089507Y+056404X0070Y0220R180 S1      
327N/C              U117  -A18        A01X+091524Y+057240X0070Y0220R090 S1      
327N/C              U117  -A19        A01X+091524Y+057437X0070Y0220R090 S1      
327N/C              U117  -A20        A01X+091524Y+057634X0070Y0220R090 S1      
327N/C              U117  -A21        A01X+091524Y+057831X0070Y0220R090 S1      
327N/C              U117  -A22        A01X+091524Y+058028X0070Y0220R090 S1      
327N/C              U117  -A23        A01X+091524Y+058225X0070Y0220R090 S1      
327N/C              U353  -26         A01X+039750Y+154195X0100Y0290R090 S1      
327N/C              U353  -16         A01X+041093Y+155341X0100Y0290R180 S1      
327N/C              U353  -13         A01X+041649Y+154785X0100Y0290R090 S1      
327N/C              U353  -15         A01X+041290Y+155341X0100Y0290R180 S1      
327N/C              U353  -12         A01X+041649Y+154588X0100Y0290R090 S1      
327N/C              Q113  -4          A01X+127488Y+090237X0240Y0240R270 S1      
327N/C              Q113  -5          A01X+127488Y+090532X0160Y0240R270 S1      
327N/C              Q113  -3          A01X+126779Y+090237X0240Y0240R270 S1      
327N/C              PU3   -7          A01X+091548Y+145751X0100Y0150R270 S1      
327N/C              PU2   -7          A01X+087348Y+145751X0100Y0150R270 S1      
327N/C              U379  -1          A01X+143831Y+101440X0160Y0360     S1      
327N/C              U415  -1          A01X+081380Y+139751X0220Y0530R180 S1      
317N/C              JPEX3_-1          A01X+188185Y+219660X0180Y    R180 S2      
017N/C              JPEX3_-1          A18X+188185Y+219660X0200Y    R180 S2      
017N/C                    -     D0080PA00X+188185Y+219660                       
317N/C              JPEX2_-1          A01X+189309Y+216801X0180Y    R180 S2      
017N/C              JPEX2_-1          A18X+189309Y+216801X0200Y    R180 S2      
017N/C                    -     D0080PA00X+189309Y+216801                       
317N/C              JPEX1_-1          A01X+192474Y+217813X0180Y    R180 S2      
017N/C              JPEX1_-1          A18X+192474Y+217813X0200Y    R180 S2      
017N/C                    -     D0080PA00X+192474Y+217813                       
317N/C              JPEX0_-1          A01X+188211Y+217907X0180Y    R180 S2      
017N/C              JPEX0_-1          A18X+188211Y+217907X0200Y    R180 S2      
017N/C                    -     D0080PA00X+188211Y+217907                       
317N/C              J45_OT-1          A01X+183586Y+212104X0180Y    R180 S2      
017N/C              J45_OT-1          A18X+183586Y+212104X0200Y    R180 S2      
017N/C                    -     D0080PA00X+183586Y+212104                       
317N/C              J44_OT-1          A01X+185176Y+212104X0180Y    R180 S2      
017N/C              J44_OT-1          A18X+185176Y+212104X0200Y    R180 S2      
017N/C                    -     D0080PA00X+185176Y+212104                       
317N/C              J43_OT-1          A01X+186707Y+217496X0180Y    R180 S2      
017N/C              J43_OT-1          A18X+186707Y+217496X0200Y    R180 S2      
017N/C                    -     D0080PA00X+186707Y+217496                       
317N/C              J42_OT-1          A01X+188297Y+217496X0180Y    R180 S2      
017N/C              J42_OT-1          A18X+188297Y+217496X0200Y    R180 S2      
017N/C                    -     D0080PA00X+188297Y+217496                       
317N/C              J41_OT-1          A01X+186023Y+215770X0180Y    R180 S2      
017N/C              J41_OT-1          A18X+186023Y+215770X0200Y    R180 S2      
017N/C                    -     D0080PA00X+186023Y+215770                       
317N/C              J40_OT-1          A01X+186034Y+207138X0180Y    R180 S2      
017N/C              J40_OT-1          A18X+186034Y+207138X0200Y    R180 S2      
017N/C                    -     D0080PA00X+186034Y+207138                       
317N/C              J39_OT-1          A01X+193520Y+215592X0180Y    R180 S2      
017N/C              J39_OT-1          A18X+193520Y+215592X0200Y    R180 S2      
017N/C                    -     D0080PA00X+193520Y+215592                       
317N/C              J38_OT-1          A01X+195110Y+215592X0180Y    R180 S2      
017N/C              J38_OT-1          A18X+195110Y+215592X0200Y    R180 S2      
017N/C                    -     D0080PA00X+195110Y+215592                       
317N/C              J37_OT-1          A01X+190130Y+207274X0180Y    R180 S2      
017N/C              J37_OT-1          A18X+190130Y+207274X0200Y    R180 S2      
017N/C                    -     D0080PA00X+190130Y+207274                       
317N/C              J36_OT-1          A01X+191720Y+207274X0180Y    R180 S2      
017N/C              J36_OT-1          A18X+191720Y+207274X0200Y    R180 S2      
017N/C                    -     D0080PA00X+191720Y+207274                       
317N/C              J35_OT-1          A01X+189004Y+206609X0180Y    R180 S2      
017N/C              J35_OT-1          A18X+189004Y+206609X0200Y    R180 S2      
017N/C                    -     D0080PA00X+189004Y+206609                       
317N/C              J34_OT-1          A01X+190594Y+206609X0180Y    R180 S2      
017N/C              J34_OT-1          A18X+190594Y+206609X0200Y    R180 S2      
017N/C                    -     D0080PA00X+190594Y+206609                       
317N/C              J33_OT-1          A01X+183087Y+208350X0180Y    R180 S2      
017N/C              J33_OT-1          A18X+183087Y+208350X0200Y    R180 S2      
017N/C                    -     D0080PA00X+183087Y+208350                       
317N/C              J32_OT-1          A01X+184088Y+208322X0180Y    R180 S2      
017N/C              J32_OT-1          A18X+184088Y+208322X0200Y    R180 S2      
017N/C                    -     D0080PA00X+184088Y+208322                       
317N/C              J31_OT-1          A01X+193621Y+217351X0180Y    R180 S2      
017N/C              J31_OT-1          A18X+193621Y+217351X0200Y    R180 S2      
017N/C                    -     D0080PA00X+193621Y+217351                       
317N/C              J30_OT-1          A01X+189312Y+205458X0180Y    R180 S2      
017N/C              J30_OT-1          A18X+189312Y+205458X0200Y    R180 S2      
017N/C                    -     D0080PA00X+189312Y+205458                       
327N/C              U419  -20         A01X+095212Y+094442X0160Y0540R180 S1      
327N/C              U419  -19         A01X+094956Y+094442X0160Y0540R180 S1      
327N/C              U419  -18         A01X+094700Y+094442X0160Y0540R180 S1      
327N/C              U419  -17         A01X+094444Y+094442X0160Y0540R180 S1      
327N/C              U419  -16         A01X+094188Y+094442X0160Y0540R180 S1      
327N/C              U419  -15         A01X+093932Y+094442X0160Y0540R180 S1      
327N/C              U419  -14         A01X+093676Y+094442X0160Y0540R180 S1      
327N/C              U419  -13         A01X+093381Y+094442X0240Y0540R180 S1      
327N/C              U419  -11         A01X+093676Y+096746X0160Y0540R180 S1      
327N/C              U419  -10         A01X+093932Y+096746X0160Y0540R180 S1      
327N/C              U419  -9          A01X+094188Y+096746X0160Y0540R180 S1      
327N/C              U419  -8          A01X+094444Y+096746X0160Y0540R180 S1      
327N/C              U419  -7          A01X+094700Y+096746X0160Y0540R180 S1      
327N/C              U419  -6          A01X+094956Y+096746X0160Y0540R180 S1      
327N/C              PEX3_H-1          A01X+192767Y+206725X0300Y    R180 S1      
327N/C              PEX2_H-1          A01X+190347Y+207935X0300Y    R180 S1      
327N/C              PEX1_H-1          A01X+191557Y+207935X0300Y    R180 S1      
327N/C              PEX0_H-1          A01X+192767Y+207935X0300Y    R180 S1      
317N/C              SCREW_-1          A01X+191371Y+215183X0180Y    R180 S2      
017N/C              SCREW_-1          A18X+191371Y+215183X0200Y    R180 S2      
017N/C                    -     D0080PA00X+191371Y+215183                       
317N/C              SCREW_-1          A01X+192201Y+215183X0180Y    R180 S2      
017N/C              SCREW_-1          A18X+192201Y+215183X0200Y    R180 S2      
017N/C                    -     D0080PA00X+192201Y+215183                       
317N/C              SCREW_-1          A01X+184650Y+217055X0180Y    R180 S2      
017N/C              SCREW_-1          A18X+184650Y+217055X0200Y    R180 S2      
017N/C                    -     D0080PA00X+184650Y+217055                       
317N/C              SCREW_-1          A01X+185480Y+217055X0180Y    R180 S2      
017N/C              SCREW_-1          A18X+185480Y+217055X0200Y    R180 S2      
017N/C                    -     D0080PA00X+185480Y+217055                       
317N/C              SCREW_-1          A01X+190594Y+205542X0180Y    R180 S2      
017N/C              SCREW_-1          A18X+190594Y+205542X0200Y    R180 S2      
017N/C                    -     D0080PA00X+190594Y+205542                       
317N/C              SCREW_-1          A01X+183365Y+205751X0180Y    R180 S2      
017N/C              SCREW_-1          A18X+183365Y+205751X0200Y    R180 S2      
017N/C                    -     D0080PA00X+183365Y+205751                       
317N/C              SCREW_-1          A01X+192344Y+218265X0180Y    R180 S2      
017N/C              SCREW_-1          A18X+192344Y+218265X0200Y    R180 S2      
017N/C                    -     D0080PA00X+192344Y+218265                       
317N/C              SCREW_-1          A01X+193174Y+218265X0180Y    R180 S2      
017N/C              SCREW_-1          A18X+193174Y+218265X0200Y    R180 S2      
017N/C                    -     D0080PA00X+193174Y+218265                       
317N/C              SCREW_-1          A01X+182935Y+207232X0180Y    R180 S2      
017N/C              SCREW_-1          A18X+182935Y+207232X0200Y    R180 S2      
017N/C                    -     D0080PA00X+182935Y+207232                       
317N/C              SCREW_-1          A01X+183765Y+207232X0180Y    R180 S2      
017N/C              SCREW_-1          A18X+183765Y+207232X0200Y    R180 S2      
017N/C                    -     D0080PA00X+183765Y+207232                       
317N/C              SCREW_-1          A01X+187050Y+206416X0180Y    R180 S2      
017N/C              SCREW_-1          A18X+187050Y+206416X0200Y    R180 S2      
017N/C                    -     D0080PA00X+187050Y+206416                       
317N/C              SCREW_-1          A01X+187880Y+206416X0180Y    R180 S2      
017N/C              SCREW_-1          A18X+187880Y+206416X0200Y    R180 S2      
017N/C                    -     D0080PA00X+187880Y+206416                       
317N/C              SCREW_-1          A01X+190925Y+215845X0180Y    R180 S2      
017N/C              SCREW_-1          A18X+190925Y+215845X0200Y    R180 S2      
017N/C                    -     D0080PA00X+190925Y+215845                       
317N/C              SCREW_-1          A01X+191755Y+215845X0180Y    R180 S2      
017N/C              SCREW_-1          A18X+191755Y+215845X0200Y    R180 S2      
017N/C                    -     D0080PA00X+191755Y+215845                       
317N/C              SCREW_-1          A01X+187450Y+207897X0180Y    R180 S2      
017N/C              SCREW_-1          A18X+187450Y+207897X0200Y    R180 S2      
017N/C                    -     D0080PA00X+187450Y+207897                       
317N/C              SCREW_-1          A01X+188280Y+207897X0180Y    R180 S2      
017N/C              SCREW_-1          A18X+188280Y+207897X0200Y    R180 S2      
017N/C                    -     D0080PA00X+188280Y+207897                       
317N/C              SCREW_-1          A01X+183300Y+206512X0180Y    R180 S2      
017N/C              SCREW_-1          A18X+183300Y+206512X0200Y    R180 S2      
017N/C                    -     D0080PA00X+183300Y+206512                       
317N/C              SCREW_-1          A01X+184130Y+206512X0180Y    R180 S2      
017N/C              SCREW_-1          A18X+184130Y+206512X0200Y    R180 S2      
017N/C                    -     D0080PA00X+184130Y+206512                       
317N/C              SCREW_-1          A01X+188454Y+215542X0180Y    R180 S2      
017N/C              SCREW_-1          A18X+188454Y+215542X0200Y    R180 S2      
017N/C                    -     D0080PA00X+188454Y+215542                       
317N/C              SCREW_-1          A01X+189284Y+215542X0180Y    R180 S2      
017N/C              SCREW_-1          A18X+189284Y+215542X0200Y    R180 S2      
017N/C                    -     D0080PA00X+189284Y+215542                       
317N/C              SCREW_-1          A01X+180671Y+218076X0180Y    R180 S2      
017N/C              SCREW_-1          A18X+180671Y+218076X0200Y    R180 S2      
017N/C                    -     D0080PA00X+180671Y+218076                       
317N/C              SCREW_-1          A01X+181501Y+218076X0180Y    R180 S2      
017N/C              SCREW_-1          A18X+181501Y+218076X0200Y    R180 S2      
017N/C                    -     D0080PA00X+181501Y+218076                       
317N/C              SCREW_-1          A01X+180908Y+216577X0180Y    R180 S2      
017N/C              SCREW_-1          A18X+180908Y+216577X0200Y    R180 S2      
017N/C                    -     D0080PA00X+180908Y+216577                       
317N/C              SCREW_-1          A01X+181738Y+216577X0180Y    R180 S2      
017N/C              SCREW_-1          A18X+181738Y+216577X0200Y    R180 S2      
017N/C                    -     D0080PA00X+181738Y+216577                       
317N/C              SCREW_-1          A01X+189457Y+217853X0180Y    R180 S2      
017N/C              SCREW_-1          A18X+189457Y+217853X0200Y    R180 S2      
017N/C                    -     D0080PA00X+189457Y+217853                       
317N/C              SCREW_-1          A01X+190287Y+217853X0180Y    R180 S2      
017N/C              SCREW_-1          A18X+190287Y+217853X0200Y    R180 S2      
017N/C                    -     D0080PA00X+190287Y+217853                       
317N/C              SCREW_-1          A01X+184768Y+218512X0180Y    R180 S2      
017N/C              SCREW_-1          A18X+184768Y+218512X0200Y    R180 S2      
017N/C                    -     D0080PA00X+184768Y+218512                       
317N/C              SCREW_-1          A01X+185598Y+218512X0180Y    R180 S2      
017N/C              SCREW_-1          A18X+185598Y+218512X0200Y    R180 S2      
017N/C                    -     D0080PA00X+185598Y+218512                       
317N/C              SCREW_-1          A01X+182543Y+210485X0180Y    R180 S2      
017N/C              SCREW_-1          A18X+182543Y+210485X0200Y    R180 S2      
017N/C                    -     D0080PA00X+182543Y+210485                       
317N/C              SCREW_-1          A01X+183373Y+210485X0180Y    R180 S2      
017N/C              SCREW_-1          A18X+183373Y+210485X0200Y    R180 S2      
017N/C                    -     D0080PA00X+183373Y+210485                       
317N/C              SCREW_-1          A01X+192186Y+217215X0180Y    R180 S2      
017N/C              SCREW_-1          A18X+192186Y+217215X0200Y    R180 S2      
017N/C                    -     D0080PA00X+192186Y+217215                       
317N/C              SCREW_-1          A01X+193016Y+217215X0180Y    R180 S2      
017N/C              SCREW_-1          A18X+193016Y+217215X0200Y    R180 S2      
017N/C                    -     D0080PA00X+193016Y+217215                       
317N/C              SCREW_-1          A01X+189834Y+206214X0180Y    R180 S2      
017N/C              SCREW_-1          A18X+189834Y+206214X0200Y    R180 S2      
017N/C                    -     D0080PA00X+189834Y+206214                       
317N/C              SCREW_-1          A01X+195943Y+215158X0180Y    R180 S2      
017N/C              SCREW_-1          A18X+195943Y+215158X0200Y    R180 S2      
017N/C                    -     D0080PA00X+195943Y+215158                       
317N/C              SCREW_-1          A01X+196913Y+215158X0180Y    R180 S2      
017N/C              SCREW_-1          A18X+196913Y+215158X0200Y    R180 S2      
017N/C                    -     D0080PA00X+196913Y+215158                       
317N/C              SCREW_-1          A01X+181237Y+205411X0180Y    R180 S2      
017N/C              SCREW_-1          A18X+181237Y+205411X0200Y    R180 S2      
017N/C                    -     D0080PA00X+181237Y+205411                       
317N/C              SCREW_-1          A01X+182207Y+205411X0180Y    R180 S2      
017N/C              SCREW_-1          A18X+182207Y+205411X0200Y    R180 S2      
017N/C                    -     D0080PA00X+182207Y+205411                       
317N/C              SCREW_-1          A01X+193638Y+216381X0180Y    R180 S2      
017N/C              SCREW_-1          A18X+193638Y+216381X0200Y    R180 S2      
017N/C                    -     D0080PA00X+193638Y+216381                       
317N/C              SCREW_-1          A01X+194608Y+216381X0180Y    R180 S2      
017N/C              SCREW_-1          A18X+194608Y+216381X0200Y    R180 S2      
017N/C                    -     D0080PA00X+194608Y+216381                       
317N/C              SCREW_-1          A01X+195943Y+216128X0180Y    R180 S2      
017N/C              SCREW_-1          A18X+195943Y+216128X0200Y    R180 S2      
017N/C                    -     D0080PA00X+195943Y+216128                       
317N/C              J64   -SCR_ D1250UA00X+058189Y+160614X2560Y2560R180 S3      
317N/C              J64   -H1   D1250UA00X+058189Y+162634X1250Y    R180 S3      
317N/C              J64   -H2   D1250UA00X+058189Y+158008X1250Y    R180 S3      
317N/C              J63   -SCR_ D1250UA00X+023543Y+160614X2560Y2560R180 S3      
317N/C              J63   -H1   D1250UA00X+023543Y+162634X1250Y    R180 S3      
317N/C              J63   -H2   D1250UA00X+023543Y+158008X1250Y    R180 S3      
317N/C              J62   -SCR_ D1250UA00X+160551Y+160614X2560Y2560R180 S3      
317N/C              J62   -H1   D1250UA00X+160551Y+162634X1250Y    R180 S3      
317N/C              J62   -H2   D1250UA00X+160551Y+158008X1250Y    R180 S3      
317N/C              J61   -SCR_ D1250UA00X+125906Y+160614X2560Y2560R180 S3      
317N/C              J61   -H1   D1250UA00X+125906Y+162634X1250Y    R180 S3      
317N/C              J61   -H2   D1250UA00X+125906Y+158008X1250Y    R180 S3      
317N/C              HANDLE-1          A01X+196913Y+216128X0180Y    R180 S2      
017N/C              HANDLE-1          A18X+196913Y+216128X0200Y    R180 S2      
017N/C                    -     D0080PA00X+196913Y+216128                       
317N/C              HANDLE-1          A01X+181237Y+206381X0180Y    R180 S2      
017N/C              HANDLE-1          A18X+181237Y+206381X0200Y    R180 S2      
017N/C                    -     D0080PA00X+181237Y+206381                       
317N/C              H81   -1    D1340UA00X+102087Y+038858X1340Y         S3      
317N/C              H142  -1    D1250UA00X+018485Y+033449X1250Y         S3      
327N/C              U423  -19         A18X+081128Y+098004X0120Y0630R180 S2      
327N/C              U423  -17         A18X+081640Y+098004X0120Y0630R180 S2      
327N/C              U423  -15         A18X+082152Y+098004X0120Y0630R180 S2      
327N/C              U423  -13         A18X+082663Y+098004X0120Y0630R180 S2      
327N/C              U423  -20         A18X+080872Y+098004X0120Y0630R180 S2      
327N/C              U423  -18         A18X+081384Y+098004X0120Y0630R180 S2      
327N/C              U423  -16         A18X+081896Y+098004X0120Y0630R180 S2      
327N/C              U423  -14         A18X+082408Y+098004X0120Y0630R180 S2      
327N/C              U424  -30         A18X+041758Y+138194X0100Y0220R090 S2      
327N/C              U424  -17         A18X+040134Y+139425X0100Y0220R180 S2      
327N/C              U424  -11         A18X+039888Y+138194X0100Y0220R270 S2      
327N/C              U424  -10         A18X+039888Y+137998X0100Y0220R270 S2      
327N/C              U424  -8          A18X+040134Y+137555X0100Y0220     S2      
327N/C              U424  -9          A18X+039888Y+137801X0100Y0220R270 S2      
317N/C              J2    -H1   D0520UA00X+090936Y+023091X0520Y    R090 S3      
317N/C              J2    -H2   D0520UA00X+090936Y+027461X0520Y    R090 S3      
327N/C              VR_HS1-1          A01X+193960Y+205739X0300Y    R090 S1      
327N/C              VR_HS0-1          A01X+194982Y+205610X0300Y    R090 S1      
317N/C              HS_BP3-1          A01X+189640Y+218502X0180Y    R090 S2      
017N/C              HS_BP3-1          A18X+189640Y+218502X0200Y    R090 S2      
017N/C                    -     D0080PA00X+189640Y+218502                       
317N/C              HS_BP2-1          A01X+187493Y+218058X0180Y    R090 S2      
017N/C              HS_BP2-1          A18X+187493Y+218058X0200Y    R090 S2      
017N/C                    -     D0080PA00X+187493Y+218058                       
317N/C              HS_BP1-1          A01X+186455Y+218502X0180Y    R090 S2      
017N/C              HS_BP1-1          A18X+186455Y+218502X0200Y    R090 S2      
017N/C                    -     D0080PA00X+186455Y+218502                       
317N/C              HS_BP0-1          A01X+183351Y+218525X0180Y    R090 S2      
017N/C              HS_BP0-1          A18X+183351Y+218525X0200Y    R090 S2      
017N/C                    -     D0080PA00X+183351Y+218525                       
327N/C              U435  -19         A01X+039747Y+074528X0110Y0340     S1      
327N/C              U435  -20         A01X+039944Y+074528X0110Y0340     S1      
327N/C              U435  -6          A01X+039078Y+076772X0110Y0340R270 S1      
327N/C              U435  -14         A01X+039078Y+075197X0110Y0340R270 S1      
327N/C              U435  -47         A01X+042582Y+077560X0110Y0340R090 S1      
327N/C              U435  -55         A01X+041125Y+078032X0110Y0340R180 S1      
327N/C              U435  -7          A01X+039078Y+076575X0110Y0340R270 S1      
327N/C              U435  -11         A01X+039078Y+075788X0110Y0340R270 S1      
327N/C              U435  -42         A01X+042582Y+076575X0110Y0340R090 S1      
327N/C              U435  -50         A01X+042110Y+078032X0110Y0340R180 S1      
327N/C              U435  -36         A01X+042582Y+075394X0110Y0340R090 S1      
327N/C              U435  -35         A01X+042582Y+075197X0110Y0340R090 S1      
327N/C              U435  -29         A01X+041716Y+074528X0110Y0340     S1      
327N/C              U435  -30         A01X+041913Y+074528X0110Y0340     S1      
327N/C              U435  -31         A01X+042110Y+074528X0110Y0340     S1      
327N/C              U435  -32         A01X+042306Y+074528X0110Y0340     S1      
327N/C              U435  -33         A01X+042582Y+074804X0110Y0340R090 S1      
327N/C              U435  -34         A01X+042582Y+075000X0110Y0340R090 S1      
327N/C              U435  -37         A01X+042582Y+075591X0110Y0340R090 S1      
327N/C              U435  -38         A01X+042582Y+075788X0110Y0340R090 S1      
327N/C              U435  -21         A01X+040141Y+074528X0110Y0340     S1      
327N/C              U435  -22         A01X+040338Y+074528X0110Y0340     S1      
327N/C              U435  -23         A01X+040535Y+074528X0110Y0340     S1      
327N/C              U435  -26         A01X+041125Y+074528X0110Y0340     S1      
327N/C              U435  -27         A01X+041322Y+074528X0110Y0340     S1      
327N/C              U435  -28         A01X+041519Y+074528X0110Y0340     S1      
327N/C              U435  -40         A01X+042582Y+076182X0110Y0340R090 S1      
327N/C              U435  -41         A01X+042582Y+076378X0110Y0340R090 S1      
327N/C              U435  -10         A01X+039078Y+075985X0110Y0340R270 S1      
327N/C              U435  -18         A01X+039550Y+074528X0110Y0340     S1      
327N/C              U435  -45         A01X+042582Y+077166X0110Y0340R090 S1      
327N/C              U435  -53         A01X+041519Y+078032X0110Y0340R180 S1      
327N/C              U435  -9          A01X+039078Y+076182X0110Y0340R270 S1      
327N/C              U435  -17         A01X+039354Y+074528X0110Y0340     S1      
327N/C              U435  -44         A01X+042582Y+076969X0110Y0340R090 S1      
327N/C              U435  -52         A01X+041716Y+078032X0110Y0340R180 S1      
327N/C              U435  -8          A01X+039078Y+076378X0110Y0340R270 S1      
327N/C              U435  -12         A01X+039078Y+075591X0110Y0340R270 S1      
327N/C              U435  -43         A01X+042582Y+076772X0110Y0340R090 S1      
327N/C              U435  -51         A01X+041913Y+078032X0110Y0340R180 S1      
327N/C              U435  -5          A01X+039078Y+076969X0110Y0340R270 S1      
327N/C              U435  -13         A01X+039078Y+075394X0110Y0340R270 S1      
327N/C              U435  -46         A01X+042582Y+077363X0110Y0340R090 S1      
327N/C              U435  -54         A01X+041322Y+078032X0110Y0340R180 S1      
327N/C              U434  -19         A01X+177017Y+087788X0110Y0340     S1      
327N/C              U434  -20         A01X+177214Y+087788X0110Y0340     S1      
327N/C              U434  -6          A01X+176348Y+090032X0110Y0340R270 S1      
327N/C              U434  -14         A01X+176348Y+088457X0110Y0340R270 S1      
327N/C              U434  -47         A01X+179852Y+090820X0110Y0340R090 S1      
327N/C              U434  -55         A01X+178395Y+091292X0110Y0340R180 S1      
327N/C              U434  -7          A01X+176348Y+089835X0110Y0340R270 S1      
327N/C              U434  -11         A01X+176348Y+089048X0110Y0340R270 S1      
327N/C              U434  -42         A01X+179852Y+089835X0110Y0340R090 S1      
327N/C              U434  -50         A01X+179380Y+091292X0110Y0340R180 S1      
327N/C              U434  -36         A01X+179852Y+088654X0110Y0340R090 S1      
327N/C              U434  -35         A01X+179852Y+088457X0110Y0340R090 S1      
327N/C              U434  -29         A01X+178986Y+087788X0110Y0340     S1      
327N/C              U434  -30         A01X+179183Y+087788X0110Y0340     S1      
327N/C              U434  -31         A01X+179380Y+087788X0110Y0340     S1      
327N/C              U434  -32         A01X+179576Y+087788X0110Y0340     S1      
327N/C              U434  -33         A01X+179852Y+088064X0110Y0340R090 S1      
327N/C              U434  -34         A01X+179852Y+088260X0110Y0340R090 S1      
327N/C              U434  -37         A01X+179852Y+088851X0110Y0340R090 S1      
327N/C              U434  -38         A01X+179852Y+089048X0110Y0340R090 S1      
327N/C              U434  -21         A01X+177411Y+087788X0110Y0340     S1      
327N/C              U434  -22         A01X+177608Y+087788X0110Y0340     S1      
327N/C              U434  -23         A01X+177805Y+087788X0110Y0340     S1      
327N/C              U434  -26         A01X+178395Y+087788X0110Y0340     S1      
327N/C              U434  -27         A01X+178592Y+087788X0110Y0340     S1      
327N/C              U434  -28         A01X+178789Y+087788X0110Y0340     S1      
327N/C              U434  -40         A01X+179852Y+089442X0110Y0340R090 S1      
327N/C              U434  -41         A01X+179852Y+089638X0110Y0340R090 S1      
327N/C              U434  -10         A01X+176348Y+089245X0110Y0340R270 S1      
327N/C              U434  -18         A01X+176820Y+087788X0110Y0340     S1      
327N/C              U434  -45         A01X+179852Y+090426X0110Y0340R090 S1      
327N/C              U434  -53         A01X+178789Y+091292X0110Y0340R180 S1      
327N/C              U434  -9          A01X+176348Y+089442X0110Y0340R270 S1      
327N/C              U434  -17         A01X+176624Y+087788X0110Y0340     S1      
327N/C              U434  -44         A01X+179852Y+090229X0110Y0340R090 S1      
327N/C              U434  -52         A01X+178986Y+091292X0110Y0340R180 S1      
327N/C              U434  -8          A01X+176348Y+089638X0110Y0340R270 S1      
327N/C              U434  -12         A01X+176348Y+088851X0110Y0340R270 S1      
327N/C              U434  -43         A01X+179852Y+090032X0110Y0340R090 S1      
327N/C              U434  -51         A01X+179183Y+091292X0110Y0340R180 S1      
327N/C              U434  -5          A01X+176348Y+090229X0110Y0340R270 S1      
327N/C              U434  -13         A01X+176348Y+088654X0110Y0340R270 S1      
327N/C              U434  -46         A01X+179852Y+090623X0110Y0340R090 S1      
327N/C              U434  -54         A01X+178592Y+091292X0110Y0340R180 S1      
317N/C              J69   -H1   D0300UA00X+097007Y+136565X0300Y    R090 S3      
317N/C              J69   -H2   D0300UA00X+097007Y+140915X0300Y    R090 S3      
317N/C              SCREW_-1          A01X+181309Y+208751X0180Y         S2      
017N/C              SCREW_-1          A18X+181309Y+208751X0200Y         S2      
017N/C                    -     D0080PA00X+181309Y+208751                       
327N/C              U442  -39         A01X+004303Y+153896X0094Y0236     S1      
327N/C              U442  -37         A01X+004697Y+153896X0094Y0236     S1      
327N/C              U442  -38         A01X+004500Y+153896X0094Y0236     S1      
327N/C              U442  -55         A01X+002276Y+152459X0094Y0236R090 S1      
327N/C              U442  -26         A01X+005740Y+152459X0094Y0236R090 S1      
327N/C              U442  -19         A01X+005740Y+151081X0094Y0236R090 S1      
327N/C              U442  -11         A01X+004500Y+150432X0094Y0236     S1      
327N/C              U442  -3          A01X+002925Y+150432X0094Y0236     S1      
327N/C              U442  -56         A01X+002276Y+152262X0094Y0236R090 S1      
327N/C              U442  -27         A01X+005740Y+152656X0094Y0236R090 S1      
327N/C              U442  -20         A01X+005740Y+151278X0094Y0236R090 S1      
327N/C              U442  -12         A01X+004697Y+150432X0094Y0236     S1      
327N/C              U442  -4          A01X+003122Y+150432X0094Y0236     S1      
327N/C              U442  -58         A01X+002276Y+151869X0094Y0236R090 S1      
327N/C              U442  -29         A01X+005740Y+153050X0094Y0236R090 S1      
327N/C              U442  -22         A01X+005740Y+151672X0094Y0236R090 S1      
327N/C              U442  -14         A01X+005091Y+150432X0094Y0236     S1      
327N/C              U442  -6          A01X+003516Y+150432X0094Y0236     S1      
327N/C              U442  -59         A01X+002276Y+151672X0094Y0236R090 S1      
327N/C              U442  -30         A01X+005740Y+153247X0094Y0236R090 S1      
327N/C              U442  -23         A01X+005740Y+151869X0094Y0236R090 S1      
327N/C              U442  -15         A01X+005287Y+150432X0094Y0236     S1      
327N/C              U442  -7          A01X+003713Y+150432X0094Y0236     S1      
327N/C              U442  -24         A01X+005740Y+152066X0094Y0236R090 S1      
327N/C              U442  -1          A01X+002532Y+150432X0094Y0236     S1      
327N/C              U442  -25         A01X+005740Y+152262X0094Y0236R090 S1      
327N/C              U442  -2          A01X+002728Y+150432X0094Y0236     S1      
327N/C              U442  -41         A01X+003910Y+153896X0094Y0236     S1      
327N/C              U442  -32         A01X+005740Y+153640X0094Y0236R090 S1      
327N/C              U442  -36         A01X+004894Y+153896X0094Y0236     S1      
327N/C              U442  -60         A01X+002276Y+151475X0094Y0236R090 S1      
327N/C              U449  -3          A01X+104160Y+133406X0240Y0420R270 S1      
327N/C              U444  -3          A01X+078603Y+161455X0240Y0420R180 S1      
317N/C              H75   -1    D1220UA00X+181732Y+156732X1220Y         S3      
317N/C              SCREW_-1          A01X+194104Y+207012X0180Y         S2      
017N/C              SCREW_-1          A18X+194104Y+207012X0200Y         S2      
017N/C                    -     D0080PA00X+194104Y+207012                       
317N/C              J4_23 -1          A01X+193630Y+207434X0180Y         S2      
017N/C              J4_23 -1          A18X+193630Y+207434X0200Y         S2      
017N/C                    -     D0080PA00X+193630Y+207434                       
C                                                                               
C  ****************************************                                     
C      TOOLING HOLE PINS ON THE BOARD                                           
C  ****************************************                                     
C                                                                               
367                       -     D0410UA00X+096439Y-007598X0410Y    R090 S3      
367                       -     D0410UA00X+096439Y-006598X0410Y    R090 S3      
367                       -     D0410UA00X+098939Y-007598X0410Y    R090 S3      
367                       -     D0410UA00X+098939Y-006598X0410Y    R090 S3      
367                       -     D0410UA00X+085541Y-006601X0410Y    R270 S3      
367                       -     D0410UA00X+085541Y-007601X0410Y    R270 S3      
367                       -     D0410UA00X+083041Y-006601X0410Y    R270 S3      
367                       -     D0410UA00X+083041Y-007601X0410Y    R270 S3      
367                       -     D0410UA00X+085541Y-007601X0410Y    R270 S3      
367                       -     D0410UA00X+085541Y-006601X0410Y    R270 S3      
367                       -     D0410UA00X+083041Y-007601X0410Y    R270 S3      
367                       -     D0410UA00X+083041Y-006601X0410Y    R270 S3      
367                       -     D0410UA00X+096439Y-006598X0410Y    R090 S3      
367                       -     D0410UA00X+096439Y-007598X0410Y    R090 S3      
367                       -     D0410UA00X+098939Y-006598X0410Y    R090 S3      
367                       -     D0410UA00X+098939Y-007598X0410Y    R090 S3      
367                       -     D0410UA00X+121769Y-007598X0410Y    R090 S3      
367                       -     D0410UA00X+121769Y-006598X0410Y    R090 S3      
367                       -     D0410UA00X+124269Y-007598X0410Y    R090 S3      
367                       -     D0410UA00X+124269Y-006598X0410Y    R090 S3      
367                       -     D0410UA00X+108891Y-006601X0410Y    R270 S3      
367                       -     D0410UA00X+108891Y-007601X0410Y    R270 S3      
367                       -     D0410UA00X+106391Y-006601X0410Y    R270 S3      
367                       -     D0410UA00X+106391Y-007601X0410Y    R270 S3      
367                       -     D0410UA00X+147419Y-007598X0410Y    R090 S3      
367                       -     D0410UA00X+147419Y-006598X0410Y    R090 S3      
367                       -     D0410UA00X+149919Y-007598X0410Y    R090 S3      
367                       -     D0410UA00X+149919Y-006598X0410Y    R090 S3      
367                       -     D0410UA00X+134541Y-006601X0410Y    R270 S3      
367                       -     D0410UA00X+134541Y-007601X0410Y    R270 S3      
367                       -     D0410UA00X+132041Y-006601X0410Y    R270 S3      
367                       -     D0410UA00X+132041Y-007601X0410Y    R270 S3      
367                       -     D0410UA00X+172869Y-007598X0410Y    R090 S3      
367                       -     D0410UA00X+172869Y-006598X0410Y    R090 S3      
367                       -     D0410UA00X+175369Y-007598X0410Y    R090 S3      
367                       -     D0410UA00X+175369Y-006598X0410Y    R090 S3      
367                       -     D0410UA00X+159991Y-006601X0410Y    R270 S3      
367                       -     D0410UA00X+159991Y-007601X0410Y    R270 S3      
367                       -     D0410UA00X+157491Y-006601X0410Y    R270 S3      
367                       -     D0410UA00X+157491Y-007601X0410Y    R270 S3      
367                       -     D0410UA00X+172869Y-007598X0410Y    R090 S3      
367                       -     D0410UA00X+172869Y-008598X0410Y    R090 S3      
367                       -     D0410UA00X+175369Y-007598X0410Y    R090 S3      
367                       -     D0410UA00X+175369Y-008598X0410Y    R090 S3      
367                       -     D0410UA00X+159991Y-008601X0410Y    R270 S3      
367                       -     D0410UA00X+159991Y-007601X0410Y    R270 S3      
367                       -     D0410UA00X+157491Y-008601X0410Y    R270 S3      
367                       -     D0410UA00X+157491Y-007601X0410Y    R270 S3      
367                       -     D0410UA00X+134541Y-008601X0410Y    R270 S3      
367                       -     D0410UA00X+134541Y-007601X0410Y    R270 S3      
367                       -     D0410UA00X+132041Y-008601X0410Y    R270 S3      
367                       -     D0410UA00X+132041Y-007601X0410Y    R270 S3      
367                       -     D0410UA00X+147419Y-007598X0410Y    R090 S3      
367                       -     D0410UA00X+147419Y-008598X0410Y    R090 S3      
367                       -     D0410UA00X+149919Y-007598X0410Y    R090 S3      
367                       -     D0410UA00X+149919Y-008598X0410Y    R090 S3      
367                       -     D0410UA00X+121769Y-007598X0410Y    R090 S3      
367                       -     D0410UA00X+121769Y-008598X0410Y    R090 S3      
367                       -     D0410UA00X+124269Y-007598X0410Y    R090 S3      
367                       -     D0410UA00X+124269Y-008598X0410Y    R090 S3      
367                       -     D0410UA00X+108891Y-008601X0410Y    R270 S3      
367                       -     D0410UA00X+108891Y-007601X0410Y    R270 S3      
367                       -     D0410UA00X+106391Y-008601X0410Y    R270 S3      
367                       -     D0410UA00X+106391Y-007601X0410Y    R270 S3      
367                       -     D0410UA00X+093954Y-003680X0410Y    R090 S3      
367                       -     D0410UA00X+093954Y-002680X0410Y    R090 S3      
367                       -     D0410UA00X+096454Y-003680X0410Y    R090 S3      
367                       -     D0410UA00X+096454Y-002680X0410Y    R090 S3      
367                       -     D0410UA00X+073541Y-002683X0410Y    R270 S3      
367                       -     D0410UA00X+073541Y-003683X0410Y    R270 S3      
367                       -     D0410UA00X+071041Y-002683X0410Y    R270 S3      
367                       -     D0410UA00X+071041Y-003683X0410Y    R270 S3      
367                       -     D0410UA00X+073541Y-003683X0410Y    R270 S3      
367                       -     D0410UA00X+073541Y-002683X0410Y    R270 S3      
367                       -     D0410UA00X+071041Y-003683X0410Y    R270 S3      
367                       -     D0410UA00X+071041Y-002683X0410Y    R270 S3      
367                       -     D0410UA00X+093954Y-002680X0410Y    R090 S3      
367                       -     D0410UA00X+093954Y-003680X0410Y    R090 S3      
367                       -     D0410UA00X+096454Y-002680X0410Y    R090 S3      
367                       -     D0410UA00X+096454Y-003680X0410Y    R090 S3      
367                       -     D0410UA00X+122304Y-003693X0410Y    R090 S3      
367                       -     D0410UA00X+122304Y-002693X0410Y    R090 S3      
367                       -     D0410UA00X+124804Y-003693X0410Y    R090 S3      
367                       -     D0410UA00X+124804Y-002693X0410Y    R090 S3      
367                       -     D0410UA00X+101891Y-002683X0410Y    R270 S3      
367                       -     D0410UA00X+101891Y-003683X0410Y    R270 S3      
367                       -     D0410UA00X+099391Y-002683X0410Y    R270 S3      
367                       -     D0410UA00X+099391Y-003683X0410Y    R270 S3      
367                       -     D0410UA00X+150954Y-003706X0410Y    R090 S3      
367                       -     D0410UA00X+150954Y-002706X0410Y    R090 S3      
367                       -     D0410UA00X+153454Y-003706X0410Y    R090 S3      
367                       -     D0410UA00X+153454Y-002706X0410Y    R090 S3      
367                       -     D0410UA00X+130541Y-002696X0410Y    R270 S3      
367                       -     D0410UA00X+130541Y-003696X0410Y    R270 S3      
367                       -     D0410UA00X+128041Y-002696X0410Y    R270 S3      
367                       -     D0410UA00X+128041Y-003696X0410Y    R270 S3      
367                       -     D0410UA00X+179404Y-003719X0410Y    R090 S3      
367                       -     D0410UA00X+179404Y-002719X0410Y    R090 S3      
367                       -     D0410UA00X+181904Y-003719X0410Y    R090 S3      
367                       -     D0410UA00X+181904Y-002719X0410Y    R090 S3      
367                       -     D0410UA00X+158991Y-002709X0410Y    R270 S3      
367                       -     D0410UA00X+158991Y-003709X0410Y    R270 S3      
367                       -     D0410UA00X+156491Y-002709X0410Y    R270 S3      
367                       -     D0410UA00X+156491Y-003709X0410Y    R270 S3      
367                       -     D0410UA00X+158991Y-004709X0410Y    R270 S3      
367                       -     D0410UA00X+158991Y-003709X0410Y    R270 S3      
367                       -     D0410UA00X+156491Y-004709X0410Y    R270 S3      
367                       -     D0410UA00X+156491Y-003709X0410Y    R270 S3      
367                       -     D0410UA00X+179404Y-003719X0410Y    R090 S3      
367                       -     D0410UA00X+179404Y-004719X0410Y    R090 S3      
367                       -     D0410UA00X+181904Y-003719X0410Y    R090 S3      
367                       -     D0410UA00X+181904Y-004719X0410Y    R090 S3      
367                       -     D0410UA00X+130541Y-004696X0410Y    R270 S3      
367                       -     D0410UA00X+130541Y-003696X0410Y    R270 S3      
367                       -     D0410UA00X+128041Y-004696X0410Y    R270 S3      
367                       -     D0410UA00X+128041Y-003696X0410Y    R270 S3      
367                       -     D0410UA00X+150954Y-003706X0410Y    R090 S3      
367                       -     D0410UA00X+150954Y-004706X0410Y    R090 S3      
367                       -     D0410UA00X+153454Y-003706X0410Y    R090 S3      
367                       -     D0410UA00X+153454Y-004706X0410Y    R090 S3      
367                       -     D0410UA00X+101891Y-004683X0410Y    R270 S3      
367                       -     D0410UA00X+101891Y-003683X0410Y    R270 S3      
367                       -     D0410UA00X+099391Y-004683X0410Y    R270 S3      
367                       -     D0410UA00X+099391Y-003683X0410Y    R270 S3      
367                       -     D0410UA00X+122304Y-003693X0410Y    R090 S3      
367                       -     D0410UA00X+122304Y-004693X0410Y    R090 S3      
367                       -     D0410UA00X+124804Y-003693X0410Y    R090 S3      
367                       -     D0410UA00X+124804Y-004693X0410Y    R090 S3      
C                                                                               
C  End-of-Job                                                                   
C                                                                               
999                                                                             
